(kicad_pcb
	(version 20260206)
	(generator "pcbnew")
	(generator_version "10.0")
	(general
		(thickness 1.21888)
		(legacy_teardrops no)
	)
	(paper "A4")
	(layers
		(0 "F.Cu" signal "TOP")
		(4 "In1.Cu" signal "SGND")
		(6 "In2.Cu" signal "IN1")
		(8 "In3.Cu" signal "IN2")
		(10 "In4.Cu" signal "SGND1")
		(2 "B.Cu" signal "BOTTOM")
		(9 "F.Adhes" user "F.Adhesive")
		(11 "B.Adhes" user "B.Adhesive")
		(13 "F.Paste" user "Top Paste")
		(15 "B.Paste" user "Bottom Paste")
		(5 "F.SilkS" user "Top Overlay")
		(7 "B.SilkS" user "Bottom Overlay")
		(1 "F.Mask" user "Top Solder")
		(3 "B.Mask" user "Bottom Solder")
		(17 "Dwgs.User" user "User.Drawings")
		(19 "Cmts.User" user "User.Comments")
		(21 "Eco1.User" user "User.Eco1")
		(23 "Eco2.User" user "User.Eco2")
		(25 "Edge.Cuts" user)
		(27 "Margin" user)
		(31 "F.CrtYd" user "Top Courtyard")
		(29 "B.CrtYd" user "Bottom Courtyard")
		(35 "F.Fab" user "Top Component Center")
		(33 "B.Fab" user "Bottom Component Center")
	)
	(setup
		(pad_to_mask_clearance 0.1016)
		(allow_soldermask_bridges_in_footprints no)
		(tenting
			(front yes)
			(back yes)
		)
		(covering
			(front no)
			(back no)
		)
		(plugging
			(front no)
			(back no)
		)
		(capping no)
		(filling no)
		(aux_axis_origin -68.261405 262.2786)
		(grid_origin -68.261405 262.2786)
		(pcbplotparams
			(layerselection 0x00000000_00000000_55555555_5755f5ff)
			(plot_on_all_layers_selection 0x00000000_00000000_00000000_00000000)
			(disableapertmacros no)
			(usegerberextensions no)
			(usegerberattributes yes)
			(usegerberadvancedattributes yes)
			(creategerberjobfile yes)
			(dashed_line_dash_ratio 12)
			(dashed_line_gap_ratio 3)
			(svgprecision 4)
			(plotframeref no)
			(mode 1)
			(useauxorigin no)
			(pdf_front_fp_property_popups yes)
			(pdf_back_fp_property_popups yes)
			(pdf_metadata yes)
			(pdf_single_document no)
			(dxfpolygonmode yes)
			(dxfimperialunits yes)
			(dxfusepcbnewfont yes)
			(psnegative no)
			(psa4output no)
			(plot_black_and_white yes)
			(sketchpadsonfab no)
			(plotpadnumbers no)
			(hidednponfab no)
			(sketchdnponfab yes)
			(crossoutdnponfab yes)
			(subtractmaskfromsilk no)
			(outputformat 1)
			(mirror no)
			(drillshape 1)
			(scaleselection 1)
			(outputdirectory "")
		)
	)
	(footprint "Capacitors:CAPC2012X14N"
		(layer "F.Cu")
		(at 149.662595 142.1366 180)
		(property "Reference" "C62"
			(at 4.849 -0.335345 0)
			(unlocked yes)
			(layer "F.SilkS")
			(effects
				(font
					(size 0.762 0.762)
					(thickness 0.2286)
				)
				(justify left bottom)
			)
		)
		(property "Value" "CAP_0805_10UF_25V"
			(at 1.5875 -3.52679 0)
			(unlocked yes)
			(layer "F.SilkS")
			(hide yes)
			(effects
				(font
					(size 1.524 1.524)
					(thickness 0.254)
				)
				(justify left bottom)
			)
		)
		(sheetname "MAC")
		(sheetfile "MAC.kicad_sch")
		(duplicate_pad_numbers_are_jumpers no)
		(fp_line
			(start 0.762 0.9652)
			(end -0.762 0.9652)
			(stroke
				(width 0.1524)
				(type solid)
			)
			(layer "F.SilkS")
		)
		(fp_line
			(start 0.762 -0.9652)
			(end -0.762 -0.9652)
			(stroke
				(width 0.1524)
				(type solid)
			)
			(layer "F.SilkS")
		)
		(pad "1" smd rect
			(at -0.9 0 270)
			(size 1.45 1.15)
			(layers "F.Cu" "F.Mask" "F.Paste")
			(net "+5.0V")
		)
		(pad "2" smd rect
			(at 0.9 0 270)
			(size 1.45 1.15)
			(layers "F.Cu" "F.Mask" "F.Paste")
			(net "GND")
		)
	)
	(footprint "Resistors:RESC1608X50N"
		(layer "F.Cu")
		(at 94.548595 122.0786 180)
		(property "Reference" "R22"
			(at 1.06 0.906655 0)
			(unlocked yes)
			(layer "F.SilkS")
			(effects
				(font
					(size 0.762 0.762)
					(thickness 0.2286)
				)
				(justify left bottom)
			)
		)
		(property "Value" "ERJ-3EKF4701V"
			(at 0.4445 -3.72999 0)
			(unlocked yes)
			(layer "F.SilkS")
			(hide yes)
			(effects
				(font
					(size 1.524 1.524)
					(thickness 0.254)
				)
				(justify left bottom)
			)
		)
		(sheetname "PCIe_JTAG")
		(sheetfile "PCIe_JTAG.kicad_sch")
		(duplicate_pad_numbers_are_jumpers no)
		(fp_line
			(start 0 -0.5)
			(end 0 0.5)
			(stroke
				(width 0.1524)
				(type solid)
			)
			(layer "F.SilkS")
		)
		(pad "1" smd rect
			(at -0.69 0 270)
			(size 1 0.72)
			(layers "F.Cu" "F.Mask" "F.Paste")
			(net "PCIE_PERST")
		)
		(pad "2" smd rect
			(at 0.69 0 270)
			(size 1 0.72)
			(layers "F.Cu" "F.Mask" "F.Paste")
			(net "+3.3V")
		)
	)
	(footprint "Resistors:RESC1608X50N"
		(layer "F.Cu")
		(at 230.288595 114.3786)
		(property "Reference" "R6"
			(at -3.398 0.321345 0)
			(unlocked yes)
			(layer "F.SilkS")
			(effects
				(font
					(size 0.762 0.762)
					(thickness 0.2286)
				)
				(justify left bottom)
			)
		)
		(property "Value" "ERJ-3EKF1002V"
			(at -4.4323 3.04419 0)
			(unlocked yes)
			(layer "F.SilkS")
			(hide yes)
			(effects
				(font
					(size 1.524 1.524)
					(thickness 0.254)
				)
				(justify left bottom)
			)
		)
		(sheetname "POWER")
		(sheetfile "POWER.kicad_sch")
		(duplicate_pad_numbers_are_jumpers no)
		(fp_line
			(start 0 0.5)
			(end 0 -0.5)
			(stroke
				(width 0.1524)
				(type solid)
			)
			(layer "F.SilkS")
		)
		(pad "1" smd rect
			(at -0.69 0 90)
			(size 1 0.72)
			(layers "F.Cu" "F.Mask" "F.Paste")
			(net "GND")
		)
		(pad "2" smd rect
			(at 0.69 0 90)
			(size 1 0.72)
			(layers "F.Cu" "F.Mask" "F.Paste")
			(net "NetR4_2")
		)
	)
	(footprint "Vault:CAPC1608X87X45ML20T05"
		(layer "F.Cu")
		(at 131.238595 75.3286 90)
		(property "Reference" "C59"
			(at -4.25 1.343345 90)
			(unlocked yes)
			(layer "F.SilkS")
			(effects
				(font
					(size 0.762 0.762)
					(thickness 0.2286)
				)
				(justify left bottom)
			)
		)
		(property "Value" "0.1uF"
			(at -3.47599 -0.2921 0)
			(unlocked yes)
			(layer "F.SilkS")
			(hide yes)
			(effects
				(font
					(size 1.524 1.524)
					(thickness 0.254)
				)
				(justify left bottom)
			)
		)
		(sheetname "GPS_IMU_SENSORS")
		(sheetfile "GPS_IMU_SENSORS.kicad_sch")
		(duplicate_pad_numbers_are_jumpers no)
		(pad "1" smd rect
			(at -0.7 0 180)
			(size 1.1 1.05)
			(layers "F.Cu" "F.Mask" "F.Paste")
			(net "GND")
		)
		(pad "2" smd rect
			(at 0.7 0 180)
			(size 1.1 1.05)
			(layers "F.Cu" "F.Mask" "F.Paste")
			(net "+3.3V")
		)
	)
	(footprint "Vault:RESC1608X55X30LL15T20"
		(layer "F.Cu")
		(at 133.738595 92.0786 180)
		(property "Reference" "R37"
			(at 2.2714 -0.026931 0)
			(unlocked yes)
			(layer "F.SilkS")
			(effects
				(font
					(size 0.762 0.762)
					(thickness 0.2286)
				)
			)
		)
		(property "Value" "10K"
			(at -2.657602 1.790085 90)
			(unlocked yes)
			(layer "F.SilkS")
			(hide yes)
			(effects
				(font
					(size 1.524 1.524)
					(thickness 0.254)
				)
			)
		)
		(sheetname "GPS_IMU_SENSORS")
		(sheetfile "GPS_IMU_SENSORS.kicad_sch")
		(duplicate_pad_numbers_are_jumpers no)
		(pad "1" smd rect
			(at -0.575 0 270)
			(size 0.85 0.75)
			(layers "F.Cu" "F.Mask" "F.Paste")
			(net "EXT_EEPROM_WP")
		)
		(pad "2" smd rect
			(at 0.575 0 270)
			(size 0.85 0.75)
			(layers "F.Cu" "F.Mask" "F.Paste")
			(net "+3.3V")
		)
	)
	(footprint "Vault:RESC1608X55X25NL10T15"
		(layer "F.Cu")
		(at 83.238595 110.0786 -90)
		(property "Reference" "R17"
			(at -2.9786 -0.026921 90)
			(unlocked yes)
			(layer "F.SilkS")
			(effects
				(font
					(size 0.762 0.762)
					(thickness 0.2286)
				)
			)
		)
		(property "Value" "49.9R"
			(at -2.911602 3.21199 180)
			(unlocked yes)
			(layer "F.SilkS")
			(hide yes)
			(effects
				(font
					(size 1.524 1.524)
					(thickness 0.254)
				)
			)
		)
		(sheetname "USER_IO")
		(sheetfile "USER_IO.kicad_sch")
		(duplicate_pad_numbers_are_jumpers no)
		(pad "1" smd rect
			(at -0.7 0)
			(size 0.9 0.7)
			(layers "F.Cu" "F.Mask" "F.Paste")
			(net "NetR17_1")
		)
		(pad "2" smd rect
			(at 0.7 0)
			(size 0.9 0.7)
			(layers "F.Cu" "F.Mask" "F.Paste")
			(net "NetAN2_1")
		)
	)
	(footprint "Vault:CAPC1608X87X45ML20T05"
		(layer "F.Cu")
		(at 111.988595 143.8786 -90)
		(property "Reference" "C2"
			(at -1.8 -0.593345 90)
			(unlocked yes)
			(layer "F.SilkS")
			(effects
				(font
					(size 0.762 0.762)
					(thickness 0.2286)
				)
				(justify left bottom)
			)
		)
		(property "Value" "0.1uF"
			(at 2.31879 1.4493 0)
			(unlocked yes)
			(layer "F.SilkS")
			(hide yes)
			(effects
				(font
					(size 1.524 1.524)
					(thickness 0.254)
				)
				(justify left bottom)
			)
		)
		(sheetname "POWER")
		(sheetfile "POWER.kicad_sch")
		(duplicate_pad_numbers_are_jumpers no)
		(pad "1" smd rect
			(at -0.7 0)
			(size 1.1 1.05)
			(layers "F.Cu" "F.Mask" "F.Paste")
			(net "GND")
		)
		(pad "2" smd rect
			(at 0.7 0)
			(size 1.1 1.05)
			(layers "F.Cu" "F.Mask" "F.Paste")
			(net "+12V")
		)
	)
	(footprint "Resistors:RESC1608X50N"
		(layer "F.Cu")
		(at 229.934595 106.8306 90)
		(property "Reference" "R2"
			(at 1.477 0.522345 90)
			(unlocked yes)
			(layer "F.SilkS")
			(effects
				(font
					(size 0.762 0.762)
					(thickness 0.2286)
				)
				(justify left bottom)
			)
		)
		(property "Value" "ERJ-3EKF4702V"
			(at -3.04419 -4.4323 0)
			(unlocked yes)
			(layer "F.SilkS")
			(hide yes)
			(effects
				(font
					(size 1.524 1.524)
					(thickness 0.254)
				)
				(justify left bottom)
			)
		)
		(sheetname "POWER")
		(sheetfile "POWER.kicad_sch")
		(duplicate_pad_numbers_are_jumpers no)
		(fp_line
			(start 0 -0.5)
			(end 0 0.5)
			(stroke
				(width 0.1524)
				(type solid)
			)
			(layer "F.SilkS")
		)
		(pad "1" smd rect
			(at -0.69 0 180)
			(size 1 0.72)
			(layers "F.Cu" "F.Mask" "F.Paste")
			(net "NetR2_1")
		)
		(pad "2" smd rect
			(at 0.69 0 180)
			(size 1 0.72)
			(layers "F.Cu" "F.Mask" "F.Paste")
			(net "+12V")
		)
	)
	(footprint "Resistors:RESC1608X50N"
		(layer "F.Cu")
		(at 236.288595 112.1786 90)
		(property "Reference" "R8"
			(at 1.5 0.393345 90)
			(unlocked yes)
			(layer "F.SilkS")
			(effects
				(font
					(size 0.762 0.762)
					(thickness 0.2286)
				)
				(justify left bottom)
			)
		)
		(property "Value" "ERJ-3EKF2201V"
			(at -3.04419 -4.4323 0)
			(unlocked yes)
			(layer "F.SilkS")
			(hide yes)
			(effects
				(font
					(size 1.524 1.524)
					(thickness 0.254)
				)
				(justify left bottom)
			)
		)
		(sheetname "POWER")
		(sheetfile "POWER.kicad_sch")
		(duplicate_pad_numbers_are_jumpers no)
		(fp_line
			(start 0 -0.5)
			(end 0 0.5)
			(stroke
				(width 0.1524)
				(type solid)
			)
			(layer "F.SilkS")
		)
		(pad "1" smd rect
			(at -0.69 0 180)
			(size 1 0.72)
			(layers "F.Cu" "F.Mask" "F.Paste")
			(net "GND")
		)
		(pad "2" smd rect
			(at 0.69 0 180)
			(size 1 0.72)
			(layers "F.Cu" "F.Mask" "F.Paste")
			(net "NetC20_1")
		)
	)
	(footprint "Resistors:RESC1608X50N"
		(layer "F.Cu")
		(at 232.982595 114.4506)
		(property "Reference" "R4"
			(at -0.619 1.771345 0)
			(unlocked yes)
			(layer "F.SilkS")
			(effects
				(font
					(size 0.762 0.762)
					(thickness 0.2286)
				)
				(justify left bottom)
			)
		)
		(property "Value" "ERJ-3EKF4702V"
			(at -4.4323 3.04419 0)
			(unlocked yes)
			(layer "F.SilkS")
			(hide yes)
			(effects
				(font
					(size 1.524 1.524)
					(thickness 0.254)
				)
				(justify left bottom)
			)
		)
		(sheetname "POWER")
		(sheetfile "POWER.kicad_sch")
		(duplicate_pad_numbers_are_jumpers no)
		(fp_line
			(start 0 0.5)
			(end 0 -0.5)
			(stroke
				(width 0.1524)
				(type solid)
			)
			(layer "F.SilkS")
		)
		(pad "1" smd rect
			(at -0.69 0 90)
			(size 1 0.72)
			(layers "F.Cu" "F.Mask" "F.Paste")
			(net "+5.0V")
		)
		(pad "2" smd rect
			(at 0.69 0 90)
			(size 1 0.72)
			(layers "F.Cu" "F.Mask" "F.Paste")
			(net "NetR4_2")
		)
	)
	(footprint "Passives:DIOM1608X06N"
		(layer "F.Cu")
		(at 79.989925 53.2366 90)
		(property "Reference" "D12"
			(at -1.45369 -1.231865 90)
			(unlocked yes)
			(layer "F.SilkS")
			(effects
				(font
					(size 0.762 0.762)
					(thickness 0.2286)
				)
				(justify left bottom)
			)
		)
		(property "Value" "RED"
			(at -4.13639 -0.5715 0)
			(unlocked yes)
			(layer "F.SilkS")
			(hide yes)
			(effects
				(font
					(size 1.524 1.524)
					(thickness 0.254)
				)
				(justify left bottom)
			)
		)
		(sheetname "USER_IO")
		(sheetfile "USER_IO.kicad_sch")
		(duplicate_pad_numbers_are_jumpers no)
		(fp_circle
			(center -1.275 -0.725)
			(end -1.225 -0.725)
			(stroke
				(width 0.1)
				(type solid)
			)
			(fill no)
			(layer "F.SilkS")
		)
		(pad "1" smd rect
			(at -0.725 0 180)
			(size 0.85 1)
			(layers "F.Cu" "F.Mask" "F.Paste")
			(net "NetD12_1")
		)
		(pad "2" smd rect
			(at 0.725 0 180)
			(size 0.85 1)
			(layers "F.Cu" "F.Mask" "F.Paste")
			(net "+3.3V")
		)
	)
	(footprint "Vault:CAPC1608X87X45ML20T05"
		(layer "F.Cu")
		(at 227.648595 119.6576)
		(property "Reference" "C15"
			(at 1.74 0.414345 0)
			(unlocked yes)
			(layer "F.SilkS")
			(effects
				(font
					(size 0.762 0.762)
					(thickness 0.2286)
				)
				(justify left bottom)
			)
		)
		(property "Value" "0.1uF"
			(at -1.1811 5.63499 0)
			(unlocked yes)
			(layer "F.SilkS")
			(hide yes)
			(effects
				(font
					(size 1.524 1.524)
					(thickness 0.254)
				)
				(justify left bottom)
			)
		)
		(sheetname "POWER")
		(sheetfile "POWER.kicad_sch")
		(duplicate_pad_numbers_are_jumpers no)
		(pad "1" smd rect
			(at -0.7 0 90)
			(size 1.1 1.05)
			(layers "F.Cu" "F.Mask" "F.Paste")
			(net "GND")
		)
		(pad "2" smd rect
			(at 0.7 0 90)
			(size 1.1 1.05)
			(layers "F.Cu" "F.Mask" "F.Paste")
			(net "+5.0V")
		)
	)
	(footprint "Vault:RESC1608X55X25LL10T15"
		(layer "F.Cu")
		(at 190.738595 88.0786)
		(property "Reference" "R10"
			(at -2.2714 -0.223069 0)
			(unlocked yes)
			(layer "F.SilkS")
			(effects
				(font
					(size 0.762 0.762)
					(thickness 0.2286)
				)
			)
		)
		(property "Value" "4.7K"
			(at -2.657602 2.60264 270)
			(unlocked yes)
			(layer "F.SilkS")
			(hide yes)
			(effects
				(font
					(size 1.524 1.524)
					(thickness 0.254)
				)
			)
		)
		(sheetname "MAC")
		(sheetfile "MAC.kicad_sch")
		(duplicate_pad_numbers_are_jumpers no)
		(pad "1" smd rect
			(at -0.65 0 90)
			(size 0.8 0.6)
			(layers "F.Cu" "F.Mask" "F.Paste")
			(net "GND")
		)
		(pad "2" smd rect
			(at 0.65 0 90)
			(size 0.8 0.6)
			(layers "F.Cu" "F.Mask" "F.Paste")
			(net "FPGA_MAC_PPS_IN1-")
		)
	)
	(footprint "Passives:IND_PM124SH"
		(layer "F.Cu")
		(at 219.012595 118.6416 90)
		(property "Reference" "L1"
			(at 5.456745 -8.78815 0)
			(unlocked yes)
			(layer "F.SilkS")
			(effects
				(font
					(size 0.762 0.762)
					(thickness 0.2286)
				)
				(justify left bottom)
			)
		)
		(property "Value" "PM124SH-100M-RC"
			(at -10.00379 -10.8331 0)
			(unlocked yes)
			(layer "F.SilkS")
			(hide yes)
			(effects
				(font
					(size 1.524 1.524)
					(thickness 0.254)
				)
				(justify left bottom)
			)
		)
		(sheetname "POWER")
		(sheetfile "POWER.kicad_sch")
		(duplicate_pad_numbers_are_jumpers no)
		(fp_line
			(start 6.681 -6.4)
			(end 6.681 6.4)
			(stroke
				(width 0.254)
				(type solid)
			)
			(layer "F.SilkS")
		)
		(fp_line
			(start -6.681 -6.4)
			(end 6.681 -6.4)
			(stroke
				(width 0.254)
				(type solid)
			)
			(layer "F.SilkS")
		)
		(fp_line
			(start -6.681 -6.4)
			(end -6.681 6.4)
			(stroke
				(width 0.254)
				(type solid)
			)
			(layer "F.SilkS")
		)
		(fp_line
			(start -6.681 6.4)
			(end 6.681 6.4)
			(stroke
				(width 0.254)
				(type solid)
			)
			(layer "F.SilkS")
		)
		(pad "1" smd rect
			(at -4.85 0 90)
			(size 2.9 5.4)
			(layers "F.Cu" "F.Mask" "F.Paste")
			(net "+5.0V")
		)
		(pad "2" smd rect
			(at 4.85 0 90)
			(size 2.9 5.4)
			(layers "F.Cu" "F.Mask" "F.Paste")
			(net "NetC4_2")
		)
	)
	(footprint "Vault:TECO-1909763-1_V"
		(layer "F.Cu")
		(at 71.838595 97.5786 90)
		(property "Reference" "J6"
			(at -1.271395 2.926921 90)
			(unlocked yes)
			(layer "F.SilkS")
			(effects
				(font
					(size 0.762 0.762)
					(thickness 0.2286)
				)
			)
		)
		(property "Value" "1909763-1"
			(at 4.608085 3.749802 90)
			(unlocked yes)
			(layer "F.SilkS")
			(hide yes)
			(effects
				(font
					(size 1.524 1.524)
					(thickness 0.254)
				)
			)
		)
		(sheetname "USER_IO")
		(sheetfile "USER_IO.kicad_sch")
		(duplicate_pad_numbers_are_jumpers no)
		(fp_line
			(start -0.55 -1.3)
			(end 0.55 -1.3)
			(stroke
				(width 0.2)
				(type solid)
			)
			(layer "F.SilkS")
		)
		(fp_circle
			(center -1.778 1.65)
			(end -1.653 1.65)
			(stroke
				(width 0.25)
				(type solid)
			)
			(fill no)
			(layer "F.SilkS")
		)
		(pad "1" smd rect
			(at -1.475 0 90)
			(size 1.05 2.2)
			(layers "F.Cu" "F.Mask" "F.Paste")
			(net "GND")
		)
		(pad "2" smd rect
			(at 0 1.525 90)
			(size 1 1.05)
			(layers "F.Cu" "F.Mask" "F.Paste")
			(net "NetAN1_1")
		)
		(pad "3" smd rect
			(at 1.475 0 90)
			(size 1.05 2.2)
			(layers "F.Cu" "F.Mask" "F.Paste")
			(net "GND")
		)
	)
	(footprint "Passives:SOT65P210X110-3N"
		(layer "F.Cu")
		(at 102.488595 69.0786 180)
		(property "Reference" "D6"
			(at 1.5 -2.593345 0)
			(unlocked yes)
			(layer "F.SilkS")
			(effects
				(font
					(size 0.762 0.762)
					(thickness 0.2286)
				)
				(justify left bottom)
			)
		)
		(property "Value" "BAT54SW"
			(at 1.5875 -3.88239 0)
			(unlocked yes)
			(layer "F.SilkS")
			(hide yes)
			(effects
				(font
					(size 1.524 1.524)
					(thickness 0.254)
				)
				(justify left bottom)
			)
		)
		(sheetname "PCIe_JTAG")
		(sheetfile "PCIe_JTAG.kicad_sch")
		(duplicate_pad_numbers_are_jumpers no)
		(fp_line
			(start 0.675 1.1)
			(end -0.325 1.1)
			(stroke
				(width 0.2)
				(type solid)
			)
			(layer "F.SilkS")
		)
		(fp_line
			(start 0.675 0.65)
			(end 0.675 1.1)
			(stroke
				(width 0.2)
				(type solid)
			)
			(layer "F.SilkS")
		)
		(fp_line
			(start 0.675 -1.1)
			(end 0.675 -0.65)
			(stroke
				(width 0.2)
				(type solid)
			)
			(layer "F.SilkS")
		)
		(fp_line
			(start 0.675 -1.1)
			(end -0.325 -1.1)
			(stroke
				(width 0.2)
				(type solid)
			)
			(layer "F.SilkS")
		)
		(fp_circle
			(center -1.125 -1.45)
			(end -1.125 -1.325)
			(stroke
				(width 0.25)
				(type solid)
			)
			(fill no)
			(layer "F.SilkS")
		)
		(pad "1" smd rect
			(at -1.125 -0.65 270)
			(size 0.5 0.9)
			(layers "F.Cu" "F.Mask" "F.Paste")
			(net "GND")
		)
		(pad "2" smd rect
			(at -1.125 0.65 270)
			(size 0.5 0.9)
			(layers "F.Cu" "F.Mask" "F.Paste")
			(net "+3.3V")
		)
		(pad "3" smd rect
			(at 1.125 0 270)
			(size 0.5 0.9)
			(layers "F.Cu" "F.Mask" "F.Paste")
			(net "FPGA_TDO")
		)
	)
	(footprint "Connectors:SAMTEC_HTST-105-01-L-DV-A"
		(layer "F.Cu")
		(at 104.617595 56.7916)
		(property "Reference" "U5"
			(at -9.629 -3.119655 0)
			(unlocked yes)
			(layer "F.SilkS")
			(effects
				(font
					(size 0.762 0.762)
					(thickness 0.2286)
				)
				(justify left bottom)
			)
		)
		(property "Value" "HTST-105-01-L-DV-A"
			(at -4.3317 21.99359 0)
			(unlocked yes)
			(layer "F.SilkS")
			(hide yes)
			(effects
				(font
					(size 1.524 1.524)
					(thickness 0.254)
				)
				(justify left bottom)
			)
		)
		(sheetname "PCIe_JTAG")
		(sheetfile "PCIe_JTAG.kicad_sch")
		(duplicate_pad_numbers_are_jumpers no)
		(fp_line
			(start -10.16 -4.635)
			(end -6.065 -4.635)
			(stroke
				(width 0.2)
				(type solid)
			)
			(layer "F.SilkS")
		)
		(fp_line
			(start -10.16 4.635)
			(end -10.16 -4.635)
			(stroke
				(width 0.2)
				(type solid)
			)
			(layer "F.SilkS")
		)
		(fp_line
			(start -10.16 4.635)
			(end -6.065 4.635)
			(stroke
				(width 0.2)
				(type solid)
			)
			(layer "F.SilkS")
		)
		(fp_line
			(start 6.065 -4.635)
			(end 10.16 -4.635)
			(stroke
				(width 0.2)
				(type solid)
			)
			(layer "F.SilkS")
		)
		(fp_line
			(start 6.065 4.635)
			(end 10.16 4.635)
			(stroke
				(width 0.2)
				(type solid)
			)
			(layer "F.SilkS")
		)
		(fp_line
			(start 10.16 4.635)
			(end 10.16 -4.635)
			(stroke
				(width 0.2)
				(type solid)
			)
			(layer "F.SilkS")
		)
		(fp_circle
			(center -7.62 5.715)
			(end -7.62 5.08)
			(stroke
				(width 0.2)
				(type solid)
			)
			(fill no)
			(layer "F.SilkS")
		)
		(pad "" np_thru_hole circle
			(at -3.81 0)
			(size 1.676 1.676)
			(drill 1.676)
			(layers "*.Cu" "*.Mask")
			(thermal_bridge_angle 90)
		)
		(pad "" np_thru_hole circle
			(at 3.81 0)
			(size 1.676 1.676)
			(drill 1.676)
			(layers "*.Cu" "*.Mask")
			(thermal_bridge_angle 90)
		)
		(pad "1" smd rect
			(at -5.08 3.43)
			(size 1.27 5.08)
			(layers "F.Cu" "F.Mask" "F.Paste")
			(net "NetR18_2")
		)
		(pad "2" smd rect
			(at -5.08 -3.43)
			(size 1.27 5.08)
			(layers "F.Cu" "F.Mask" "F.Paste")
			(net "GND")
		)
		(pad "3" smd rect
			(at -2.54 3.43)
			(size 1.27 5.08)
			(layers "F.Cu" "F.Mask" "F.Paste")
			(net "NetR19_2")
		)
		(pad "4" smd rect
			(at -2.54 -3.43)
			(size 1.27 5.08)
			(layers "F.Cu" "F.Mask" "F.Paste")
			(net "+3.3V")
		)
		(pad "5" smd rect
			(at 0 3.43)
			(size 1.27 5.08)
			(layers "F.Cu" "F.Mask" "F.Paste")
			(net "NetR20_2")
		)
		(pad "6" smd rect
			(at 0 -3.43)
			(size 1.27 5.08)
			(layers "F.Cu" "F.Mask" "F.Paste")
			(net "+3.3V")
		)
		(pad "7" smd rect
			(at 2.54 3.43)
			(size 1.27 5.08)
			(layers "F.Cu" "F.Mask" "F.Paste")
		)
		(pad "8" smd rect
			(at 2.54 -3.43)
			(size 1.27 5.08)
			(layers "F.Cu" "F.Mask" "F.Paste")
		)
		(pad "9" smd rect
			(at 5.08 3.43)
			(size 1.27 5.08)
			(layers "F.Cu" "F.Mask" "F.Paste")
			(net "NetR21_2")
		)
		(pad "10" smd rect
			(at 5.08 -3.43)
			(size 1.27 5.08)
			(layers "F.Cu" "F.Mask" "F.Paste")
			(net "GND")
		)
	)
	(footprint "Vault:RESC1608X55X30NL15T15"
		(layer "F.Cu")
		(at 120.238595 90.5786 90)
		(property "Reference" "R26"
			(at 3.14763 0.055781 90)
			(unlocked yes)
			(layer "F.SilkS")
			(effects
				(font
					(size 0.762 0.762)
					(thickness 0.2286)
				)
			)
		)
		(property "Value" "4.7K"
			(at -3.114802 2.39944 0)
			(unlocked yes)
			(layer "F.SilkS")
			(hide yes)
			(effects
				(font
					(size 1.524 1.524)
					(thickness 0.254)
				)
			)
		)
		(sheetname "GPS_IMU_SENSORS")
		(sheetfile "GPS_IMU_SENSORS.kicad_sch")
		(duplicate_pad_numbers_are_jumpers no)
		(pad "1" smd rect
			(at -0.75 0 180)
			(size 0.95 0.95)
			(layers "F.Cu" "F.Mask" "F.Paste")
			(net "SDA")
		)
		(pad "2" smd rect
			(at 0.75 0 180)
			(size 0.95 0.95)
			(layers "F.Cu" "F.Mask" "F.Paste")
			(net "+3.3V")
		)
	)
	(footprint "Passives:DIOM1608X06N"
		(layer "F.Cu")
		(at 90.234595 53.2366 90)
		(property "Reference" "D14"
			(at -1.47909 -1.367335 90)
			(unlocked yes)
			(layer "F.SilkS")
			(effects
				(font
					(size 0.762 0.762)
					(thickness 0.2286)
				)
				(justify left bottom)
			)
		)
		(property "Value" "RED"
			(at -4.13639 -0.5715 0)
			(unlocked yes)
			(layer "F.SilkS")
			(hide yes)
			(effects
				(font
					(size 1.524 1.524)
					(thickness 0.254)
				)
				(justify left bottom)
			)
		)
		(sheetname "USER_IO")
		(sheetfile "USER_IO.kicad_sch")
		(duplicate_pad_numbers_are_jumpers no)
		(fp_circle
			(center -1.275 -0.725)
			(end -1.225 -0.725)
			(stroke
				(width 0.1)
				(type solid)
			)
			(fill no)
			(layer "F.SilkS")
		)
		(pad "1" smd rect
			(at -0.725 0 180)
			(size 0.85 1)
			(layers "F.Cu" "F.Mask" "F.Paste")
			(net "NetD14_1")
		)
		(pad "2" smd rect
			(at 0.725 0 180)
			(size 0.85 1)
			(layers "F.Cu" "F.Mask" "F.Paste")
			(net "+3.3V")
		)
	)
	(footprint "Connectors:AMPHENOL-901-143-6RFX"
		(layer "F.Cu")
		(at 63.564595 137.5646 180)
		(property "Reference" "AN4"
			(at 4.076 -6.107345 0)
			(unlocked yes)
			(layer "F.SilkS")
			(effects
				(font
					(size 0.762 0.762)
					(thickness 0.2286)
				)
				(justify left bottom)
			)
		)
		(property "Value" "901-143-6RFX"
			(at 4.6101 -12.21359 0)
			(unlocked yes)
			(layer "F.SilkS")
			(hide yes)
			(effects
				(font
					(size 1.524 1.524)
					(thickness 0.254)
				)
				(justify left bottom)
			)
		)
		(sheetname "USER_IO")
		(sheetfile "USER_IO.kicad_sch")
		(duplicate_pad_numbers_are_jumpers no)
		(fp_line
			(start 4.318 3.556)
			(end 3.302 4.572)
			(stroke
				(width 0.1778)
				(type solid)
			)
			(layer "F.SilkS")
		)
		(fp_line
			(start 4.318 -3.556)
			(end 3.302 -4.572)
			(stroke
				(width 0.1778)
				(type solid)
			)
			(layer "F.SilkS")
		)
		(fp_line
			(start 3.302 4.572)
			(end 2.54 4.572)
			(stroke
				(width 0.1778)
				(type solid)
			)
			(layer "F.SilkS")
		)
		(fp_line
			(start 3.302 -4.572)
			(end 2.54 -4.572)
			(stroke
				(width 0.1778)
				(type solid)
			)
			(layer "F.SilkS")
		)
		(fp_line
			(start 2.54 4.572)
			(end -4.572 4.572)
			(stroke
				(width 0.1778)
				(type solid)
			)
			(layer "F.SilkS")
		)
		(fp_line
			(start 2.54 -4.572)
			(end -4.572 -4.572)
			(stroke
				(width 0.1778)
				(type solid)
			)
			(layer "F.SilkS")
		)
		(fp_line
			(start -4.572 2.54)
			(end -4.572 4.572)
			(stroke
				(width 0.1778)
				(type solid)
			)
			(layer "F.SilkS")
		)
		(fp_line
			(start -4.572 -4.572)
			(end -4.572 -2.54)
			(stroke
				(width 0.1778)
				(type solid)
			)
			(layer "F.SilkS")
		)
		(pad "1" thru_hole circle
			(at 0 0 180)
			(size 2.8448 2.8448)
			(drill 1.524)
			(layers "*.Cu" "*.Mask")
			(remove_unused_layers no)
			(net "NetAN4_1")
			(thermal_bridge_angle 90)
		)
		(pad "2" thru_hole circle
			(at -2.54 2.54 180)
			(size 3.048 3.048)
			(drill 1.7272)
			(layers "*.Cu" "*.Mask")
			(remove_unused_layers no)
			(net "GND")
			(thermal_bridge_angle 90)
		)
		(pad "3" thru_hole circle
			(at -2.54 -2.54 180)
			(size 3.048 3.048)
			(drill 1.7272)
			(layers "*.Cu" "*.Mask")
			(remove_unused_layers no)
			(net "GND")
			(thermal_bridge_angle 90)
		)
		(pad "4" thru_hole circle
			(at 2.54 -2.54 180)
			(size 3.048 3.048)
			(drill 1.7272)
			(layers "*.Cu" "*.Mask")
			(remove_unused_layers no)
			(net "GND")
			(thermal_bridge_angle 90)
		)
		(pad "5" thru_hole circle
			(at 2.54 2.54 180)
			(size 3.048 3.048)
			(drill 1.7272)
			(layers "*.Cu" "*.Mask")
			(remove_unused_layers no)
			(net "GND")
			(thermal_bridge_angle 90)
		)
	)
	(footprint "Capacitors:CAPC2012X14N"
		(layer "F.Cu")
		(at 220.088595 87.9786 90)
		(property "Reference" "C8"
			(at 3 0.393345 90)
			(unlocked yes)
			(layer "F.SilkS")
			(effects
				(font
					(size 0.762 0.762)
					(thickness 0.2286)
				)
				(justify left bottom)
			)
		)
		(property "Value" "CAP_0805_10UF_25V"
			(at -10.63879 10.0965 0)
			(unlocked yes)
			(layer "F.SilkS")
			(hide yes)
			(effects
				(font
					(size 1.524 1.524)
					(thickness 0.254)
				)
				(justify left bottom)
			)
		)
		(sheetname "POWER")
		(sheetfile "POWER.kicad_sch")
		(duplicate_pad_numbers_are_jumpers no)
		(fp_line
			(start -0.762 -0.9652)
			(end 0.762 -0.9652)
			(stroke
				(width 0.1524)
				(type solid)
			)
			(layer "F.SilkS")
		)
		(fp_line
			(start -0.762 0.9652)
			(end 0.762 0.9652)
			(stroke
				(width 0.1524)
				(type solid)
			)
			(layer "F.SilkS")
		)
		(pad "1" smd rect
			(at -0.9 0 180)
			(size 1.45 1.15)
			(layers "F.Cu" "F.Mask" "F.Paste")
			(net "+3.3V")
		)
		(pad "2" smd rect
			(at 0.9 0 180)
			(size 1.45 1.15)
			(layers "F.Cu" "F.Mask" "F.Paste")
			(net "GND")
		)
	)
	(footprint "FPGA_CONN:FPGA_CONN"
		(locked yes)
		(layer "F.Cu")
		(at 125.389655 117.4386)
		(property "Reference" "P1"
			(at -27.35726 -23.265455 0)
			(unlocked yes)
			(layer "F.SilkS")
			(effects
				(font
					(size 0.762 0.762)
					(thickness 0.2286)
				)
				(justify left bottom)
			)
		)
		(property "Value" "FPGA_CONN"
			(at -43.9575 52.70297 0)
			(unlocked yes)
			(layer "F.SilkS")
			(hide yes)
			(effects
				(font
					(size 1.524 1.524)
					(thickness 0.254)
				)
				(justify left bottom)
			)
		)
		(sheetname "FPGA")
		(sheetfile "FPGA.kicad_sch")
		(duplicate_pad_numbers_are_jumpers no)
		(fp_line
			(start -27.51976 -22.5712)
			(end 27.48039 -22.5712)
			(stroke
				(width 0.127)
				(type solid)
			)
			(layer "F.SilkS")
		)
		(fp_line
			(start -27.51976 22.42896)
			(end -27.51976 -22.5712)
			(stroke
				(width 0.127)
				(type solid)
			)
			(layer "F.SilkS")
		)
		(fp_line
			(start -27.51976 22.42896)
			(end 27.48039 22.42896)
			(stroke
				(width 0.127)
				(type solid)
			)
			(layer "F.SilkS")
		)
		(fp_line
			(start -25.81135 -10.82624)
			(end -25.21141 -10.82624)
			(stroke
				(width 0.15011)
				(type solid)
			)
			(layer "F.SilkS")
		)
		(fp_line
			(start -25.81135 -10.15924)
			(end -25.81135 -10.82624)
			(stroke
				(width 0.15011)
				(type solid)
			)
			(layer "F.SilkS")
		)
		(fp_line
			(start -25.81135 10.57377)
			(end -25.81135 9.90676)
			(stroke
				(width 0.15011)
				(type solid)
			)
			(layer "F.SilkS")
		)
		(fp_line
			(start -25.81135 10.57377)
			(end -25.21141 10.57377)
			(stroke
				(width 0.15011)
				(type solid)
			)
			(layer "F.SilkS")
		)
		(fp_line
			(start -25.21141 -11.37615)
			(end -22.41131 -11.37615)
			(stroke
				(width 0.15011)
				(type solid)
			)
			(layer "F.SilkS")
		)
		(fp_line
			(start -25.21141 -10.82624)
			(end -25.21141 -11.37615)
			(stroke
				(width 0.15011)
				(type solid)
			)
			(layer "F.SilkS")
		)
		(fp_line
			(start -25.21141 11.12368)
			(end -25.21141 10.57377)
			(stroke
				(width 0.15011)
				(type solid)
			)
			(layer "F.SilkS")
		)
		(fp_line
			(start -25.21141 11.12368)
			(end -22.41131 11.12368)
			(stroke
				(width 0.15011)
				(type solid)
			)
			(layer "F.SilkS")
		)
		(fp_line
			(start -22.41131 -10.82624)
			(end -22.41131 -11.37615)
			(stroke
				(width 0.15011)
				(type solid)
			)
			(layer "F.SilkS")
		)
		(fp_line
			(start -22.41131 -10.82624)
			(end -21.81136 -10.82624)
			(stroke
				(width 0.15011)
				(type solid)
			)
			(layer "F.SilkS")
		)
		(fp_line
			(start -22.41131 10.57377)
			(end -21.81136 10.57377)
			(stroke
				(width 0.15011)
				(type solid)
			)
			(layer "F.SilkS")
		)
		(fp_line
			(start -22.41131 11.12368)
			(end -22.41131 10.57377)
			(stroke
				(width 0.15011)
				(type solid)
			)
			(layer "F.SilkS")
		)
		(fp_line
			(start -21.81136 -10.15924)
			(end -21.81136 -10.82624)
			(stroke
				(width 0.15011)
				(type solid)
			)
			(layer "F.SilkS")
		)
		(fp_line
			(start -21.81136 10.57377)
			(end -21.81136 9.90676)
			(stroke
				(width 0.15011)
				(type solid)
			)
			(layer "F.SilkS")
		)
		(fp_line
			(start -12.20127 -20.19529)
			(end -11.65136 -20.19529)
			(stroke
				(width 0.15011)
				(type solid)
			)
			(layer "F.SilkS")
		)
		(fp_line
			(start -12.20127 -17.39519)
			(end -12.20127 -20.19529)
			(stroke
				(width 0.15011)
				(type solid)
			)
			(layer "F.SilkS")
		)
		(fp_line
			(start -12.20127 -17.39519)
			(end -11.65136 -17.39519)
			(stroke
				(width 0.15011)
				(type solid)
			)
			(layer "F.SilkS")
		)
		(fp_line
			(start -12.20102 17.39519)
			(end -11.65111 17.39519)
			(stroke
				(width 0.15011)
				(type solid)
			)
			(layer "F.SilkS")
		)
		(fp_line
			(start -12.20102 20.19529)
			(end -12.20102 17.39519)
			(stroke
				(width 0.15011)
				(type solid)
			)
			(layer "F.SilkS")
		)
		(fp_line
			(start -12.20102 20.19529)
			(end -11.65111 20.19529)
			(stroke
				(width 0.15011)
				(type solid)
			)
			(layer "F.SilkS")
		)
		(fp_line
			(start -11.65136 -20.79523)
			(end -10.98436 -20.79523)
			(stroke
				(width 0.15011)
				(type solid)
			)
			(layer "F.SilkS")
		)
		(fp_line
			(start -11.65136 -20.19529)
			(end -11.65136 -20.79523)
			(stroke
				(width 0.15011)
				(type solid)
			)
			(layer "F.SilkS")
		)
		(fp_line
			(start -11.65136 -16.79524)
			(end -11.65136 -17.39519)
			(stroke
				(width 0.15011)
				(type solid)
			)
			(layer "F.SilkS")
		)
		(fp_line
			(start -11.65136 -16.79524)
			(end -10.98436 -16.79524)
			(stroke
				(width 0.15011)
				(type solid)
			)
			(layer "F.SilkS")
		)
		(fp_line
			(start -11.65111 16.79524)
			(end -10.9841 16.79524)
			(stroke
				(width 0.15011)
				(type solid)
			)
			(layer "F.SilkS")
		)
		(fp_line
			(start -11.65111 17.39519)
			(end -11.65111 16.79524)
			(stroke
				(width 0.15011)
				(type solid)
			)
			(layer "F.SilkS")
		)
		(fp_line
			(start -11.65111 20.79523)
			(end -11.65111 20.19529)
			(stroke
				(width 0.15011)
				(type solid)
			)
			(layer "F.SilkS")
		)
		(fp_line
			(start -11.65111 20.79523)
			(end -10.9841 20.79523)
			(stroke
				(width 0.15011)
				(type solid)
			)
			(layer "F.SilkS")
		)
		(fp_line
			(start 9.08164 -20.79523)
			(end 9.74865 -20.79523)
			(stroke
				(width 0.15011)
				(type solid)
			)
			(layer "F.SilkS")
		)
		(fp_line
			(start 9.08164 -16.79524)
			(end 9.74865 -16.79524)
			(stroke
				(width 0.15011)
				(type solid)
			)
			(layer "F.SilkS")
		)
		(fp_line
			(start 9.0819 16.79524)
			(end 9.7489 16.79524)
			(stroke
				(width 0.15011)
				(type solid)
			)
			(layer "F.SilkS")
		)
		(fp_line
			(start 9.0819 20.79523)
			(end 9.7489 20.79523)
			(stroke
				(width 0.15011)
				(type solid)
			)
			(layer "F.SilkS")
		)
		(fp_line
			(start 9.74865 -20.19529)
			(end 9.74865 -20.79523)
			(stroke
				(width 0.15011)
				(type solid)
			)
			(layer "F.SilkS")
		)
		(fp_line
			(start 9.74865 -20.19529)
			(end 10.29856 -20.19529)
			(stroke
				(width 0.15011)
				(type solid)
			)
			(layer "F.SilkS")
		)
		(fp_line
			(start 9.74865 -17.39519)
			(end 10.29856 -17.39519)
			(stroke
				(width 0.15011)
				(type solid)
			)
			(layer "F.SilkS")
		)
		(fp_line
			(start 9.74865 -16.79524)
			(end 9.74865 -17.39519)
			(stroke
				(width 0.15011)
				(type solid)
			)
			(layer "F.SilkS")
		)
		(fp_line
			(start 9.7489 17.39519)
			(end 9.7489 16.79524)
			(stroke
				(width 0.15011)
				(type solid)
			)
			(layer "F.SilkS")
		)
		(fp_line
			(start 9.7489 17.39519)
			(end 10.29881 17.39519)
			(stroke
				(width 0.15011)
				(type solid)
			)
			(layer "F.SilkS")
		)
		(fp_line
			(start 9.7489 20.19529)
			(end 10.29881 20.19529)
			(stroke
				(width 0.15011)
				(type solid)
			)
			(layer "F.SilkS")
		)
		(fp_line
			(start 9.7489 20.79523)
			(end 9.7489 20.19529)
			(stroke
				(width 0.15011)
				(type solid)
			)
			(layer "F.SilkS")
		)
		(fp_line
			(start 10.29856 -17.39519)
			(end 10.29856 -20.19529)
			(stroke
				(width 0.15011)
				(type solid)
			)
			(layer "F.SilkS")
		)
		(fp_line
			(start 10.29881 20.19529)
			(end 10.29881 17.39519)
			(stroke
				(width 0.15011)
				(type solid)
			)
			(layer "F.SilkS")
		)
		(fp_line
			(start 21.81136 -10.82523)
			(end 22.41131 -10.82523)
			(stroke
				(width 0.15011)
				(type solid)
			)
			(layer "F.SilkS")
		)
		(fp_line
			(start 21.81136 -10.15822)
			(end 21.81136 -10.82523)
			(stroke
				(width 0.15011)
				(type solid)
			)
			(layer "F.SilkS")
		)
		(fp_line
			(start 21.81136 10.57478)
			(end 21.81136 9.90778)
			(stroke
				(width 0.15011)
				(type solid)
			)
			(layer "F.SilkS")
		)
		(fp_line
			(start 21.81136 10.57478)
			(end 22.41131 10.57478)
			(stroke
				(width 0.15011)
				(type solid)
			)
			(layer "F.SilkS")
		)
		(fp_line
			(start 22.41131 -11.37514)
			(end 25.2114 -11.37514)
			(stroke
				(width 0.15011)
				(type solid)
			)
			(layer "F.SilkS")
		)
		(fp_line
			(start 22.41131 -10.82523)
			(end 22.41131 -11.37514)
			(stroke
				(width 0.15011)
				(type solid)
			)
			(layer "F.SilkS")
		)
		(fp_line
			(start 22.41131 11.12469)
			(end 22.41131 10.57478)
			(stroke
				(width 0.15011)
				(type solid)
			)
			(layer "F.SilkS")
		)
		(fp_line
			(start 22.41131 11.12469)
			(end 25.2114 11.12469)
			(stroke
				(width 0.15011)
				(type solid)
			)
			(layer "F.SilkS")
		)
		(fp_line
			(start 25.2114 -10.82523)
			(end 25.2114 -11.37514)
			(stroke
				(width 0.15011)
				(type solid)
			)
			(layer "F.SilkS")
		)
		(fp_line
			(start 25.2114 -10.82523)
			(end 25.81135 -10.82523)
			(stroke
				(width 0.15011)
				(type solid)
			)
			(layer "F.SilkS")
		)
		(fp_line
			(start 25.2114 10.57478)
			(end 25.81135 10.57478)
			(stroke
				(width 0.15011)
				(type solid)
			)
			(layer "F.SilkS")
		)
		(fp_line
			(start 25.2114 11.12469)
			(end 25.2114 10.57478)
			(stroke
				(width 0.15011)
				(type solid)
			)
			(layer "F.SilkS")
		)
		(fp_line
			(start 25.81135 -10.15822)
			(end 25.81135 -10.82523)
			(stroke
				(width 0.15011)
				(type solid)
			)
			(layer "F.SilkS")
		)
		(fp_line
			(start 25.81135 10.57478)
			(end 25.81135 9.90778)
			(stroke
				(width 0.15011)
				(type solid)
			)
			(layer "F.SilkS")
		)
		(fp_line
			(start 27.48039 22.42896)
			(end 27.48039 -22.5712)
			(stroke
				(width 0.127)
				(type solid)
			)
			(layer "F.SilkS")
		)
		(fp_circle
			(center -20.30616 9.64921)
			(end -20.30616 9.44906)
			(stroke
				(width 0.40005)
				(type solid)
			)
			(fill no)
			(layer "F.SilkS")
		)
		(fp_circle
			(center -10.7268 -15.29004)
			(end -10.7268 -15.49019)
			(stroke
				(width 0.40005)
				(type solid)
			)
			(fill no)
			(layer "F.SilkS")
		)
		(fp_circle
			(center 8.82434 15.29004)
			(end 8.82434 15.08989)
			(stroke
				(width 0.40005)
				(type solid)
			)
			(fill no)
			(layer "F.SilkS")
		)
		(fp_circle
			(center 20.30616 -9.90067)
			(end 20.30616 -10.10082)
			(stroke
				(width 0.40005)
				(type solid)
			)
			(fill no)
			(layer "F.SilkS")
		)
		(fp_text user "3"
			(at -24.53272 -12.1572 360)
			(unlocked yes)
			(layer "F.SilkS")
			(effects
				(font
					(size 1.524 1.524)
					(thickness 0.254)
				)
				(justify left bottom)
			)
		)
		(fp_text user "2"
			(at -14.37272 -17.8722 360)
			(unlocked yes)
			(layer "F.SilkS")
			(effects
				(font
					(size 1.524 1.524)
					(thickness 0.254)
				)
				(justify left bottom)
			)
		)
		(fp_text user "4"
			(at -14.37272 19.5928 360)
			(unlocked yes)
			(layer "F.SilkS")
			(effects
				(font
					(size 1.524 1.524)
					(thickness 0.254)
				)
				(justify left bottom)
			)
		)
		(fp_text user "1"
			(at 23.09228 -12.1572 360)
			(unlocked yes)
			(layer "F.SilkS")
			(effects
				(font
					(size 1.524 1.524)
					(thickness 0.254)
				)
				(justify left bottom)
			)
		)
		(pad "A-1" smd rect
			(at 21.78647 -9.87527)
			(size 1.54991 0.24994)
			(layers "F.Cu" "F.Mask" "F.Paste")
			(net "+5.0V")
		)
		(pad "A-2" smd rect
			(at 25.83624 -9.87527)
			(size 1.54991 0.24994)
			(layers "F.Cu" "F.Mask" "F.Paste")
			(net "+5.0V")
		)
		(pad "A-3" smd rect
			(at 21.78647 -9.37514)
			(size 1.54991 0.24994)
			(layers "F.Cu" "F.Mask" "F.Paste")
			(net "+5.0V")
		)
		(pad "A-4" smd rect
			(at 25.83624 -9.37514)
			(size 1.54991 0.24994)
			(layers "F.Cu" "F.Mask" "F.Paste")
			(net "+5.0V")
		)
		(pad "A-5" smd rect
			(at 21.78647 -8.87527)
			(size 1.54991 0.24994)
			(layers "F.Cu" "F.Mask" "F.Paste")
			(net "+5.0V")
		)
		(pad "A-6" smd rect
			(at 25.83624 -8.87527)
			(size 1.54991 0.24994)
			(layers "F.Cu" "F.Mask" "F.Paste")
			(net "+5.0V")
		)
		(pad "A-7" smd rect
			(at 21.78647 -8.37514)
			(size 1.54991 0.24994)
			(layers "F.Cu" "F.Mask" "F.Paste")
			(net "+5.0V")
		)
		(pad "A-8" smd rect
			(at 25.83624 -8.37514)
			(size 1.54991 0.24994)
			(layers "F.Cu" "F.Mask" "F.Paste")
			(net "+5.0V")
		)
		(pad "A-9" smd rect
			(at 21.78647 -7.87527)
			(size 1.54991 0.24994)
			(layers "F.Cu" "F.Mask" "F.Paste")
			(net "GND")
		)
		(pad "A-10" smd rect
			(at 25.83624 -7.87527)
			(size 1.54991 0.24994)
			(layers "F.Cu" "F.Mask" "F.Paste")
			(net "GND")
		)
		(pad "A-11" smd rect
			(at 21.78647 -7.37514)
			(size 1.54991 0.24994)
			(layers "F.Cu" "F.Mask" "F.Paste")
		)
		(pad "A-12" smd rect
			(at 25.83624 -7.37514)
			(size 1.54991 0.24994)
			(layers "F.Cu" "F.Mask" "F.Paste")
		)
		(pad "A-13" smd rect
			(at 21.78647 -6.87527)
			(size 1.54991 0.24994)
			(layers "F.Cu" "F.Mask" "F.Paste")
		)
		(pad "A-14" smd rect
			(at 25.83624 -6.87527)
			(size 1.54991 0.24994)
			(layers "F.Cu" "F.Mask" "F.Paste")
		)
		(pad "A-15" smd rect
			(at 21.78647 -6.37515)
			(size 1.54991 0.24994)
			(layers "F.Cu" "F.Mask" "F.Paste")
		)
		(pad "A-16" smd rect
			(at 25.83624 -6.37515)
			(size 1.54991 0.24994)
			(layers "F.Cu" "F.Mask" "F.Paste")
		)
		(pad "A-17" smd rect
			(at 21.78647 -5.87527)
			(size 1.54991 0.24994)
			(layers "F.Cu" "F.Mask" "F.Paste")
		)
		(pad "A-18" smd rect
			(at 25.83624 -5.87527)
			(size 1.54991 0.24994)
			(layers "F.Cu" "F.Mask" "F.Paste")
		)
		(pad "A-19" smd rect
			(at 21.78647 -5.37515)
			(size 1.54991 0.24994)
			(layers "F.Cu" "F.Mask" "F.Paste")
			(net "GND")
		)
		(pad "A-20" smd rect
			(at 25.83624 -5.37515)
			(size 1.54991 0.24994)
			(layers "F.Cu" "F.Mask" "F.Paste")
			(net "GND")
		)
		(pad "A-21" smd rect
			(at 21.78647 -4.87528)
			(size 1.54991 0.24994)
			(layers "F.Cu" "F.Mask" "F.Paste")
		)
		(pad "A-22" smd rect
			(at 25.83624 -4.87528)
			(size 1.54991 0.24994)
			(layers "F.Cu" "F.Mask" "F.Paste")
			(net "GPS1_RST")
		)
		(pad "A-23" smd rect
			(at 21.78647 -4.37515)
			(size 1.54991 0.24994)
			(layers "F.Cu" "F.Mask" "F.Paste")
		)
		(pad "A-24" smd rect
			(at 25.83624 -4.37515)
			(size 1.54991 0.24994)
			(layers "F.Cu" "F.Mask" "F.Paste")
		)
		(pad "A-25" smd rect
			(at 21.78647 -3.87528)
			(size 1.54991 0.24994)
			(layers "F.Cu" "F.Mask" "F.Paste")
		)
		(pad "A-26" smd rect
			(at 25.83624 -3.87528)
			(size 1.54991 0.24994)
			(layers "F.Cu" "F.Mask" "F.Paste")
		)
		(pad "A-27" smd rect
			(at 21.78647 -3.37515)
			(size 1.54991 0.24994)
			(layers "F.Cu" "F.Mask" "F.Paste")
		)
		(pad "A-28" smd rect
			(at 25.83624 -3.37515)
			(size 1.54991 0.24994)
			(layers "F.Cu" "F.Mask" "F.Paste")
		)
		(pad "A-29" smd rect
			(at 21.78647 -2.87528)
			(size 1.54991 0.24994)
			(layers "F.Cu" "F.Mask" "F.Paste")
			(net "GND")
		)
		(pad "A-30" smd rect
			(at 25.83624 -2.87528)
			(size 1.54991 0.24994)
			(layers "F.Cu" "F.Mask" "F.Paste")
			(net "GND")
		)
		(pad "A-31" smd rect
			(at 21.78647 -2.37515)
			(size 1.54991 0.24994)
			(layers "F.Cu" "F.Mask" "F.Paste")
		)
		(pad "A-32" smd rect
			(at 25.83624 -2.37515)
			(size 1.54991 0.24994)
			(layers "F.Cu" "F.Mask" "F.Paste")
			(net "GPS1_TP1")
		)
		(pad "A-33" smd rect
			(at 21.78647 -1.87528)
			(size 1.54991 0.24994)
			(layers "F.Cu" "F.Mask" "F.Paste")
		)
		(pad "A-34" smd rect
			(at 25.83624 -1.87528)
			(size 1.54991 0.24994)
			(layers "F.Cu" "F.Mask" "F.Paste")
			(net "GPS1_TP2")
		)
		(pad "A-35" smd rect
			(at 21.78647 -1.37516)
			(size 1.54991 0.24994)
			(layers "F.Cu" "F.Mask" "F.Paste")
		)
		(pad "A-36" smd rect
			(at 25.83624 -1.37516)
			(size 1.54991 0.24994)
			(layers "F.Cu" "F.Mask" "F.Paste")
		)
		(pad "A-37" smd rect
			(at 21.78647 -0.87528)
			(size 1.54991 0.24994)
			(layers "F.Cu" "F.Mask" "F.Paste")
		)
		(pad "A-38" smd rect
			(at 25.83624 -0.87528)
			(size 1.54991 0.24994)
			(layers "F.Cu" "F.Mask" "F.Paste")
		)
		(pad "A-39" smd rect
			(at 21.78647 -0.37516)
			(size 1.54991 0.24994)
			(layers "F.Cu" "F.Mask" "F.Paste")
			(net "GND")
		)
		(pad "A-40" smd rect
			(at 25.83624 -0.37516)
			(size 1.54991 0.24994)
			(layers "F.Cu" "F.Mask" "F.Paste")
			(net "GND")
		)
		(pad "A-41" smd rect
			(at 21.78647 0.12471)
			(size 1.54991 0.24994)
			(layers "F.Cu" "F.Mask" "F.Paste")
		)
		(pad "A-42" smd rect
			(at 25.83624 0.12471)
			(size 1.54991 0.24994)
			(layers "F.Cu" "F.Mask" "F.Paste")
		)
		(pad "A-43" smd rect
			(at 21.78647 0.62484)
			(size 1.54991 0.24994)
			(layers "F.Cu" "F.Mask" "F.Paste")
		)
		(pad "A-44" smd rect
			(at 25.83624 0.62484)
			(size 1.54991 0.24994)
			(layers "F.Cu" "F.Mask" "F.Paste")
			(net "EXT_EEPROM_WP")
		)
		(pad "A-45" smd rect
			(at 21.78647 1.12471)
			(size 1.54991 0.24994)
			(layers "F.Cu" "F.Mask" "F.Paste")
		)
		(pad "A-46" smd rect
			(at 25.83624 1.12471)
			(size 1.54991 0.24994)
			(layers "F.Cu" "F.Mask" "F.Paste")
		)
		(pad "A-47" smd rect
			(at 21.78647 1.62484)
			(size 1.54991 0.24994)
			(layers "F.Cu" "F.Mask" "F.Paste")
		)
		(pad "A-48" smd rect
			(at 25.83624 1.62484)
			(size 1.54991 0.24994)
			(layers "F.Cu" "F.Mask" "F.Paste")
		)
		(pad "A-49" smd rect
			(at 21.78647 2.12471)
			(size 1.54991 0.24994)
			(layers "F.Cu" "F.Mask" "F.Paste")
			(net "GND")
		)
		(pad "A-50" smd rect
			(at 25.83624 2.12471)
			(size 1.54991 0.24994)
			(layers "F.Cu" "F.Mask" "F.Paste")
			(net "GND")
		)
		(pad "A-51" smd rect
			(at 21.78647 2.62484)
			(size 1.54991 0.24994)
			(layers "F.Cu" "F.Mask" "F.Paste")
		)
		(pad "A-52" smd rect
			(at 25.83624 2.62484)
			(size 1.54991 0.24994)
			(layers "F.Cu" "F.Mask" "F.Paste")
		)
		(pad "A-53" smd rect
			(at 21.78647 3.12471)
			(size 1.54991 0.24994)
			(layers "F.Cu" "F.Mask" "F.Paste")
		)
		(pad "A-54" smd rect
			(at 25.83624 3.12471)
			(size 1.54991 0.24994)
			(layers "F.Cu" "F.Mask" "F.Paste")
		)
		(pad "A-55" smd rect
			(at 21.78647 3.62483)
			(size 1.54991 0.24994)
			(layers "F.Cu" "F.Mask" "F.Paste")
		)
		(pad "A-56" smd rect
			(at 25.83624 3.62483)
			(size 1.54991 0.24994)
			(layers "F.Cu" "F.Mask" "F.Paste")
		)
		(pad "A-57" smd rect
			(at 21.78647 4.12471)
			(size 1.54991 0.24994)
			(layers "F.Cu" "F.Mask" "F.Paste")
		)
		(pad "A-58" smd rect
			(at 25.83624 4.12471)
			(size 1.54991 0.24994)
			(layers "F.Cu" "F.Mask" "F.Paste")
		)
		(pad "A-59" smd rect
			(at 21.78647 4.62483)
			(size 1.54991 0.24994)
			(layers "F.Cu" "F.Mask" "F.Paste")
			(net "GND")
		)
		(pad "A-60" smd rect
			(at 25.83624 4.62483)
			(size 1.54991 0.24994)
			(layers "F.Cu" "F.Mask" "F.Paste")
			(net "GND")
		)
		(pad "A-61" smd rect
			(at 21.78647 5.1247)
			(size 1.54991 0.24994)
			(layers "F.Cu" "F.Mask" "F.Paste")
		)
		(pad "A-62" smd rect
			(at 25.83624 5.1247)
			(size 1.54991 0.24994)
			(layers "F.Cu" "F.Mask" "F.Paste")
		)
		(pad "A-63" smd rect
			(at 21.78647 5.62483)
			(size 1.54991 0.24994)
			(layers "F.Cu" "F.Mask" "F.Paste")
		)
		(pad "A-64" smd rect
			(at 25.83624 5.62483)
			(size 1.54991 0.24994)
			(layers "F.Cu" "F.Mask" "F.Paste")
		)
		(pad "A-65" smd rect
			(at 21.78647 6.1247)
			(size 1.54991 0.24994)
			(layers "F.Cu" "F.Mask" "F.Paste")
		)
		(pad "A-66" smd rect
			(at 25.83624 6.1247)
			(size 1.54991 0.24994)
			(layers "F.Cu" "F.Mask" "F.Paste")
		)
		(pad "A-67" smd rect
			(at 21.78647 6.62483)
			(size 1.54991 0.24994)
			(layers "F.Cu" "F.Mask" "F.Paste")
			(net "KEY2")
		)
		(pad "A-68" smd rect
			(at 25.83624 6.62483)
			(size 1.54991 0.24994)
			(layers "F.Cu" "F.Mask" "F.Paste")
		)
		(pad "A-69" smd rect
			(at 21.78647 7.1247)
			(size 1.54991 0.24994)
			(layers "F.Cu" "F.Mask" "F.Paste")
			(net "GND")
		)
		(pad "A-70" smd rect
			(at 25.83624 7.1247)
			(size 1.54991 0.24994)
			(layers "F.Cu" "F.Mask" "F.Paste")
			(net "GND")
		)
		(pad "A-71" smd rect
			(at 21.78647 7.62483)
			(size 1.54991 0.24994)
			(layers "F.Cu" "F.Mask" "F.Paste")
			(net "LED4")
		)
		(pad "A-72" smd rect
			(at 25.83624 7.62483)
			(size 1.54991 0.24994)
			(layers "F.Cu" "F.Mask" "F.Paste")
		)
		(pad "A-73" smd rect
			(at 21.78647 8.1247)
			(size 1.54991 0.24994)
			(layers "F.Cu" "F.Mask" "F.Paste")
			(net "LED3")
		)
		(pad "A-74" smd rect
			(at 25.83624 8.1247)
			(size 1.54991 0.24994)
			(layers "F.Cu" "F.Mask" "F.Paste")
		)
		(pad "A-75" smd rect
			(at 21.78647 8.62482)
			(size 1.54991 0.24994)
			(layers "F.Cu" "F.Mask" "F.Paste")
			(net "LED2")
		)
		(pad "A-76" smd rect
			(at 25.83624 8.62482)
			(size 1.54991 0.24994)
			(layers "F.Cu" "F.Mask" "F.Paste")
		)
		(pad "A-77" smd rect
			(at 21.78647 9.1247)
			(size 1.54991 0.24994)
			(layers "F.Cu" "F.Mask" "F.Paste")
			(net "LED1")
		)
		(pad "A-78" smd rect
			(at 25.83624 9.1247)
			(size 1.54991 0.24994)
			(layers "F.Cu" "F.Mask" "F.Paste")
		)
		(pad "A-79" smd rect
			(at 21.78647 9.62482)
			(size 1.54991 0.24994)
			(layers "F.Cu" "F.Mask" "F.Paste")
		)
		(pad "A-80" smd rect
			(at 25.83624 9.62482)
			(size 1.54991 0.24994)
			(layers "F.Cu" "F.Mask" "F.Paste")
		)
		(pad "A-81" smd rect
			(at 23.8 -11.3)
			(size 1.70002 1.35001)
			(layers "F.Cu" "F.Mask" "F.Paste")
		)
		(pad "A-82" thru_hole circle
			(at 23.81136 -10.1252)
			(size 0.55016 0.55016)
			(drill 0.55016)
			(layers "*.Cu" "*.Mask")
			(remove_unused_layers no)
			(thermal_bridge_angle 90)
		)
		(pad "A-83" thru_hole circle
			(at 23.81136 9.87476)
			(size 0.55016 0.55016)
			(drill 0.55016)
			(layers "*.Cu" "*.Mask")
			(remove_unused_layers no)
			(thermal_bridge_angle 90)
		)
		(pad "A-84" smd rect
			(at 23.8 11.05)
			(size 1.70002 1.35001)
			(layers "F.Cu" "F.Mask" "F.Paste")
		)
		(pad "B-1" smd rect
			(at -10.7014 -16.77035)
			(size 0.24994 1.54991)
			(layers "F.Cu" "F.Mask" "F.Paste")
		)
		(pad "B-2" smd rect
			(at -10.7014 -20.82013)
			(size 0.24994 1.54991)
			(layers "F.Cu" "F.Mask" "F.Paste")
		)
		(pad "B-3" smd rect
			(at -10.20128 -16.77035)
			(size 0.24994 1.54991)
			(layers "F.Cu" "F.Mask" "F.Paste")
		)
		(pad "B-4" smd rect
			(at -10.20128 -20.82013)
			(size 0.24994 1.54991)
			(layers "F.Cu" "F.Mask" "F.Paste")
		)
		(pad "B-5" smd rect
			(at -9.7014 -16.77035)
			(size 0.24994 1.54991)
			(layers "F.Cu" "F.Mask" "F.Paste")
		)
		(pad "B-6" smd rect
			(at -9.7014 -20.82013)
			(size 0.24994 1.54991)
			(layers "F.Cu" "F.Mask" "F.Paste")
		)
		(pad "B-7" smd rect
			(at -9.20128 -16.77035)
			(size 0.24994 1.54991)
			(layers "F.Cu" "F.Mask" "F.Paste")
		)
		(pad "B-8" smd rect
			(at -9.20128 -20.82013)
			(size 0.24994 1.54991)
			(layers "F.Cu" "F.Mask" "F.Paste")
			(net "MAC_USB_PWR")
		)
		(pad "B-9" smd rect
			(at -8.70141 -16.77035)
			(size 0.24994 1.54991)
			(layers "F.Cu" "F.Mask" "F.Paste")
			(net "GND")
		)
		(pad "B-10" smd rect
			(at -8.70141 -20.82013)
			(size 0.24994 1.54991)
			(layers "F.Cu" "F.Mask" "F.Paste")
			(net "GND")
		)
		(pad "B-11" smd rect
			(at -8.20128 -16.77035)
			(size 0.24994 1.54991)
			(layers "F.Cu" "F.Mask" "F.Paste")
			(net "MAC_RF_OUT")
		)
		(pad "B-12" smd rect
			(at -8.20128 -20.82013)
			(size 0.24994 1.54991)
			(layers "F.Cu" "F.Mask" "F.Paste")
		)
		(pad "B-13" smd rect
			(at -7.70141 -16.77035)
			(size 0.24994 1.54991)
			(layers "F.Cu" "F.Mask" "F.Paste")
			(net "MAC_RF_OUT")
		)
		(pad "B-14" smd rect
			(at -7.70141 -20.82013)
			(size 0.24994 1.54991)
			(layers "F.Cu" "F.Mask" "F.Paste")
		)
		(pad "B-15" smd rect
			(at -7.20128 -16.77035)
			(size 0.24994 1.54991)
			(layers "F.Cu" "F.Mask" "F.Paste")
		)
		(pad "B-16" smd rect
			(at -7.20128 -20.82013)
			(size 0.24994 1.54991)
			(layers "F.Cu" "F.Mask" "F.Paste")
		)
		(pad "B-17" smd rect
			(at -6.70141 -16.77035)
			(size 0.24994 1.54991)
			(layers "F.Cu" "F.Mask" "F.Paste")
		)
		(pad "B-18" smd rect
			(at -6.70141 -20.82013)
			(size 0.24994 1.54991)
			(layers "F.Cu" "F.Mask" "F.Paste")
		)
		(pad "B-19" smd rect
			(at -6.20128 -16.77035)
			(size 0.24994 1.54991)
			(layers "F.Cu" "F.Mask" "F.Paste")
			(net "GND")
		)
		(pad "B-20" smd rect
			(at -6.20128 -20.82013)
			(size 0.24994 1.54991)
			(layers "F.Cu" "F.Mask" "F.Paste")
			(net "GND")
		)
		(pad "B-21" smd rect
			(at -5.70141 -16.77035)
			(size 0.24994 1.54991)
			(layers "F.Cu" "F.Mask" "F.Paste")
			(net "ANT1")
		)
		(pad "B-22" smd rect
			(at -5.70141 -20.82013)
			(size 0.24994 1.54991)
			(layers "F.Cu" "F.Mask" "F.Paste")
		)
		(pad "B-23" smd rect
			(at -5.20129 -16.77035)
			(size 0.24994 1.54991)
			(layers "F.Cu" "F.Mask" "F.Paste")
			(net "ANT2")
		)
		(pad "B-24" smd rect
			(at -5.20129 -20.82013)
			(size 0.24994 1.54991)
			(layers "F.Cu" "F.Mask" "F.Paste")
		)
		(pad "B-25" smd rect
			(at -4.70141 -16.77035)
			(size 0.24994 1.54991)
			(layers "F.Cu" "F.Mask" "F.Paste")
			(net "ANT3")
		)
		(pad "B-26" smd rect
			(at -4.70141 -20.82013)
			(size 0.24994 1.54991)
			(layers "F.Cu" "F.Mask" "F.Paste")
			(net "MAC_TX")
		)
		(pad "B-27" smd rect
			(at -4.20129 -16.77035)
			(size 0.24994 1.54991)
			(layers "F.Cu" "F.Mask" "F.Paste")
			(net "ANT4")
		)
		(pad "B-28" smd rect
			(at -4.20129 -20.82013)
			(size 0.24994 1.54991)
			(layers "F.Cu" "F.Mask" "F.Paste")
			(net "MAC_RX")
		)
		(pad "B-29" smd rect
			(at -3.70142 -16.77035)
			(size 0.24994 1.54991)
			(layers "F.Cu" "F.Mask" "F.Paste")
			(net "GND")
		)
		(pad "B-30" smd rect
			(at -3.70142 -20.82013)
			(size 0.24994 1.54991)
			(layers "F.Cu" "F.Mask" "F.Paste")
			(net "GND")
		)
		(pad "B-31" smd rect
			(at -3.20129 -16.77035)
			(size 0.24994 1.54991)
			(layers "F.Cu" "F.Mask" "F.Paste")
		)
		(pad "B-32" smd rect
			(at -3.20129 -20.82013)
			(size 0.24994 1.54991)
			(layers "F.Cu" "F.Mask" "F.Paste")
		)
		(pad "B-33" smd rect
			(at -2.70142 -16.77035)
			(size 0.24994 1.54991)
			(layers "F.Cu" "F.Mask" "F.Paste")
			(net "MAC_FREQ_CTRL")
		)
		(pad "B-34" smd rect
			(at -2.70142 -20.82013)
			(size 0.24994 1.54991)
			(layers "F.Cu" "F.Mask" "F.Paste")
		)
		(pad "B-35" smd rect
			(at -2.20129 -16.77035)
			(size 0.24994 1.54991)
			(layers "F.Cu" "F.Mask" "F.Paste")
			(net "MAC_ALARM")
		)
		(pad "B-36" smd rect
			(at -2.20129 -20.82013)
			(size 0.24994 1.54991)
			(layers "F.Cu" "F.Mask" "F.Paste")
		)
		(pad "B-37" smd rect
			(at -1.70142 -16.77035)
			(size 0.24994 1.54991)
			(layers "F.Cu" "F.Mask" "F.Paste")
			(net "MAC_BITE")
		)
		(pad "B-38" smd rect
			(at -1.70142 -20.82013)
			(size 0.24994 1.54991)
			(layers "F.Cu" "F.Mask" "F.Paste")
		)
		(pad "B-39" smd rect
			(at -1.20129 -16.77035)
			(size 0.24994 1.54991)
			(layers "F.Cu" "F.Mask" "F.Paste")
			(net "GND")
		)
		(pad "B-40" smd rect
			(at -1.20129 -20.82013)
			(size 0.24994 1.54991)
			(layers "F.Cu" "F.Mask" "F.Paste")
			(net "GND")
		)
		(pad "B-41" smd rect
			(at -0.70142 -16.77035)
			(size 0.24994 1.54991)
			(layers "F.Cu" "F.Mask" "F.Paste")
		)
		(pad "B-42" smd rect
			(at -0.70142 -20.82013)
			(size 0.24994 1.54991)
			(layers "F.Cu" "F.Mask" "F.Paste")
		)
		(pad "B-43" smd rect
			(at -0.2013 -16.77035)
			(size 0.24994 1.54991)
			(layers "F.Cu" "F.Mask" "F.Paste")
			(net "FPGA_MAC_PPS_OUT-")
		)
		(pad "B-44" smd rect
			(at -0.2013 -20.82013)
			(size 0.24994 1.54991)
			(layers "F.Cu" "F.Mask" "F.Paste")
		)
		(pad "B-45" smd rect
			(at 0.29858 -16.77035)
			(size 0.24994 1.54991)
			(layers "F.Cu" "F.Mask" "F.Paste")
		)
		(pad "B-46" smd rect
			(at 0.29858 -20.82013)
			(size 0.24994 1.54991)
			(layers "F.Cu" "F.Mask" "F.Paste")
		)
		(pad "B-47" smd rect
			(at 0.7987 -16.77035)
			(size 0.24994 1.54991)
			(layers "F.Cu" "F.Mask" "F.Paste")
			(net "FPGA_MAC_PPS_IN0-")
		)
		(pad "B-48" smd rect
			(at 0.7987 -20.82013)
			(size 0.24994 1.54991)
			(layers "F.Cu" "F.Mask" "F.Paste")
		)
		(pad "B-49" smd rect
			(at 1.29857 -16.77035)
			(size 0.24994 1.54991)
			(layers "F.Cu" "F.Mask" "F.Paste")
			(net "GND")
		)
		(pad "B-50" smd rect
			(at 1.29857 -20.82013)
			(size 0.24994 1.54991)
			(layers "F.Cu" "F.Mask" "F.Paste")
			(net "GND")
		)
		(pad "B-51" smd rect
			(at 1.7987 -16.77035)
			(size 0.24994 1.54991)
			(layers "F.Cu" "F.Mask" "F.Paste")
		)
		(pad "B-52" smd rect
			(at 1.7987 -20.82013)
			(size 0.24994 1.54991)
			(layers "F.Cu" "F.Mask" "F.Paste")
		)
		(pad "B-53" smd rect
			(at 2.29857 -16.77035)
			(size 0.24994 1.54991)
			(layers "F.Cu" "F.Mask" "F.Paste")
			(net "FPGA_MAC_PPS_IN1-")
		)
		(pad "B-54" smd rect
			(at 2.29857 -20.82013)
			(size 0.24994 1.54991)
			(layers "F.Cu" "F.Mask" "F.Paste")
		)
		(pad "B-55" smd rect
			(at 2.7987 -16.77035)
			(size 0.24994 1.54991)
			(layers "F.Cu" "F.Mask" "F.Paste")
		)
		(pad "B-56" smd rect
			(at 2.7987 -20.82013)
			(size 0.24994 1.54991)
			(layers "F.Cu" "F.Mask" "F.Paste")
		)
		(pad "B-57" smd rect
			(at 3.29857 -16.77035)
			(size 0.24994 1.54991)
			(layers "F.Cu" "F.Mask" "F.Paste")
		)
		(pad "B-58" smd rect
			(at 3.29857 -20.82013)
			(size 0.24994 1.54991)
			(layers "F.Cu" "F.Mask" "F.Paste")
		)
		(pad "B-59" smd rect
			(at 3.7987 -16.77035)
			(size 0.24994 1.54991)
			(layers "F.Cu" "F.Mask" "F.Paste")
			(net "GND")
		)
		(pad "B-60" smd rect
			(at 3.7987 -20.82013)
			(size 0.24994 1.54991)
			(layers "F.Cu" "F.Mask" "F.Paste")
			(net "GND")
		)
		(pad "B-61" smd rect
			(at 4.29857 -16.77035)
			(size 0.24994 1.54991)
			(layers "F.Cu" "F.Mask" "F.Paste")
			(net "SDA")
		)
		(pad "B-62" smd rect
			(at 4.29857 -20.82013)
			(size 0.24994 1.54991)
			(layers "F.Cu" "F.Mask" "F.Paste")
		)
		(pad "B-63" smd rect
			(at 4.79869 -16.77035)
			(size 0.24994 1.54991)
			(layers "F.Cu" "F.Mask" "F.Paste")
		)
		(pad "B-64" smd rect
			(at 4.79869 -20.82013)
			(size 0.24994 1.54991)
			(layers "F.Cu" "F.Mask" "F.Paste")
		)
		(pad "B-65" smd rect
			(at 5.29857 -16.77035)
			(size 0.24994 1.54991)
			(layers "F.Cu" "F.Mask" "F.Paste")
		)
		(pad "B-66" smd rect
			(at 5.29857 -20.82013)
			(size 0.24994 1.54991)
			(layers "F.Cu" "F.Mask" "F.Paste")
		)
		(pad "B-67" smd rect
			(at 5.79869 -16.77035)
			(size 0.24994 1.54991)
			(layers "F.Cu" "F.Mask" "F.Paste")
			(net "SCL")
		)
		(pad "B-68" smd rect
			(at 5.79869 -20.82013)
			(size 0.24994 1.54991)
			(layers "F.Cu" "F.Mask" "F.Paste")
		)
		(pad "B-69" smd rect
			(at 6.29856 -16.77035)
			(size 0.24994 1.54991)
			(layers "F.Cu" "F.Mask" "F.Paste")
			(net "GND")
		)
		(pad "B-70" smd rect
			(at 6.29856 -20.82013)
			(size 0.24994 1.54991)
			(layers "F.Cu" "F.Mask" "F.Paste")
			(net "GND")
		)
		(pad "B-71" smd rect
			(at 6.79869 -16.77035)
			(size 0.24994 1.54991)
			(layers "F.Cu" "F.Mask" "F.Paste")
		)
		(pad "B-72" smd rect
			(at 6.79869 -20.82013)
			(size 0.24994 1.54991)
			(layers "F.Cu" "F.Mask" "F.Paste")
			(net "MAC_USB+")
		)
		(pad "B-73" smd rect
			(at 7.29856 -16.77035)
			(size 0.24994 1.54991)
			(layers "F.Cu" "F.Mask" "F.Paste")
		)
		(pad "B-74" smd rect
			(at 7.29856 -20.82013)
			(size 0.24994 1.54991)
			(layers "F.Cu" "F.Mask" "F.Paste")
			(net "MAC_USB-")
		)
		(pad "B-75" smd rect
			(at 7.79869 -16.77035)
			(size 0.24994 1.54991)
			(layers "F.Cu" "F.Mask" "F.Paste")
		)
		(pad "B-76" smd rect
			(at 7.79869 -20.82013)
			(size 0.24994 1.54991)
			(layers "F.Cu" "F.Mask" "F.Paste")
		)
		(pad "B-77" smd rect
			(at 8.29856 -16.77035)
			(size 0.24994 1.54991)
			(layers "F.Cu" "F.Mask" "F.Paste")
		)
		(pad "B-78" smd rect
			(at 8.29856 -20.82013)
			(size 0.24994 1.54991)
			(layers "F.Cu" "F.Mask" "F.Paste")
		)
		(pad "B-79" smd rect
			(at 8.79869 -16.77035)
			(size 0.24994 1.54991)
			(layers "F.Cu" "F.Mask" "F.Paste")
			(net "GPS1_RX")
		)
		(pad "B-80" smd rect
			(at 8.79869 -20.82013)
			(size 0.24994 1.54991)
			(layers "F.Cu" "F.Mask" "F.Paste")
			(net "GPS1_TX")
		)
		(pad "B-81" smd rect
			(at -12.125 -18.8)
			(size 1.35001 1.70002)
			(layers "F.Cu" "F.Mask" "F.Paste")
		)
		(pad "B-82" thru_hole circle
			(at -10.95134 -18.79524)
			(size 0.55016 0.55016)
			(drill 0.55016)
			(layers "*.Cu" "*.Mask")
			(remove_unused_layers no)
			(thermal_bridge_angle 90)
		)
		(pad "B-83" thru_hole circle
			(at 9.04862 -18.79524)
			(size 0.55016 0.55016)
			(drill 0.55016)
			(layers "*.Cu" "*.Mask")
			(remove_unused_layers no)
			(thermal_bridge_angle 90)
		)
		(pad "B-84" smd rect
			(at 10.225 -18.8)
			(size 1.35001 1.70002)
			(layers "F.Cu" "F.Mask" "F.Paste")
		)
		(pad "C-1" smd rect
			(at -21.78647 9.62381)
			(size 1.54991 0.24994)
			(layers "F.Cu" "F.Mask" "F.Paste")
		)
		(pad "C-2" smd rect
			(at -25.83625 9.62381)
			(size 1.54991 0.24994)
			(layers "F.Cu" "F.Mask" "F.Paste")
		)
		(pad "C-3" smd rect
			(at -21.78647 9.12368)
			(size 1.54991 0.24994)
			(layers "F.Cu" "F.Mask" "F.Paste")
		)
		(pad "C-4" smd rect
			(at -25.83625 9.12368)
			(size 1.54991 0.24994)
			(layers "F.Cu" "F.Mask" "F.Paste")
		)
		(pad "C-5" smd rect
			(at -21.78647 8.62381)
			(size 1.54991 0.24994)
			(layers "F.Cu" "F.Mask" "F.Paste")
		)
		(pad "C-6" smd rect
			(at -25.83625 8.62381)
			(size 1.54991 0.24994)
			(layers "F.Cu" "F.Mask" "F.Paste")
		)
		(pad "C-7" smd rect
			(at -21.78647 8.12368)
			(size 1.54991 0.24994)
			(layers "F.Cu" "F.Mask" "F.Paste")
		)
		(pad "C-8" smd rect
			(at -25.83625 8.12368)
			(size 1.54991 0.24994)
			(layers "F.Cu" "F.Mask" "F.Paste")
		)
		(pad "C-9" smd rect
			(at -21.78647 7.62381)
			(size 1.54991 0.24994)
			(layers "F.Cu" "F.Mask" "F.Paste")
			(net "GND")
		)
		(pad "C-10" smd rect
			(at -25.83625 7.62381)
			(size 1.54991 0.24994)
			(layers "F.Cu" "F.Mask" "F.Paste")
			(net "GND")
		)
		(pad "C-11" smd rect
			(at -21.78647 7.12368)
			(size 1.54991 0.24994)
			(layers "F.Cu" "F.Mask" "F.Paste")
		)
		(pad "C-12" smd rect
			(at -25.83625 7.12368)
			(size 1.54991 0.24994)
			(layers "F.Cu" "F.Mask" "F.Paste")
		)
		(pad "C-13" smd rect
			(at -21.78647 6.62381)
			(size 1.54991 0.24994)
			(layers "F.Cu" "F.Mask" "F.Paste")
		)
		(pad "C-14" smd rect
			(at -25.83625 6.62381)
			(size 1.54991 0.24994)
			(layers "F.Cu" "F.Mask" "F.Paste")
		)
		(pad "C-15" smd rect
			(at -21.78647 6.12369)
			(size 1.54991 0.24994)
			(layers "F.Cu" "F.Mask" "F.Paste")
		)
		(pad "C-16" smd rect
			(at -25.83625 6.12369)
			(size 1.54991 0.24994)
			(layers "F.Cu" "F.Mask" "F.Paste")
		)
		(pad "C-17" smd rect
			(at -21.78647 5.62381)
			(size 1.54991 0.24994)
			(layers "F.Cu" "F.Mask" "F.Paste")
		)
		(pad "C-18" smd rect
			(at -25.83625 5.62381)
			(size 1.54991 0.24994)
			(layers "F.Cu" "F.Mask" "F.Paste")
		)
		(pad "C-19" smd rect
			(at -21.78647 5.12369)
			(size 1.54991 0.24994)
			(layers "F.Cu" "F.Mask" "F.Paste")
			(net "GND")
		)
		(pad "C-20" smd rect
			(at -25.83625 5.12369)
			(size 1.54991 0.24994)
			(layers "F.Cu" "F.Mask" "F.Paste")
			(net "GND")
		)
		(pad "C-21" smd rect
			(at -21.78647 4.62382)
			(size 1.54991 0.24994)
			(layers "F.Cu" "F.Mask" "F.Paste")
			(net "PCIE_PERST")
		)
		(pad "C-22" smd rect
			(at -25.83625 4.62382)
			(size 1.54991 0.24994)
			(layers "F.Cu" "F.Mask" "F.Paste")
		)
		(pad "C-23" smd rect
			(at -21.78647 4.12369)
			(size 1.54991 0.24994)
			(layers "F.Cu" "F.Mask" "F.Paste")
			(net "KEY1")
		)
		(pad "C-24" smd rect
			(at -25.83625 4.12369)
			(size 1.54991 0.24994)
			(layers "F.Cu" "F.Mask" "F.Paste")
		)
		(pad "C-25" smd rect
			(at -21.78647 3.62382)
			(size 1.54991 0.24994)
			(layers "F.Cu" "F.Mask" "F.Paste")
		)
		(pad "C-26" smd rect
			(at -25.83625 3.62382)
			(size 1.54991 0.24994)
			(layers "F.Cu" "F.Mask" "F.Paste")
		)
		(pad "C-27" smd rect
			(at -21.78647 3.12369)
			(size 1.54991 0.24994)
			(layers "F.Cu" "F.Mask" "F.Paste")
		)
		(pad "C-28" smd rect
			(at -25.83625 3.12369)
			(size 1.54991 0.24994)
			(layers "F.Cu" "F.Mask" "F.Paste")
		)
		(pad "C-29" smd rect
			(at -21.78647 2.62382)
			(size 1.54991 0.24994)
			(layers "F.Cu" "F.Mask" "F.Paste")
			(net "GND")
		)
		(pad "C-30" smd rect
			(at -25.83625 2.62382)
			(size 1.54991 0.24994)
			(layers "F.Cu" "F.Mask" "F.Paste")
			(net "GND")
		)
		(pad "C-31" smd rect
			(at -21.78647 2.12369)
			(size 1.54991 0.24994)
			(layers "F.Cu" "F.Mask" "F.Paste")
		)
		(pad "C-32" smd rect
			(at -25.83625 2.12369)
			(size 1.54991 0.24994)
			(layers "F.Cu" "F.Mask" "F.Paste")
		)
		(pad "C-33" smd rect
			(at -21.78647 1.62382)
			(size 1.54991 0.24994)
			(layers "F.Cu" "F.Mask" "F.Paste")
		)
		(pad "C-34" smd rect
			(at -25.83625 1.62382)
			(size 1.54991 0.24994)
			(layers "F.Cu" "F.Mask" "F.Paste")
		)
		(pad "C-35" smd rect
			(at -21.78647 1.1237)
			(size 1.54991 0.24994)
			(layers "F.Cu" "F.Mask" "F.Paste")
		)
		(pad "C-36" smd rect
			(at -25.83625 1.1237)
			(size 1.54991 0.24994)
			(layers "F.Cu" "F.Mask" "F.Paste")
		)
		(pad "C-37" smd rect
			(at -21.78647 0.62382)
			(size 1.54991 0.24994)
			(layers "F.Cu" "F.Mask" "F.Paste")
		)
		(pad "C-38" smd rect
			(at -25.83625 0.62382)
			(size 1.54991 0.24994)
			(layers "F.Cu" "F.Mask" "F.Paste")
		)
		(pad "C-39" smd rect
			(at -21.78647 0.1237)
			(size 1.54991 0.24994)
			(layers "F.Cu" "F.Mask" "F.Paste")
			(net "GND")
		)
		(pad "C-40" smd rect
			(at -25.83625 0.1237)
			(size 1.54991 0.24994)
			(layers "F.Cu" "F.Mask" "F.Paste")
			(net "GND")
		)
		(pad "C-41" smd rect
			(at -21.78647 -0.37617)
			(size 1.54991 0.24994)
			(layers "F.Cu" "F.Mask" "F.Paste")
		)
		(pad "C-42" smd rect
			(at -25.83625 -0.37617)
			(size 1.54991 0.24994)
			(layers "F.Cu" "F.Mask" "F.Paste")
		)
		(pad "C-43" smd rect
			(at -21.78647 -0.8763)
			(size 1.54991 0.24994)
			(layers "F.Cu" "F.Mask" "F.Paste")
		)
		(pad "C-44" smd rect
			(at -25.83625 -0.8763)
			(size 1.54991 0.24994)
			(layers "F.Cu" "F.Mask" "F.Paste")
		)
		(pad "C-45" smd rect
			(at -21.78647 -1.37617)
			(size 1.54991 0.24994)
			(layers "F.Cu" "F.Mask" "F.Paste")
		)
		(pad "C-46" smd rect
			(at -25.83625 -1.37617)
			(size 1.54991 0.24994)
			(layers "F.Cu" "F.Mask" "F.Paste")
		)
		(pad "C-47" smd rect
			(at -21.78647 -1.8763)
			(size 1.54991 0.24994)
			(layers "F.Cu" "F.Mask" "F.Paste")
		)
		(pad "C-48" smd rect
			(at -25.83625 -1.8763)
			(size 1.54991 0.24994)
			(layers "F.Cu" "F.Mask" "F.Paste")
		)
		(pad "C-49" smd rect
			(at -21.78647 -2.37617)
			(size 1.54991 0.24994)
			(layers "F.Cu" "F.Mask" "F.Paste")
			(net "GND")
		)
		(pad "C-50" smd rect
			(at -25.83625 -2.37617)
			(size 1.54991 0.24994)
			(layers "F.Cu" "F.Mask" "F.Paste")
			(net "GND")
		)
		(pad "C-51" smd rect
			(at -21.78647 -2.8763)
			(size 1.54991 0.24994)
			(layers "F.Cu" "F.Mask" "F.Paste")
		)
		(pad "C-52" smd rect
			(at -25.83625 -2.8763)
			(size 1.54991 0.24994)
			(layers "F.Cu" "F.Mask" "F.Paste")
		)
		(pad "C-53" smd rect
			(at -21.78647 -3.37617)
			(size 1.54991 0.24994)
			(layers "F.Cu" "F.Mask" "F.Paste")
		)
		(pad "C-54" smd rect
			(at -25.83625 -3.37617)
			(size 1.54991 0.24994)
			(layers "F.Cu" "F.Mask" "F.Paste")
		)
		(pad "C-55" smd rect
			(at -21.78647 -3.87629)
			(size 1.54991 0.24994)
			(layers "F.Cu" "F.Mask" "F.Paste")
		)
		(pad "C-56" smd rect
			(at -25.83625 -3.87629)
			(size 1.54991 0.24994)
			(layers "F.Cu" "F.Mask" "F.Paste")
		)
		(pad "C-57" smd rect
			(at -21.78647 -4.37617)
			(size 1.54991 0.24994)
			(layers "F.Cu" "F.Mask" "F.Paste")
		)
		(pad "C-58" smd rect
			(at -25.83625 -4.37617)
			(size 1.54991 0.24994)
			(layers "F.Cu" "F.Mask" "F.Paste")
		)
		(pad "C-59" smd rect
			(at -21.78647 -4.87629)
			(size 1.54991 0.24994)
			(layers "F.Cu" "F.Mask" "F.Paste")
			(net "GND")
		)
		(pad "C-60" smd rect
			(at -25.83625 -4.87629)
			(size 1.54991 0.24994)
			(layers "F.Cu" "F.Mask" "F.Paste")
			(net "GND")
		)
		(pad "C-61" smd rect
			(at -21.78647 -5.37616)
			(size 1.54991 0.24994)
			(layers "F.Cu" "F.Mask" "F.Paste")
		)
		(pad "C-62" smd rect
			(at -25.83625 -5.37616)
			(size 1.54991 0.24994)
			(layers "F.Cu" "F.Mask" "F.Paste")
		)
		(pad "C-63" smd rect
			(at -21.78647 -5.87629)
			(size 1.54991 0.24994)
			(layers "F.Cu" "F.Mask" "F.Paste")
		)
		(pad "C-64" smd rect
			(at -25.83625 -5.87629)
			(size 1.54991 0.24994)
			(layers "F.Cu" "F.Mask" "F.Paste")
		)
		(pad "C-65" smd rect
			(at -21.78647 -6.37616)
			(size 1.54991 0.24994)
			(layers "F.Cu" "F.Mask" "F.Paste")
		)
		(pad "C-66" smd rect
			(at -25.83625 -6.37616)
			(size 1.54991 0.24994)
			(layers "F.Cu" "F.Mask" "F.Paste")
		)
		(pad "C-67" smd rect
			(at -21.78647 -6.87629)
			(size 1.54991 0.24994)
			(layers "F.Cu" "F.Mask" "F.Paste")
		)
		(pad "C-68" smd rect
			(at -25.83625 -6.87629)
			(size 1.54991 0.24994)
			(layers "F.Cu" "F.Mask" "F.Paste")
		)
		(pad "C-69" smd rect
			(at -21.78647 -7.37616)
			(size 1.54991 0.24994)
			(layers "F.Cu" "F.Mask" "F.Paste")
			(net "GND")
		)
		(pad "C-70" smd rect
			(at -25.83625 -7.37616)
			(size 1.54991 0.24994)
			(layers "F.Cu" "F.Mask" "F.Paste")
			(net "GND")
		)
		(pad "C-71" smd rect
			(at -21.78647 -7.87629)
			(size 1.54991 0.24994)
			(layers "F.Cu" "F.Mask" "F.Paste")
		)
		(pad "C-72" smd rect
			(at -25.83625 -7.87629)
			(size 1.54991 0.24994)
			(layers "F.Cu" "F.Mask" "F.Paste")
		)
		(pad "C-73" smd rect
			(at -21.78647 -8.37616)
			(size 1.54991 0.24994)
			(layers "F.Cu" "F.Mask" "F.Paste")
		)
		(pad "C-74" smd rect
			(at -25.83625 -8.37616)
			(size 1.54991 0.24994)
			(layers "F.Cu" "F.Mask" "F.Paste")
		)
		(pad "C-75" smd rect
			(at -21.78647 -8.87628)
			(size 1.54991 0.24994)
			(layers "F.Cu" "F.Mask" "F.Paste")
		)
		(pad "C-76" smd rect
			(at -25.83625 -8.87628)
			(size 1.54991 0.24994)
			(layers "F.Cu" "F.Mask" "F.Paste")
		)
		(pad "C-77" smd rect
			(at -21.78647 -9.37616)
			(size 1.54991 0.24994)
			(layers "F.Cu" "F.Mask" "F.Paste")
			(net "FPGA_TCK")
		)
		(pad "C-78" smd rect
			(at -25.83625 -9.37616)
			(size 1.54991 0.24994)
			(layers "F.Cu" "F.Mask" "F.Paste")
			(net "FPGA_TDI")
		)
		(pad "C-79" smd rect
			(at -21.78647 -9.87628)
			(size 1.54991 0.24994)
			(layers "F.Cu" "F.Mask" "F.Paste")
			(net "FPGA_TDO")
		)
		(pad "C-80" smd rect
			(at -25.83625 -9.87628)
			(size 1.54991 0.24994)
			(layers "F.Cu" "F.Mask" "F.Paste")
			(net "FPGA_TMS")
		)
		(pad "C-81" smd rect
			(at -23.8 11.05)
			(size 1.70002 1.35001)
			(layers "F.Cu" "F.Mask" "F.Paste")
		)
		(pad "C-82" thru_hole circle
			(at -23.81136 9.87374)
			(size 0.55016 0.55016)
			(drill 0.55016)
			(layers "*.Cu" "*.Mask")
			(remove_unused_layers no)
			(thermal_bridge_angle 90)
		)
		(pad "C-83" thru_hole circle
			(at -23.81136 -10.12622)
			(size 0.55016 0.55016)
			(drill 0.55016)
			(layers "*.Cu" "*.Mask")
			(remove_unused_layers no)
			(thermal_bridge_angle 90)
		)
		(pad "C-84" smd rect
			(at -23.8 -11.3)
			(size 1.70002 1.35001)
			(layers "F.Cu" "F.Mask" "F.Paste")
		)
		(pad "D-1" smd rect
			(at 8.79894 16.77035)
			(size 0.24994 1.54991)
			(layers "F.Cu" "F.Mask" "F.Paste")
		)
		(pad "D-2" smd rect
			(at 8.79894 20.82013)
			(size 0.24994 1.54991)
			(layers "F.Cu" "F.Mask" "F.Paste")
		)
		(pad "D-3" smd rect
			(at 8.29881 16.77035)
			(size 0.24994 1.54991)
			(layers "F.Cu" "F.Mask" "F.Paste")
		)
		(pad "D-4" smd rect
			(at 8.29881 20.82013)
			(size 0.24994 1.54991)
			(layers "F.Cu" "F.Mask" "F.Paste")
		)
		(pad "D-5" smd rect
			(at 7.79894 16.77035)
			(size 0.24994 1.54991)
			(layers "F.Cu" "F.Mask" "F.Paste")
		)
		(pad "D-6" smd rect
			(at 7.79894 20.82013)
			(size 0.24994 1.54991)
			(layers "F.Cu" "F.Mask" "F.Paste")
		)
		(pad "D-7" smd rect
			(at 7.29882 16.77035)
			(size 0.24994 1.54991)
			(layers "F.Cu" "F.Mask" "F.Paste")
		)
		(pad "D-8" smd rect
			(at 7.29882 20.82013)
			(size 0.24994 1.54991)
			(layers "F.Cu" "F.Mask" "F.Paste")
		)
		(pad "D-9" smd rect
			(at 6.79894 16.77035)
			(size 0.24994 1.54991)
			(layers "F.Cu" "F.Mask" "F.Paste")
			(net "GND")
		)
		(pad "D-10" smd rect
			(at 6.79894 20.82013)
			(size 0.24994 1.54991)
			(layers "F.Cu" "F.Mask" "F.Paste")
			(net "GND")
		)
		(pad "D-11" smd rect
			(at 6.29882 16.77035)
			(size 0.24994 1.54991)
			(layers "F.Cu" "F.Mask" "F.Paste")
		)
		(pad "D-12" smd rect
			(at 6.29882 20.82013)
			(size 0.24994 1.54991)
			(layers "F.Cu" "F.Mask" "F.Paste")
			(net "PCIE_TX2_P")
		)
		(pad "D-13" smd rect
			(at 5.79895 16.77035)
			(size 0.24994 1.54991)
			(layers "F.Cu" "F.Mask" "F.Paste")
		)
		(pad "D-14" smd rect
			(at 5.79895 20.82013)
			(size 0.24994 1.54991)
			(layers "F.Cu" "F.Mask" "F.Paste")
			(net "PCIE_TX2_N")
		)
		(pad "D-15" smd rect
			(at 5.29882 16.77035)
			(size 0.24994 1.54991)
			(layers "F.Cu" "F.Mask" "F.Paste")
			(net "GND")
		)
		(pad "D-16" smd rect
			(at 5.29882 20.82013)
			(size 0.24994 1.54991)
			(layers "F.Cu" "F.Mask" "F.Paste")
		)
		(pad "D-17" smd rect
			(at 4.79895 16.77035)
			(size 0.24994 1.54991)
			(layers "F.Cu" "F.Mask" "F.Paste")
			(net "PCIE_TX3_P")
		)
		(pad "D-18" smd rect
			(at 4.79895 20.82013)
			(size 0.24994 1.54991)
			(layers "F.Cu" "F.Mask" "F.Paste")
			(net "PCIE_RX2_P")
		)
		(pad "D-19" smd rect
			(at 4.29882 16.77035)
			(size 0.24994 1.54991)
			(layers "F.Cu" "F.Mask" "F.Paste")
			(net "PCIE_TX3_N")
		)
		(pad "D-20" smd rect
			(at 4.29882 20.82013)
			(size 0.24994 1.54991)
			(layers "F.Cu" "F.Mask" "F.Paste")
			(net "PCIE_RX2_N")
		)
		(pad "D-21" smd rect
			(at 3.79895 16.77035)
			(size 0.24994 1.54991)
			(layers "F.Cu" "F.Mask" "F.Paste")
			(net "GND")
		)
		(pad "D-22" smd rect
			(at 3.79895 20.82013)
			(size 0.24994 1.54991)
			(layers "F.Cu" "F.Mask" "F.Paste")
		)
		(pad "D-23" smd rect
			(at 3.29882 16.77035)
			(size 0.24994 1.54991)
			(layers "F.Cu" "F.Mask" "F.Paste")
			(net "PCIE_RX3_P")
		)
		(pad "D-24" smd rect
			(at 3.29882 20.82013)
			(size 0.24994 1.54991)
			(layers "F.Cu" "F.Mask" "F.Paste")
			(net "PCIE_TX1_P")
		)
		(pad "D-25" smd rect
			(at 2.79895 16.77035)
			(size 0.24994 1.54991)
			(layers "F.Cu" "F.Mask" "F.Paste")
			(net "PCIE_RX3_N")
		)
		(pad "D-26" smd rect
			(at 2.79895 20.82013)
			(size 0.24994 1.54991)
			(layers "F.Cu" "F.Mask" "F.Paste")
			(net "PCIE_TX1_N")
		)
		(pad "D-27" smd rect
			(at 2.29883 16.77035)
			(size 0.24994 1.54991)
			(layers "F.Cu" "F.Mask" "F.Paste")
			(net "GND")
		)
		(pad "D-28" smd rect
			(at 2.29883 20.82013)
			(size 0.24994 1.54991)
			(layers "F.Cu" "F.Mask" "F.Paste")
		)
		(pad "D-29" smd rect
			(at 1.79895 16.77035)
			(size 0.24994 1.54991)
			(layers "F.Cu" "F.Mask" "F.Paste")
			(net "PCIE_TX0_P")
		)
		(pad "D-30" smd rect
			(at 1.79895 20.82013)
			(size 0.24994 1.54991)
			(layers "F.Cu" "F.Mask" "F.Paste")
			(net "PCIE_RX1_P")
		)
		(pad "D-31" smd rect
			(at 1.29883 16.77035)
			(size 0.24994 1.54991)
			(layers "F.Cu" "F.Mask" "F.Paste")
			(net "PCIE_TX0_N")
		)
		(pad "D-32" smd rect
			(at 1.29883 20.82013)
			(size 0.24994 1.54991)
			(layers "F.Cu" "F.Mask" "F.Paste")
			(net "PCIE_RX1_N")
		)
		(pad "D-33" smd rect
			(at 0.79896 16.77035)
			(size 0.24994 1.54991)
			(layers "F.Cu" "F.Mask" "F.Paste")
			(net "GND")
		)
		(pad "D-34" smd rect
			(at 0.79896 20.82013)
			(size 0.24994 1.54991)
			(layers "F.Cu" "F.Mask" "F.Paste")
		)
		(pad "D-35" smd rect
			(at 0.29883 16.77035)
			(size 0.24994 1.54991)
			(layers "F.Cu" "F.Mask" "F.Paste")
			(net "PCIE_RX0_P")
		)
		(pad "D-36" smd rect
			(at 0.29883 20.82013)
			(size 0.24994 1.54991)
			(layers "F.Cu" "F.Mask" "F.Paste")
			(net "PCIE_CLK_P")
		)
		(pad "D-37" smd rect
			(at -0.20104 16.77035)
			(size 0.24994 1.54991)
			(layers "F.Cu" "F.Mask" "F.Paste")
			(net "PCIE_RX0_N")
		)
		(pad "D-38" smd rect
			(at -0.20104 20.82013)
			(size 0.24994 1.54991)
			(layers "F.Cu" "F.Mask" "F.Paste")
			(net "PCIE_CLK_N")
		)
		(pad "D-39" smd rect
			(at -0.70117 16.77035)
			(size 0.24994 1.54991)
			(layers "F.Cu" "F.Mask" "F.Paste")
			(net "GND")
		)
		(pad "D-40" smd rect
			(at -0.70117 20.82013)
			(size 0.24994 1.54991)
			(layers "F.Cu" "F.Mask" "F.Paste")
			(net "GND")
		)
		(pad "D-41" smd rect
			(at -1.20104 16.77035)
			(size 0.24994 1.54991)
			(layers "F.Cu" "F.Mask" "F.Paste")
		)
		(pad "D-42" smd rect
			(at -1.20104 20.82013)
			(size 0.24994 1.54991)
			(layers "F.Cu" "F.Mask" "F.Paste")
		)
		(pad "D-43" smd rect
			(at -1.70117 16.77035)
			(size 0.24994 1.54991)
			(layers "F.Cu" "F.Mask" "F.Paste")
		)
		(pad "D-44" smd rect
			(at -1.70117 20.82013)
			(size 0.24994 1.54991)
			(layers "F.Cu" "F.Mask" "F.Paste")
		)
		(pad "D-45" smd rect
			(at -2.20104 16.77035)
			(size 0.24994 1.54991)
			(layers "F.Cu" "F.Mask" "F.Paste")
		)
		(pad "D-46" smd rect
			(at -2.20104 20.82013)
			(size 0.24994 1.54991)
			(layers "F.Cu" "F.Mask" "F.Paste")
		)
		(pad "D-47" smd rect
			(at -2.70116 16.77035)
			(size 0.24994 1.54991)
			(layers "F.Cu" "F.Mask" "F.Paste")
		)
		(pad "D-48" smd rect
			(at -2.70116 20.82013)
			(size 0.24994 1.54991)
			(layers "F.Cu" "F.Mask" "F.Paste")
		)
		(pad "D-49" smd rect
			(at -3.20104 16.77035)
			(size 0.24994 1.54991)
			(layers "F.Cu" "F.Mask" "F.Paste")
			(net "GND")
		)
		(pad "D-50" smd rect
			(at -3.20104 20.82013)
			(size 0.24994 1.54991)
			(layers "F.Cu" "F.Mask" "F.Paste")
			(net "GND")
		)
		(pad "D-51" smd rect
			(at -3.70116 16.77035)
			(size 0.24994 1.54991)
			(layers "F.Cu" "F.Mask" "F.Paste")
		)
		(pad "D-52" smd rect
			(at -3.70116 20.82013)
			(size 0.24994 1.54991)
			(layers "F.Cu" "F.Mask" "F.Paste")
		)
		(pad "D-53" smd rect
			(at -4.20103 16.77035)
			(size 0.24994 1.54991)
			(layers "F.Cu" "F.Mask" "F.Paste")
		)
		(pad "D-54" smd rect
			(at -4.20103 20.82013)
			(size 0.24994 1.54991)
			(layers "F.Cu" "F.Mask" "F.Paste")
		)
		(pad "D-55" smd rect
			(at -4.70116 16.77035)
			(size 0.24994 1.54991)
			(layers "F.Cu" "F.Mask" "F.Paste")
		)
		(pad "D-56" smd rect
			(at -4.70116 20.82013)
			(size 0.24994 1.54991)
			(layers "F.Cu" "F.Mask" "F.Paste")
		)
		(pad "D-57" smd rect
			(at -5.20103 16.77035)
			(size 0.24994 1.54991)
			(layers "F.Cu" "F.Mask" "F.Paste")
		)
		(pad "D-58" smd rect
			(at -5.20103 20.82013)
			(size 0.24994 1.54991)
			(layers "F.Cu" "F.Mask" "F.Paste")
		)
		(pad "D-59" smd rect
			(at -5.70116 16.77035)
			(size 0.24994 1.54991)
			(layers "F.Cu" "F.Mask" "F.Paste")
			(net "GND")
		)
		(pad "D-60" smd rect
			(at -5.70116 20.82013)
			(size 0.24994 1.54991)
			(layers "F.Cu" "F.Mask" "F.Paste")
			(net "GND")
		)
		(pad "D-61" smd rect
			(at -6.20103 16.77035)
			(size 0.24994 1.54991)
			(layers "F.Cu" "F.Mask" "F.Paste")
		)
		(pad "D-62" smd rect
			(at -6.20103 20.82013)
			(size 0.24994 1.54991)
			(layers "F.Cu" "F.Mask" "F.Paste")
		)
		(pad "D-63" smd rect
			(at -6.70116 16.77035)
			(size 0.24994 1.54991)
			(layers "F.Cu" "F.Mask" "F.Paste")
		)
		(pad "D-64" smd rect
			(at -6.70116 20.82013)
			(size 0.24994 1.54991)
			(layers "F.Cu" "F.Mask" "F.Paste")
		)
		(pad "D-65" smd rect
			(at -7.20103 16.77035)
			(size 0.24994 1.54991)
			(layers "F.Cu" "F.Mask" "F.Paste")
		)
		(pad "D-66" smd rect
			(at -7.20103 20.82013)
			(size 0.24994 1.54991)
			(layers "F.Cu" "F.Mask" "F.Paste")
		)
		(pad "D-67" smd rect
			(at -7.70115 16.77035)
			(size 0.24994 1.54991)
			(layers "F.Cu" "F.Mask" "F.Paste")
		)
		(pad "D-68" smd rect
			(at -7.70115 20.82013)
			(size 0.24994 1.54991)
			(layers "F.Cu" "F.Mask" "F.Paste")
		)
		(pad "D-69" smd rect
			(at -8.20103 16.77035)
			(size 0.24994 1.54991)
			(layers "F.Cu" "F.Mask" "F.Paste")
			(net "GND")
		)
		(pad "D-70" smd rect
			(at -8.20103 20.82013)
			(size 0.24994 1.54991)
			(layers "F.Cu" "F.Mask" "F.Paste")
			(net "GND")
		)
		(pad "D-71" smd rect
			(at -8.70115 16.77035)
			(size 0.24994 1.54991)
			(layers "F.Cu" "F.Mask" "F.Paste")
		)
		(pad "D-72" smd rect
			(at -8.70115 20.82013)
			(size 0.24994 1.54991)
			(layers "F.Cu" "F.Mask" "F.Paste")
		)
		(pad "D-73" smd rect
			(at -9.20102 16.77035)
			(size 0.24994 1.54991)
			(layers "F.Cu" "F.Mask" "F.Paste")
		)
		(pad "D-74" smd rect
			(at -9.20102 20.82013)
			(size 0.24994 1.54991)
			(layers "F.Cu" "F.Mask" "F.Paste")
		)
		(pad "D-75" smd rect
			(at -9.70115 16.77035)
			(size 0.24994 1.54991)
			(layers "F.Cu" "F.Mask" "F.Paste")
		)
		(pad "D-76" smd rect
			(at -9.70115 20.82013)
			(size 0.24994 1.54991)
			(layers "F.Cu" "F.Mask" "F.Paste")
		)
		(pad "D-77" smd rect
			(at -10.20102 16.77035)
			(size 0.24994 1.54991)
			(layers "F.Cu" "F.Mask" "F.Paste")
		)
		(pad "D-78" smd rect
			(at -10.20102 20.82013)
			(size 0.24994 1.54991)
			(layers "F.Cu" "F.Mask" "F.Paste")
		)
		(pad "D-79" smd rect
			(at -10.70115 16.77035)
			(size 0.24994 1.54991)
			(layers "F.Cu" "F.Mask" "F.Paste")
		)
		(pad "D-80" smd rect
			(at -10.70115 20.82013)
			(size 0.24994 1.54991)
			(layers "F.Cu" "F.Mask" "F.Paste")
		)
		(pad "D-81" smd rect
			(at 10.225 18.8)
			(size 1.35001 1.70002)
			(layers "F.Cu" "F.Mask" "F.Paste")
		)
		(pad "D-82" thru_hole circle
			(at 9.04888 18.79524)
			(size 0.55016 0.55016)
			(drill 0.55016)
			(layers "*.Cu" "*.Mask")
			(remove_unused_layers no)
			(thermal_bridge_angle 90)
		)
		(pad "D-83" thru_hole circle
			(at -10.95108 18.79524)
			(size 0.55016 0.55016)
			(drill 0.55016)
			(layers "*.Cu" "*.Mask")
			(remove_unused_layers no)
			(thermal_bridge_angle 90)
		)
		(pad "D-84" smd rect
			(at -12.125 18.8)
			(size 1.35001 1.70002)
			(layers "F.Cu" "F.Mask" "F.Paste")
		)
		(pad "MNT-1" thru_hole rect
			(at -24.95156 -20.00834)
			(size 0 0)
			(drill 2.99999)
			(layers "*.Cu" "*.Mask")
			(remove_unused_layers no)
		)
		(pad "MNT-2" thru_hole rect
			(at 24.98484 -20.00834)
			(size 0 0)
			(drill 2.99999)
			(layers "*.Cu" "*.Mask")
			(remove_unused_layers no)
		)
		(pad "MNT-3" thru_hole rect
			(at 24.98484 19.86966)
			(size 0 0)
			(drill 2.99999)
			(layers "*.Cu" "*.Mask")
			(remove_unused_layers no)
		)
		(pad "MNT-4" thru_hole rect
			(at -24.92616 19.86966)
			(size 0 0)
			(drill 2.99999)
			(layers "*.Cu" "*.Mask")
			(remove_unused_layers no)
		)
	)
	(footprint "Vault:CAPC1608X87X45ML20T05"
		(layer "F.Cu")
		(at 151.488595 86.2786 -90)
		(property "Reference" "C31"
			(at 2.721395 -0.026921 90)
			(unlocked yes)
			(layer "F.SilkS")
			(effects
				(font
					(size 0.762 0.762)
					(thickness 0.2286)
				)
			)
		)
		(property "Value" "0.1uF"
			(at 2.09443 2.657602 270)
			(unlocked yes)
			(layer "F.SilkS")
			(hide yes)
			(effects
				(font
					(size 1.524 1.524)
					(thickness 0.254)
				)
			)
		)
		(sheetname "GPS_IMU_SENSORS")
		(sheetfile "GPS_IMU_SENSORS.kicad_sch")
		(duplicate_pad_numbers_are_jumpers no)
		(pad "1" smd rect
			(at -0.7 0)
			(size 1.1 1.05)
			(layers "F.Cu" "F.Mask" "F.Paste")
			(net "GND")
		)
		(pad "2" smd rect
			(at 0.7 0)
			(size 1.1 1.05)
			(layers "F.Cu" "F.Mask" "F.Paste")
			(net "+3.3V")
		)
	)
	(footprint "Vault:FP-318BQ-MFG"
		(layer "F.Cu")
		(at 86.238595 122.8286)
		(property "Reference" "U8"
			(at 1.478605 2.776921 360)
			(unlocked yes)
			(layer "F.SilkS")
			(effects
				(font
					(size 0.762 0.762)
					(thickness 0.2286)
				)
			)
		)
		(property "Value" "NC7SZ125M5"
			(at 5.03956 3.495802 0)
			(unlocked yes)
			(layer "F.SilkS")
			(hide yes)
			(effects
				(font
					(size 1.524 1.524)
					(thickness 0.254)
				)
			)
		)
		(sheetname "USER_IO")
		(sheetfile "USER_IO.kicad_sch")
		(duplicate_pad_numbers_are_jumpers no)
		(fp_line
			(start -0.325 -1.575)
			(end 0.325 -1.575)
			(stroke
				(width 0.2)
				(type solid)
			)
			(layer "F.SilkS")
		)
		(fp_line
			(start -0.325 1.575)
			(end 0.325 1.575)
			(stroke
				(width 0.2)
				(type solid)
			)
			(layer "F.SilkS")
		)
		(fp_line
			(start 0.825 0.225)
			(end 0.825 -0.225)
			(stroke
				(width 0.2)
				(type solid)
			)
			(layer "F.SilkS")
		)
		(fp_circle
			(center -2.45 -0.95)
			(end -2.45 -1.075)
			(stroke
				(width 0.25)
				(type solid)
			)
			(fill no)
			(layer "F.SilkS")
		)
		(fp_line
			(start -1.8 -1.825)
			(end 1.8 -1.825)
			(stroke
				(width 0.2)
				(type solid)
			)
			(layer "F.CrtYd")
		)
		(fp_line
			(start -1.8 1.825)
			(end -1.8 -1.825)
			(stroke
				(width 0.2)
				(type solid)
			)
			(layer "F.CrtYd")
		)
		(fp_line
			(start -1.8 1.825)
			(end 1.8 1.825)
			(stroke
				(width 0.2)
				(type solid)
			)
			(layer "F.CrtYd")
		)
		(fp_line
			(start 1.8 1.825)
			(end 1.8 -1.825)
			(stroke
				(width 0.2)
				(type solid)
			)
			(layer "F.CrtYd")
		)
		(fp_line
			(start -1.8 -1.825)
			(end 1.8 -1.825)
			(stroke
				(width 0.2)
				(type solid)
			)
			(layer "F.Fab")
		)
		(fp_line
			(start -1.8 1.825)
			(end -1.8 -1.825)
			(stroke
				(width 0.2)
				(type solid)
			)
			(layer "F.Fab")
		)
		(fp_line
			(start -1.8 1.825)
			(end 1.8 1.825)
			(stroke
				(width 0.2)
				(type solid)
			)
			(layer "F.Fab")
		)
		(fp_line
			(start -0.5 0)
			(end 0.5 0)
			(stroke
				(width 0.1)
				(type solid)
			)
			(layer "F.Fab")
		)
		(fp_line
			(start 0 0.5)
			(end 0 -0.5)
			(stroke
				(width 0.1)
				(type solid)
			)
			(layer "F.Fab")
		)
		(fp_line
			(start 1.8 1.825)
			(end 1.8 -1.825)
			(stroke
				(width 0.2)
				(type solid)
			)
			(layer "F.Fab")
		)
		(fp_text user "${REFERENCE}"
			(at 0 0.28494 360)
			(unlocked yes)
			(layer "F.Fab")
			(effects
				(font
					(face "Arial")
					(size 0.63 0.63)
					(thickness 0.1)
				)
				(justify left bottom)
			)
		)
		(pad "1" smd rect
			(at -1.2 -0.95)
			(size 1 0.7)
			(layers "F.Cu" "F.Mask" "F.Paste")
			(net "GND")
			(solder_mask_margin 0)
			(solder_paste_margin 0)
		)
		(pad "2" smd rect
			(at -1.2 0)
			(size 1 0.7)
			(layers "F.Cu" "F.Mask" "F.Paste")
			(net "NetR15_1")
			(solder_mask_margin 0)
			(solder_paste_margin 0)
		)
		(pad "3" smd rect
			(at -1.2 0.95)
			(size 1 0.7)
			(layers "F.Cu" "F.Mask" "F.Paste")
			(net "GND")
			(solder_mask_margin 0)
			(solder_paste_margin 0)
		)
		(pad "4" smd rect
			(at 1.2 0.95)
			(size 1 0.7)
			(layers "F.Cu" "F.Mask" "F.Paste")
			(net "ANT3")
			(solder_mask_margin 0)
			(solder_paste_margin 0)
		)
		(pad "5" smd rect
			(at 1.2 -0.95)
			(size 1 0.7)
			(layers "F.Cu" "F.Mask" "F.Paste")
			(net "+3.3V")
			(solder_mask_margin 0)
			(solder_paste_margin 0)
		)
	)
	(footprint "Vault:FP-318BQ-MFG"
		(layer "F.Cu")
		(at 86.488595 110.5786 180)
		(property "Reference" "U11"
			(at -1.228605 2.723079 0)
			(unlocked yes)
			(layer "F.SilkS")
			(effects
				(font
					(size 0.762 0.762)
					(thickness 0.2286)
				)
			)
		)
		(property "Value" "NC7SZ125M5"
			(at 5.03956 3.495792 180)
			(unlocked yes)
			(layer "F.SilkS")
			(hide yes)
			(effects
				(font
					(size 1.524 1.524)
					(thickness 0.254)
				)
			)
		)
		(sheetname "USER_IO")
		(sheetfile "USER_IO.kicad_sch")
		(duplicate_pad_numbers_are_jumpers no)
		(fp_line
			(start 0.825 -0.225)
			(end 0.825 0.225)
			(stroke
				(width 0.2)
				(type solid)
			)
			(layer "F.SilkS")
		)
		(fp_line
			(start 0.325 1.575)
			(end -0.325 1.575)
			(stroke
				(width 0.2)
				(type solid)
			)
			(layer "F.SilkS")
		)
		(fp_line
			(start 0.325 -1.575)
			(end -0.325 -1.575)
			(stroke
				(width 0.2)
				(type solid)
			)
			(layer "F.SilkS")
		)
		(fp_circle
			(center -2.45 -0.95)
			(end -2.45 -0.825)
			(stroke
				(width 0.25)
				(type solid)
			)
			(fill no)
			(layer "F.SilkS")
		)
		(fp_line
			(start 1.8 1.825)
			(end -1.8 1.825)
			(stroke
				(width 0.2)
				(type solid)
			)
			(layer "F.CrtYd")
		)
		(fp_line
			(start 1.8 -1.825)
			(end 1.8 1.825)
			(stroke
				(width 0.2)
				(type solid)
			)
			(layer "F.CrtYd")
		)
		(fp_line
			(start 1.8 -1.825)
			(end -1.8 -1.825)
			(stroke
				(width 0.2)
				(type solid)
			)
			(layer "F.CrtYd")
		)
		(fp_line
			(start -1.8 -1.825)
			(end -1.8 1.825)
			(stroke
				(width 0.2)
				(type solid)
			)
			(layer "F.CrtYd")
		)
		(fp_line
			(start 1.8 1.825)
			(end -1.8 1.825)
			(stroke
				(width 0.2)
				(type solid)
			)
			(layer "F.Fab")
		)
		(fp_line
			(start 1.8 -1.825)
			(end 1.8 1.825)
			(stroke
				(width 0.2)
				(type solid)
			)
			(layer "F.Fab")
		)
		(fp_line
			(start 1.8 -1.825)
			(end -1.8 -1.825)
			(stroke
				(width 0.2)
				(type solid)
			)
			(layer "F.Fab")
		)
		(fp_line
			(start 0.5 0)
			(end -0.5 0)
			(stroke
				(width 0.1)
				(type solid)
			)
			(layer "F.Fab")
		)
		(fp_line
			(start 0 -0.5)
			(end 0 0.5)
			(stroke
				(width 0.1)
				(type solid)
			)
			(layer "F.Fab")
		)
		(fp_line
			(start -1.8 -1.825)
			(end -1.8 1.825)
			(stroke
				(width 0.2)
				(type solid)
			)
			(layer "F.Fab")
		)
		(fp_text user "${REFERENCE}"
			(at 0 0.28494 180)
			(unlocked yes)
			(layer "F.Fab")
			(effects
				(font
					(face "Arial")
					(size 0.63 0.63)
					(thickness 0.1)
				)
				(justify left bottom)
			)
		)
		(pad "1" smd rect
			(at -1.2 -0.95 180)
			(size 1 0.7)
			(layers "F.Cu" "F.Mask" "F.Paste")
			(net "GND")
			(solder_mask_margin 0)
			(solder_paste_margin 0)
		)
		(pad "2" smd rect
			(at -1.2 0 180)
			(size 1 0.7)
			(layers "F.Cu" "F.Mask" "F.Paste")
			(net "ANT2")
			(solder_mask_margin 0)
			(solder_paste_margin 0)
		)
		(pad "3" smd rect
			(at -1.2 0.95 180)
			(size 1 0.7)
			(layers "F.Cu" "F.Mask" "F.Paste")
			(net "GND")
			(solder_mask_margin 0)
			(solder_paste_margin 0)
		)
		(pad "4" smd rect
			(at 1.2 0.95 180)
			(size 1 0.7)
			(layers "F.Cu" "F.Mask" "F.Paste")
			(net "NetR17_1")
			(solder_mask_margin 0)
			(solder_paste_margin 0)
		)
		(pad "5" smd rect
			(at 1.2 -0.95 180)
			(size 1 0.7)
			(layers "F.Cu" "F.Mask" "F.Paste")
			(net "+3.3V")
			(solder_mask_margin 0)
			(solder_paste_margin 0)
		)
	)
	(footprint "Vault:CAPC1608X87X45ML20T05"
		(layer "F.Cu")
		(at 219.588595 92.6786 180)
		(property "Reference" "C12"
			(at 4.2 0.106655 0)
			(unlocked yes)
			(layer "F.SilkS")
			(effects
				(font
					(size 0.762 0.762)
					(thickness 0.2286)
				)
				(justify left bottom)
			)
		)
		(property "Value" "0.1uF"
			(at -12.7889 -3.09499 0)
			(unlocked yes)
			(layer "F.SilkS")
			(hide yes)
			(effects
				(font
					(size 1.524 1.524)
					(thickness 0.254)
				)
				(justify left bottom)
			)
		)
		(sheetname "POWER")
		(sheetfile "POWER.kicad_sch")
		(duplicate_pad_numbers_are_jumpers no)
		(pad "1" smd rect
			(at -0.7 0 270)
			(size 1.1 1.05)
			(layers "F.Cu" "F.Mask" "F.Paste")
			(net "GND")
		)
		(pad "2" smd rect
			(at 0.7 0 270)
			(size 1.1 1.05)
			(layers "F.Cu" "F.Mask" "F.Paste")
			(net "+3.3V")
		)
	)
	(footprint "Vault:CAPC1608X87X45ML20T05"
		(layer "F.Cu")
		(at 86.488595 100.3286)
		(property "Reference" "C26"
			(at -2.8214 0.026921 0)
			(unlocked yes)
			(layer "F.SilkS")
			(effects
				(font
					(size 0.762 0.762)
					(thickness 0.2286)
				)
			)
		)
		(property "Value" "0.1uF"
			(at 2.09443 2.657602 0)
			(unlocked yes)
			(layer "F.SilkS")
			(hide yes)
			(effects
				(font
					(size 1.524 1.524)
					(thickness 0.254)
				)
			)
		)
		(sheetname "USER_IO")
		(sheetfile "USER_IO.kicad_sch")
		(duplicate_pad_numbers_are_jumpers no)
		(pad "1" smd rect
			(at -0.7 0 90)
			(size 1.1 1.05)
			(layers "F.Cu" "F.Mask" "F.Paste")
			(net "+3.3V")
		)
		(pad "2" smd rect
			(at 0.7 0 90)
			(size 1.1 1.05)
			(layers "F.Cu" "F.Mask" "F.Paste")
			(net "GND")
		)
	)
	(footprint "Vault:RESC1609X50X30NL10T20"
		(layer "F.Cu")
		(at 174.238595 87.5786 -90)
		(property "Reference" "R12"
			(at 2.2714 -0.026931 90)
			(unlocked yes)
			(layer "F.SilkS")
			(effects
				(font
					(size 0.762 0.762)
					(thickness 0.2286)
				)
			)
		)
		(property "Value" "110R"
			(at -2.911592 2.27248 180)
			(unlocked yes)
			(layer "F.SilkS")
			(hide yes)
			(effects
				(font
					(size 1.524 1.524)
					(thickness 0.254)
				)
			)
		)
		(sheetname "MAC")
		(sheetfile "MAC.kicad_sch")
		(duplicate_pad_numbers_are_jumpers no)
		(pad "1" smd rect
			(at -0.625 0)
			(size 0.95 0.8)
			(layers "F.Cu" "F.Mask" "F.Paste")
			(net "MAC_PPS_OUT-")
		)
		(pad "2" smd rect
			(at 0.625 0)
			(size 0.95 0.8)
			(layers "F.Cu" "F.Mask" "F.Paste")
			(net "MAC_PPS_OUT+")
		)
	)
	(footprint "Connectors:AMPHENOL-901-143-6RFX"
		(layer "F.Cu")
		(at 63.564595 110.8946 180)
		(property "Reference" "AN2"
			(at 4.076 -6.277345 0)
			(unlocked yes)
			(layer "F.SilkS")
			(effects
				(font
					(size 0.762 0.762)
					(thickness 0.2286)
				)
				(justify left bottom)
			)
		)
		(property "Value" "901-143-6RFX"
			(at 4.6101 -2.05359 0)
			(unlocked yes)
			(layer "F.SilkS")
			(hide yes)
			(effects
				(font
					(size 1.524 1.524)
					(thickness 0.254)
				)
				(justify left bottom)
			)
		)
		(sheetname "USER_IO")
		(sheetfile "USER_IO.kicad_sch")
		(duplicate_pad_numbers_are_jumpers no)
		(fp_line
			(start 4.318 3.556)
			(end 3.302 4.572)
			(stroke
				(width 0.1778)
				(type solid)
			)
			(layer "F.SilkS")
		)
		(fp_line
			(start 4.318 -3.556)
			(end 3.302 -4.572)
			(stroke
				(width 0.1778)
				(type solid)
			)
			(layer "F.SilkS")
		)
		(fp_line
			(start 3.302 4.572)
			(end 2.54 4.572)
			(stroke
				(width 0.1778)
				(type solid)
			)
			(layer "F.SilkS")
		)
		(fp_line
			(start 3.302 -4.572)
			(end 2.54 -4.572)
			(stroke
				(width 0.1778)
				(type solid)
			)
			(layer "F.SilkS")
		)
		(fp_line
			(start 2.54 4.572)
			(end -4.572 4.572)
			(stroke
				(width 0.1778)
				(type solid)
			)
			(layer "F.SilkS")
		)
		(fp_line
			(start 2.54 -4.572)
			(end -4.572 -4.572)
			(stroke
				(width 0.1778)
				(type solid)
			)
			(layer "F.SilkS")
		)
		(fp_line
			(start -4.572 2.54)
			(end -4.572 4.572)
			(stroke
				(width 0.1778)
				(type solid)
			)
			(layer "F.SilkS")
		)
		(fp_line
			(start -4.572 -4.572)
			(end -4.572 -2.54)
			(stroke
				(width 0.1778)
				(type solid)
			)
			(layer "F.SilkS")
		)
		(pad "1" thru_hole circle
			(at 0 0 180)
			(size 2.8448 2.8448)
			(drill 1.524)
			(layers "*.Cu" "*.Mask")
			(remove_unused_layers no)
			(net "NetAN2_1")
			(thermal_bridge_angle 90)
		)
		(pad "2" thru_hole circle
			(at -2.54 2.54 180)
			(size 3.048 3.048)
			(drill 1.7272)
			(layers "*.Cu" "*.Mask")
			(remove_unused_layers no)
			(net "GND")
			(thermal_bridge_angle 90)
		)
		(pad "3" thru_hole circle
			(at -2.54 -2.54 180)
			(size 3.048 3.048)
			(drill 1.7272)
			(layers "*.Cu" "*.Mask")
			(remove_unused_layers no)
			(net "GND")
			(thermal_bridge_angle 90)
		)
		(pad "4" thru_hole circle
			(at 2.54 -2.54 180)
			(size 3.048 3.048)
			(drill 1.7272)
			(layers "*.Cu" "*.Mask")
			(remove_unused_layers no)
			(net "GND")
			(thermal_bridge_angle 90)
		)
		(pad "5" thru_hole circle
			(at 2.54 2.54 180)
			(size 3.048 3.048)
			(drill 1.7272)
			(layers "*.Cu" "*.Mask")
			(remove_unused_layers no)
			(net "GND")
			(thermal_bridge_angle 90)
		)
	)
	(footprint "Vault:RESC1608X55X30NL15T15"
		(layer "F.Cu")
		(at 74.788595 56.9786 90)
		(property "Reference" "R16"
			(at 0.1286 -1.673069 90)
			(unlocked yes)
			(layer "F.SilkS")
			(effects
				(font
					(size 0.762 0.762)
					(thickness 0.2286)
				)
			)
		)
		(property "Value" "200 OHM"
			(at -2.085402 4.85075 0)
			(unlocked yes)
			(layer "F.SilkS")
			(hide yes)
			(effects
				(font
					(size 1.524 1.524)
					(thickness 0.254)
				)
			)
		)
		(sheetname "USER_IO")
		(sheetfile "USER_IO.kicad_sch")
		(duplicate_pad_numbers_are_jumpers no)
		(pad "1" smd rect
			(at -0.675 0 180)
			(size 0.95 0.8)
			(layers "F.Cu" "F.Mask" "F.Paste")
			(net "LED1")
		)
		(pad "2" smd rect
			(at 0.675 0 180)
			(size 0.95 0.8)
			(layers "F.Cu" "F.Mask" "F.Paste")
			(net "NetD11_1")
		)
	)
	(footprint "Capacitors:CAPC2012X14N"
		(layer "F.Cu")
		(at 219.393595 106.0686 -90)
		(property "Reference" "C5"
			(at 3.41 -0.488345 90)
			(unlocked yes)
			(layer "F.SilkS")
			(effects
				(font
					(size 0.762 0.762)
					(thickness 0.2286)
				)
				(justify left bottom)
			)
		)
		(property "Value" "CAP_0805_10UF_25V"
			(at -19.07921 -10.6045 0)
			(unlocked yes)
			(layer "F.SilkS")
			(hide yes)
			(effects
				(font
					(size 1.524 1.524)
					(thickness 0.254)
				)
				(justify left bottom)
			)
		)
		(sheetname "POWER")
		(sheetfile "POWER.kicad_sch")
		(duplicate_pad_numbers_are_jumpers no)
		(fp_line
			(start 0.762 0.9652)
			(end -0.762 0.9652)
			(stroke
				(width 0.1524)
				(type solid)
			)
			(layer "F.SilkS")
		)
		(fp_line
			(start 0.762 -0.9652)
			(end -0.762 -0.9652)
			(stroke
				(width 0.1524)
				(type solid)
			)
			(layer "F.SilkS")
		)
		(pad "1" smd rect
			(at -0.9 0)
			(size 1.45 1.15)
			(layers "F.Cu" "F.Mask" "F.Paste")
			(net "+12V")
		)
		(pad "2" smd rect
			(at 0.9 0)
			(size 1.45 1.15)
			(layers "F.Cu" "F.Mask" "F.Paste")
			(net "GND")
		)
	)
	(footprint "Vault:TECO-1909763-1_V"
		(layer "F.Cu")
		(at 71.838595 124.1786 90)
		(property "Reference" "J9"
			(at -1.421395 2.926921 90)
			(unlocked yes)
			(layer "F.SilkS")
			(effects
				(font
					(size 0.762 0.762)
					(thickness 0.2286)
				)
			)
		)
		(property "Value" "1909763-1"
			(at 4.608085 3.749802 90)
			(unlocked yes)
			(layer "F.SilkS")
			(hide yes)
			(effects
				(font
					(size 1.524 1.524)
					(thickness 0.254)
				)
			)
		)
		(sheetname "USER_IO")
		(sheetfile "USER_IO.kicad_sch")
		(duplicate_pad_numbers_are_jumpers no)
		(fp_line
			(start -0.55 -1.3)
			(end 0.55 -1.3)
			(stroke
				(width 0.2)
				(type solid)
			)
			(layer "F.SilkS")
		)
		(fp_circle
			(center -1.778 1.65)
			(end -1.653 1.65)
			(stroke
				(width 0.25)
				(type solid)
			)
			(fill no)
			(layer "F.SilkS")
		)
		(pad "1" smd rect
			(at -1.475 0 90)
			(size 1.05 2.2)
			(layers "F.Cu" "F.Mask" "F.Paste")
			(net "GND")
		)
		(pad "2" smd rect
			(at 0 1.525 90)
			(size 1 1.05)
			(layers "F.Cu" "F.Mask" "F.Paste")
			(net "NetAN3_1")
		)
		(pad "3" smd rect
			(at 1.475 0 90)
			(size 1.05 2.2)
			(layers "F.Cu" "F.Mask" "F.Paste")
			(net "GND")
		)
	)
	(footprint "Vault:M08A_L"
		(layer "F.Cu")
		(at 178.988595 88.8286)
		(property "Reference" "U4"
			(at 1.478605 -3.473069 0)
			(unlocked yes)
			(layer "F.SilkS")
			(effects
				(font
					(size 0.762 0.762)
					(thickness 0.2286)
				)
			)
		)
		(property "Value" "DS90LV028AQMA"
			(at 6.74058 4.207002 0)
			(unlocked yes)
			(layer "F.SilkS")
			(hide yes)
			(effects
				(font
					(size 1.524 1.524)
					(thickness 0.254)
				)
			)
		)
		(sheetname "MAC")
		(sheetfile "MAC.kicad_sch")
		(duplicate_pad_numbers_are_jumpers no)
		(fp_line
			(start -1 -2.5)
			(end 1 -2.5)
			(stroke
				(width 0.2)
				(type solid)
			)
			(layer "F.SilkS")
		)
		(fp_line
			(start -1 2.5)
			(end -1 -2.5)
			(stroke
				(width 0.2)
				(type solid)
			)
			(layer "F.SilkS")
		)
		(fp_line
			(start -1 2.5)
			(end 1 2.5)
			(stroke
				(width 0.2)
				(type solid)
			)
			(layer "F.SilkS")
		)
		(fp_line
			(start 1 2.5)
			(end 1 -2.5)
			(stroke
				(width 0.2)
				(type solid)
			)
			(layer "F.SilkS")
		)
		(fp_circle
			(center -2.35 -2.755)
			(end -2.35 -2.88)
			(stroke
				(width 0.25)
				(type solid)
			)
			(fill no)
			(layer "F.SilkS")
		)
		(fp_circle
			(center -0.2 -1.7)
			(end -0.2 -1.9)
			(stroke
				(width 0.4)
				(type solid)
			)
			(fill no)
			(layer "F.SilkS")
		)
		(pad "1" smd oval
			(at -2.35 -1.905 90)
			(size 0.6 1.9)
			(layers "F.Cu" "F.Mask" "F.Paste")
			(net "MAC_PPS_OUT-")
		)
		(pad "2" smd oval
			(at -2.35 -0.635 90)
			(size 0.6 1.9)
			(layers "F.Cu" "F.Mask" "F.Paste")
			(net "MAC_PPS_OUT+")
		)
		(pad "3" smd oval
			(at -2.35 0.635 90)
			(size 0.6 1.9)
			(layers "F.Cu" "F.Mask" "F.Paste")
		)
		(pad "4" smd oval
			(at -2.35 1.905 90)
			(size 0.6 1.9)
			(layers "F.Cu" "F.Mask" "F.Paste")
		)
		(pad "5" smd oval
			(at 2.35 1.905 90)
			(size 0.6 1.9)
			(layers "F.Cu" "F.Mask" "F.Paste")
			(net "GND")
		)
		(pad "6" smd oval
			(at 2.35 0.635 90)
			(size 0.6 1.9)
			(layers "F.Cu" "F.Mask" "F.Paste")
		)
		(pad "7" smd oval
			(at 2.35 -0.635 90)
			(size 0.6 1.9)
			(layers "F.Cu" "F.Mask" "F.Paste")
			(net "NetR13_1")
		)
		(pad "8" smd oval
			(at 2.35 -1.905 90)
			(size 0.6 1.9)
			(layers "F.Cu" "F.Mask" "F.Paste")
			(net "+3.3V")
		)
	)
	(footprint "Passives:DIOM1608X06N"
		(layer "F.Cu")
		(at 85.112255 53.2366 90)
		(property "Reference" "D13"
			(at -1.55529 -1.375795 90)
			(unlocked yes)
			(layer "F.SilkS")
			(effects
				(font
					(size 0.762 0.762)
					(thickness 0.2286)
				)
				(justify left bottom)
			)
		)
		(property "Value" "RED"
			(at -4.13639 -0.5715 0)
			(unlocked yes)
			(layer "F.SilkS")
			(hide yes)
			(effects
				(font
					(size 1.524 1.524)
					(thickness 0.254)
				)
				(justify left bottom)
			)
		)
		(sheetname "USER_IO")
		(sheetfile "USER_IO.kicad_sch")
		(duplicate_pad_numbers_are_jumpers no)
		(fp_circle
			(center -1.275 -0.725)
			(end -1.225 -0.725)
			(stroke
				(width 0.1)
				(type solid)
			)
			(fill no)
			(layer "F.SilkS")
		)
		(pad "1" smd rect
			(at -0.725 0 180)
			(size 0.85 1)
			(layers "F.Cu" "F.Mask" "F.Paste")
			(net "NetD13_1")
		)
		(pad "2" smd rect
			(at 0.725 0 180)
			(size 0.85 1)
			(layers "F.Cu" "F.Mask" "F.Paste")
			(net "+3.3V")
		)
	)
	(footprint "Resistors:RESC1608X50N"
		(layer "F.Cu")
		(at 216.853595 105.8146 -90)
		(property "Reference" "R3"
			(at 2.864 -0.428345 90)
			(unlocked yes)
			(layer "F.SilkS")
			(effects
				(font
					(size 0.762 0.762)
					(thickness 0.2286)
				)
				(justify left bottom)
			)
		)
		(property "Value" "ERJ-3EKF4702V"
			(at -18.92681 -16.2687 0)
			(unlocked yes)
			(layer "F.SilkS")
			(hide yes)
			(effects
				(font
					(size 1.524 1.524)
					(thickness 0.254)
				)
				(justify left bottom)
			)
		)
		(sheetname "POWER")
		(sheetfile "POWER.kicad_sch")
		(duplicate_pad_numbers_are_jumpers no)
		(fp_line
			(start 0 0.5)
			(end 0 -0.5)
			(stroke
				(width 0.1524)
				(type solid)
			)
			(layer "F.SilkS")
		)
		(pad "1" smd rect
			(at -0.69 0)
			(size 1 0.72)
			(layers "F.Cu" "F.Mask" "F.Paste")
			(net "NetR3_1")
		)
		(pad "2" smd rect
			(at 0.69 0)
			(size 1 0.72)
			(layers "F.Cu" "F.Mask" "F.Paste")
			(net "+12V")
		)
	)
	(footprint "Connectors:AMPHENOL-901-143-6RFX"
		(layer "F.Cu")
		(at 63.564595 97.5596 180)
		(property "Reference" "AN1"
			(at 4.076 -6.362345 0)
			(unlocked yes)
			(layer "F.SilkS")
			(effects
				(font
					(size 0.762 0.762)
					(thickness 0.2286)
				)
				(justify left bottom)
			)
		)
		(property "Value" "901-143-6RFX"
			(at 4.6101 -12.21359 0)
			(unlocked yes)
			(layer "F.SilkS")
			(hide yes)
			(effects
				(font
					(size 1.524 1.524)
					(thickness 0.254)
				)
				(justify left bottom)
			)
		)
		(sheetname "USER_IO")
		(sheetfile "USER_IO.kicad_sch")
		(duplicate_pad_numbers_are_jumpers no)
		(fp_line
			(start 4.318 3.556)
			(end 3.302 4.572)
			(stroke
				(width 0.1778)
				(type solid)
			)
			(layer "F.SilkS")
		)
		(fp_line
			(start 4.318 -3.556)
			(end 3.302 -4.572)
			(stroke
				(width 0.1778)
				(type solid)
			)
			(layer "F.SilkS")
		)
		(fp_line
			(start 3.302 4.572)
			(end 2.54 4.572)
			(stroke
				(width 0.1778)
				(type solid)
			)
			(layer "F.SilkS")
		)
		(fp_line
			(start 3.302 -4.572)
			(end 2.54 -4.572)
			(stroke
				(width 0.1778)
				(type solid)
			)
			(layer "F.SilkS")
		)
		(fp_line
			(start 2.54 4.572)
			(end -4.572 4.572)
			(stroke
				(width 0.1778)
				(type solid)
			)
			(layer "F.SilkS")
		)
		(fp_line
			(start 2.54 -4.572)
			(end -4.572 -4.572)
			(stroke
				(width 0.1778)
				(type solid)
			)
			(layer "F.SilkS")
		)
		(fp_line
			(start -4.572 2.54)
			(end -4.572 4.572)
			(stroke
				(width 0.1778)
				(type solid)
			)
			(layer "F.SilkS")
		)
		(fp_line
			(start -4.572 -4.572)
			(end -4.572 -2.54)
			(stroke
				(width 0.1778)
				(type solid)
			)
			(layer "F.SilkS")
		)
		(pad "1" thru_hole circle
			(at 0 0 180)
			(size 2.8448 2.8448)
			(drill 1.524)
			(layers "*.Cu" "*.Mask")
			(remove_unused_layers no)
			(net "NetAN1_1")
			(thermal_bridge_angle 90)
		)
		(pad "2" thru_hole circle
			(at -2.54 2.54 180)
			(size 3.048 3.048)
			(drill 1.7272)
			(layers "*.Cu" "*.Mask")
			(remove_unused_layers no)
			(net "GND")
			(thermal_bridge_angle 90)
		)
		(pad "3" thru_hole circle
			(at -2.54 -2.54 180)
			(size 3.048 3.048)
			(drill 1.7272)
			(layers "*.Cu" "*.Mask")
			(remove_unused_layers no)
			(net "GND")
			(thermal_bridge_angle 90)
		)
		(pad "4" thru_hole circle
			(at 2.54 -2.54 180)
			(size 3.048 3.048)
			(drill 1.7272)
			(layers "*.Cu" "*.Mask")
			(remove_unused_layers no)
			(net "GND")
			(thermal_bridge_angle 90)
		)
		(pad "5" thru_hole circle
			(at 2.54 2.54 180)
			(size 3.048 3.048)
			(drill 1.7272)
			(layers "*.Cu" "*.Mask")
			(remove_unused_layers no)
			(net "GND")
			(thermal_bridge_angle 90)
		)
	)
	(footprint "Vault:CAPC1608X87X45ML20T05"
		(layer "F.Cu")
		(at 227.648595 118.1336)
		(property "Reference" "C16"
			(at 1.74 0.638345 0)
			(unlocked yes)
			(layer "F.SilkS")
			(effects
				(font
					(size 0.762 0.762)
					(thickness 0.2286)
				)
				(justify left bottom)
			)
		)
		(property "Value" "0.1uF"
			(at 0.3429 7.15899 0)
			(unlocked yes)
			(layer "F.SilkS")
			(hide yes)
			(effects
				(font
					(size 1.524 1.524)
					(thickness 0.254)
				)
				(justify left bottom)
			)
		)
		(sheetname "POWER")
		(sheetfile "POWER.kicad_sch")
		(duplicate_pad_numbers_are_jumpers no)
		(pad "1" smd rect
			(at -0.7 0 90)
			(size 1.1 1.05)
			(layers "F.Cu" "F.Mask" "F.Paste")
			(net "GND")
		)
		(pad "2" smd rect
			(at 0.7 0 90)
			(size 1.1 1.05)
			(layers "F.Cu" "F.Mask" "F.Paste")
			(net "+5.0V")
		)
	)
	(footprint "Resistors:RESC1608X50N"
		(layer "F.Cu")
		(at 214.008795 98.0676 90)
		(property "Reference" "R5"
			(at 1.639 0.398145 90)
			(unlocked yes)
			(layer "F.SilkS")
			(effects
				(font
					(size 0.762 0.762)
					(thickness 0.2286)
				)
				(justify left bottom)
			)
		)
		(property "Value" "ERJ-3EKF2612V"
			(at -3.17119 -1.0033 0)
			(unlocked yes)
			(layer "F.SilkS")
			(hide yes)
			(effects
				(font
					(size 1.524 1.524)
					(thickness 0.254)
				)
				(justify left bottom)
			)
		)
		(sheetname "POWER")
		(sheetfile "POWER.kicad_sch")
		(duplicate_pad_numbers_are_jumpers no)
		(fp_line
			(start 0 -0.5)
			(end 0 0.5)
			(stroke
				(width 0.1524)
				(type solid)
			)
			(layer "F.SilkS")
		)
		(pad "1" smd rect
			(at -0.69 0 180)
			(size 1 0.72)
			(layers "F.Cu" "F.Mask" "F.Paste")
			(net "NetR5_1")
		)
		(pad "2" smd rect
			(at 0.69 0 180)
			(size 1 0.72)
			(layers "F.Cu" "F.Mask" "F.Paste")
			(net "+3.3V")
		)
	)
	(footprint "Resistors:RESC2012X50N"
		(layer "F.Cu")
		(at 99.488595 65.3286 90)
		(property "Reference" "R18"
			(at -1.25 -3.906655 90)
			(unlocked yes)
			(layer "F.SilkS")
			(effects
				(font
					(size 0.762 0.762)
					(thickness 0.2286)
				)
				(justify left bottom)
			)
		)
		(property "Value" "CRCW080533R0FKEA"
			(at -3.52679 -1.5875 0)
			(unlocked yes)
			(layer "F.SilkS")
			(hide yes)
			(effects
				(font
					(size 1.524 1.524)
					(thickness 0.254)
				)
				(justify left bottom)
			)
		)
		(sheetname "PCIe_JTAG")
		(sheetfile "PCIe_JTAG.kicad_sch")
		(duplicate_pad_numbers_are_jumpers no)
		(fp_line
			(start 0 -0.762)
			(end 0 0.762)
			(stroke
				(width 0.1524)
				(type solid)
			)
			(layer "F.SilkS")
		)
		(pad "1" smd rect
			(at -1 0 180)
			(size 1.45 0.95)
			(layers "F.Cu" "F.Mask" "F.Paste")
			(net "FPGA_TCK")
		)
		(pad "2" smd rect
			(at 1 0 180)
			(size 1.45 0.95)
			(layers "F.Cu" "F.Mask" "F.Paste")
			(net "NetR18_2")
		)
	)
	(footprint "Capacitors:CAPC2012X14N"
		(layer "F.Cu")
		(at 227.648595 106.4496 90)
		(property "Reference" "C6"
			(at 2.046 0.483345 90)
			(unlocked yes)
			(layer "F.SilkS")
			(effects
				(font
					(size 0.762 0.762)
					(thickness 0.2286)
				)
				(justify left bottom)
			)
		)
		(property "Value" "CAP_0805_10UF_25V"
			(at -3.39979 -5.0165 0)
			(unlocked yes)
			(layer "F.SilkS")
			(hide yes)
			(effects
				(font
					(size 1.524 1.524)
					(thickness 0.254)
				)
				(justify left bottom)
			)
		)
		(sheetname "POWER")
		(sheetfile "POWER.kicad_sch")
		(duplicate_pad_numbers_are_jumpers no)
		(fp_line
			(start -0.762 -0.9652)
			(end 0.762 -0.9652)
			(stroke
				(width 0.1524)
				(type solid)
			)
			(layer "F.SilkS")
		)
		(fp_line
			(start -0.762 0.9652)
			(end 0.762 0.9652)
			(stroke
				(width 0.1524)
				(type solid)
			)
			(layer "F.SilkS")
		)
		(pad "1" smd rect
			(at -0.9 0 180)
			(size 1.45 1.15)
			(layers "F.Cu" "F.Mask" "F.Paste")
			(net "+12V")
		)
		(pad "2" smd rect
			(at 0.9 0 180)
			(size 1.45 1.15)
			(layers "F.Cu" "F.Mask" "F.Paste")
			(net "GND")
		)
	)
	(footprint "Vault:CAPC1608X87X45ML20T05"
		(layer "F.Cu")
		(at 185.488595 87.8286 -90)
		(property "Reference" "C24"
			(at 2.7714 -0.026931 90)
			(unlocked yes)
			(layer "F.SilkS")
			(effects
				(font
					(size 0.762 0.762)
					(thickness 0.2286)
				)
			)
		)
		(property "Value" "0.1uF"
			(at 2.09443 2.657602 270)
			(unlocked yes)
			(layer "F.SilkS")
			(hide yes)
			(effects
				(font
					(size 1.524 1.524)
					(thickness 0.254)
				)
			)
		)
		(sheetname "MAC")
		(sheetfile "MAC.kicad_sch")
		(duplicate_pad_numbers_are_jumpers no)
		(pad "1" smd rect
			(at -0.7 0)
			(size 1.1 1.05)
			(layers "F.Cu" "F.Mask" "F.Paste")
			(net "+3.3V")
		)
		(pad "2" smd rect
			(at 0.7 0)
			(size 1.1 1.05)
			(layers "F.Cu" "F.Mask" "F.Paste")
			(net "GND")
		)
	)
	(footprint "Vault:RESC1608X55X30NL15T15"
		(layer "F.Cu")
		(at 79.988595 56.9786 90)
		(property "Reference" "R28"
			(at -1.2 -1.206655 90)
			(unlocked yes)
			(layer "F.SilkS")
			(effects
				(font
					(size 0.762 0.762)
					(thickness 0.2286)
				)
				(justify left bottom)
			)
		)
		(property "Value" "200 OHM"
			(at -3.72999 -0.4445 0)
			(unlocked yes)
			(layer "F.SilkS")
			(hide yes)
			(effects
				(font
					(size 1.524 1.524)
					(thickness 0.254)
				)
				(justify left bottom)
			)
		)
		(sheetname "USER_IO")
		(sheetfile "USER_IO.kicad_sch")
		(duplicate_pad_numbers_are_jumpers no)
		(pad "1" smd rect
			(at -0.675 0 180)
			(size 0.95 0.8)
			(layers "F.Cu" "F.Mask" "F.Paste")
			(net "LED2")
		)
		(pad "2" smd rect
			(at 0.675 0 180)
			(size 0.95 0.8)
			(layers "F.Cu" "F.Mask" "F.Paste")
			(net "NetD12_1")
		)
	)
	(footprint "Capacitors:CAPC2012X14N"
		(layer "F.Cu")
		(at 227.775595 124.4836 180)
		(property "Reference" "C13"
			(at -1.94991 -0.690055 0)
			(unlocked yes)
			(layer "F.SilkS")
			(effects
				(font
					(size 0.762 0.762)
					(thickness 0.2286)
				)
				(justify left bottom)
			)
		)
		(property "Value" "CAP_0805_10UF_25V"
			(at 7.4295 -0.98679 0)
			(unlocked yes)
			(layer "F.SilkS")
			(hide yes)
			(effects
				(font
					(size 1.524 1.524)
					(thickness 0.254)
				)
				(justify left bottom)
			)
		)
		(sheetname "POWER")
		(sheetfile "POWER.kicad_sch")
		(duplicate_pad_numbers_are_jumpers no)
		(fp_line
			(start 0.762 0.9652)
			(end -0.762 0.9652)
			(stroke
				(width 0.1524)
				(type solid)
			)
			(layer "F.SilkS")
		)
		(fp_line
			(start 0.762 -0.9652)
			(end -0.762 -0.9652)
			(stroke
				(width 0.1524)
				(type solid)
			)
			(layer "F.SilkS")
		)
		(pad "1" smd rect
			(at -0.9 0 270)
			(size 1.45 1.15)
			(layers "F.Cu" "F.Mask" "F.Paste")
			(net "+5.0V")
		)
		(pad "2" smd rect
			(at 0.9 0 270)
			(size 1.45 1.15)
			(layers "F.Cu" "F.Mask" "F.Paste")
			(net "GND")
		)
	)
	(footprint "Resistors:RESC1608X50N"
		(layer "F.Cu")
		(at 214.188595 88.5786 90)
		(property "Reference" "R1"
			(at 2.4 0.393345 90)
			(unlocked yes)
			(layer "F.SilkS")
			(effects
				(font
					(size 0.762 0.762)
					(thickness 0.2286)
				)
				(justify left bottom)
			)
		)
		(property "Value" "ERJ-3EKF2000V"
			(at -3.17119 -1.0033 0)
			(unlocked yes)
			(layer "F.SilkS")
			(hide yes)
			(effects
				(font
					(size 1.524 1.524)
					(thickness 0.254)
				)
				(justify left bottom)
			)
		)
		(sheetname "POWER")
		(sheetfile "POWER.kicad_sch")
		(duplicate_pad_numbers_are_jumpers no)
		(fp_line
			(start 0 -0.5)
			(end 0 0.5)
			(stroke
				(width 0.1524)
				(type solid)
			)
			(layer "F.SilkS")
		)
		(pad "1" smd rect
			(at -0.69 0 180)
			(size 1 0.72)
			(layers "F.Cu" "F.Mask" "F.Paste")
			(net "GND")
		)
		(pad "2" smd rect
			(at 0.69 0 180)
			(size 1 0.72)
			(layers "F.Cu" "F.Mask" "F.Paste")
			(net "NetD4_1")
		)
	)
	(footprint "Resistors:RESC1005X04N"
		(layer "F.Cu")
		(at 122.088595 145.5786 -90)
		(property "Reference" "R23"
			(at 1.27491 0.808535 90)
			(unlocked yes)
			(layer "F.SilkS")
			(effects
				(font
					(size 0.762 0.762)
					(thickness 0.2286)
				)
				(justify left bottom)
			)
		)
		(property "Value" "ERJ-2GE0R00X"
			(at 3.42519 0.2413 0)
			(unlocked yes)
			(layer "F.SilkS")
			(hide yes)
			(effects
				(font
					(size 1.524 1.524)
					(thickness 0.254)
				)
				(justify left bottom)
			)
		)
		(sheetname "PCIe_JTAG")
		(sheetfile "PCIe_JTAG.kicad_sch")
		(duplicate_pad_numbers_are_jumpers no)
		(pad "1" smd rect
			(at -0.425 0)
			(size 0.6 0.65)
			(layers "F.Cu" "F.Mask" "F.Paste")
			(net "PRSNT")
		)
		(pad "2" smd rect
			(at 0.425 0)
			(size 0.6 0.65)
			(layers "F.Cu" "F.Mask" "F.Paste")
			(net "NetP2_B17")
		)
	)
	(footprint "Passives:IND_PM124SH"
		(layer "F.Cu")
		(at 228.156595 94.2576 -90)
		(property "Reference" "L2"
			(at -7.488745 -4.73741 0)
			(unlocked yes)
			(layer "F.SilkS")
			(effects
				(font
					(size 0.762 0.762)
					(thickness 0.2286)
				)
				(justify left bottom)
			)
		)
		(property "Value" "PM124SH-100M-RC"
			(at 11.14679 12.7381 0)
			(unlocked yes)
			(layer "F.SilkS")
			(hide yes)
			(effects
				(font
					(size 1.524 1.524)
					(thickness 0.254)
				)
				(justify left bottom)
			)
		)
		(sheetname "POWER")
		(sheetfile "POWER.kicad_sch")
		(duplicate_pad_numbers_are_jumpers no)
		(fp_line
			(start -6.681 6.4)
			(end -6.681 -6.4)
			(stroke
				(width 0.254)
				(type solid)
			)
			(layer "F.SilkS")
		)
		(fp_line
			(start 6.681 6.4)
			(end -6.681 6.4)
			(stroke
				(width 0.254)
				(type solid)
			)
			(layer "F.SilkS")
		)
		(fp_line
			(start 6.681 6.4)
			(end 6.681 -6.4)
			(stroke
				(width 0.254)
				(type solid)
			)
			(layer "F.SilkS")
		)
		(fp_line
			(start 6.681 -6.4)
			(end -6.681 -6.4)
			(stroke
				(width 0.254)
				(type solid)
			)
			(layer "F.SilkS")
		)
		(pad "1" smd rect
			(at -4.85 0 270)
			(size 2.9 5.4)
			(layers "F.Cu" "F.Mask" "F.Paste")
			(net "+3.3V")
		)
		(pad "2" smd rect
			(at 4.85 0 270)
			(size 2.9 5.4)
			(layers "F.Cu" "F.Mask" "F.Paste")
			(net "NetC3_2")
		)
	)
	(footprint "Resistors:RESC1608X50N"
		(layer "F.Cu")
		(at 219.488595 98.0786 180)
		(property "Reference" "R7"
			(at 3.982 -0.350345 0)
			(unlocked yes)
			(layer "F.SilkS")
			(effects
				(font
					(size 0.762 0.762)
					(thickness 0.2286)
				)
				(justify left bottom)
			)
		)
		(property "Value" "ERJ-3EKF1002V"
			(at -10.9347 3.94081 0)
			(unlocked yes)
			(layer "F.SilkS")
			(hide yes)
			(effects
				(font
					(size 1.524 1.524)
					(thickness 0.254)
				)
				(justify left bottom)
			)
		)
		(sheetname "POWER")
		(sheetfile "POWER.kicad_sch")
		(duplicate_pad_numbers_are_jumpers no)
		(fp_line
			(start 0 -0.5)
			(end 0 0.5)
			(stroke
				(width 0.1524)
				(type solid)
			)
			(layer "F.SilkS")
		)
		(pad "1" smd rect
			(at -0.69 0 270)
			(size 1 0.72)
			(layers "F.Cu" "F.Mask" "F.Paste")
			(net "GND")
		)
		(pad "2" smd rect
			(at 0.69 0 270)
			(size 1 0.72)
			(layers "F.Cu" "F.Mask" "F.Paste")
			(net "NetR5_1")
		)
	)
	(footprint "Vault:SOT143-4L"
		(layer "F.Cu")
		(at 72.538595 103.9286 90)
		(property "Reference" "D2"
			(at -2.926931 1.178605 360)
			(unlocked yes)
			(layer "F.SilkS")
			(effects
				(font
					(size 0.762 0.762)
					(thickness 0.2286)
				)
			)
		)
		(property "Value" "8240136"
			(at 2.7035 3.368802 90)
			(unlocked yes)
			(layer "F.SilkS")
			(hide yes)
			(effects
				(font
					(size 1.524 1.524)
					(thickness 0.254)
				)
			)
		)
		(sheetname "USER_IO")
		(sheetfile "USER_IO.kicad_sch")
		(duplicate_pad_numbers_are_jumpers no)
		(fp_line
			(start 2.05 -1.7)
			(end 2.05 1.7)
			(stroke
				(width 0.2)
				(type solid)
			)
			(layer "F.SilkS")
		)
		(fp_line
			(start -2.05 -1.7)
			(end 2.05 -1.7)
			(stroke
				(width 0.2)
				(type solid)
			)
			(layer "F.SilkS")
		)
		(fp_line
			(start -2.05 -1.7)
			(end -2.05 1.675)
			(stroke
				(width 0.2)
				(type solid)
			)
			(layer "F.SilkS")
		)
		(fp_line
			(start -2.05 1.7)
			(end 2.05 1.7)
			(stroke
				(width 0.2)
				(type solid)
			)
			(layer "F.SilkS")
		)
		(fp_circle
			(center -2.404 -1.075)
			(end -2.15 -1.075)
			(stroke
				(width 0.2)
				(type solid)
			)
			(fill no)
			(layer "F.SilkS")
		)
		(pad "1" smd rect
			(at -1.1 -0.75 180)
			(size 1.4 1.4)
			(layers "F.Cu" "F.Mask" "F.Paste")
			(net "GND")
		)
		(pad "2" smd rect
			(at -1.1 0.95 180)
			(size 1 1.4)
			(layers "F.Cu" "F.Mask" "F.Paste")
			(net "NetAN2_1")
		)
		(pad "3" smd rect
			(at 1.1 0.95 180)
			(size 1 1.4)
			(layers "F.Cu" "F.Mask" "F.Paste")
			(net "NetAN1_1")
		)
		(pad "4" smd rect
			(at 1.1 -0.95 180)
			(size 1 1.4)
			(layers "F.Cu" "F.Mask" "F.Paste")
			(net "+3.3V")
		)
	)
	(footprint "Capacitors:CAPC2012X14N"
		(layer "F.Cu")
		(at 227.775595 121.6896 180)
		(property "Reference" "C14"
			(at -1.97531 -1.604455 0)
			(unlocked yes)
			(layer "F.SilkS")
			(effects
				(font
					(size 0.762 0.762)
					(thickness 0.2286)
				)
				(justify left bottom)
			)
		)
		(property "Value" "CAP_0805_10UF_25V"
			(at 4.6355 -3.78079 0)
			(unlocked yes)
			(layer "F.SilkS")
			(hide yes)
			(effects
				(font
					(size 1.524 1.524)
					(thickness 0.254)
				)
				(justify left bottom)
			)
		)
		(sheetname "POWER")
		(sheetfile "POWER.kicad_sch")
		(duplicate_pad_numbers_are_jumpers no)
		(fp_line
			(start 0.762 0.9652)
			(end -0.762 0.9652)
			(stroke
				(width 0.1524)
				(type solid)
			)
			(layer "F.SilkS")
		)
		(fp_line
			(start 0.762 -0.9652)
			(end -0.762 -0.9652)
			(stroke
				(width 0.1524)
				(type solid)
			)
			(layer "F.SilkS")
		)
		(pad "1" smd rect
			(at -0.9 0 270)
			(size 1.45 1.15)
			(layers "F.Cu" "F.Mask" "F.Paste")
			(net "+5.0V")
		)
		(pad "2" smd rect
			(at 0.9 0 270)
			(size 1.45 1.15)
			(layers "F.Cu" "F.Mask" "F.Paste")
			(net "GND")
		)
	)
	(footprint "Vault:CAPC1608X87X45ML20T05"
		(layer "F.Cu")
		(at 219.588595 94.3786 180)
		(property "Reference" "C11"
			(at 4.1 0.606655 0)
			(unlocked yes)
			(layer "F.SilkS")
			(effects
				(font
					(size 0.762 0.762)
					(thickness 0.2286)
				)
				(justify left bottom)
			)
		)
		(property "Value" "0.1uF"
			(at -11.3919 -1.69799 0)
			(unlocked yes)
			(layer "F.SilkS")
			(hide yes)
			(effects
				(font
					(size 1.524 1.524)
					(thickness 0.254)
				)
				(justify left bottom)
			)
		)
		(sheetname "POWER")
		(sheetfile "POWER.kicad_sch")
		(duplicate_pad_numbers_are_jumpers no)
		(pad "1" smd rect
			(at -0.7 0 270)
			(size 1.1 1.05)
			(layers "F.Cu" "F.Mask" "F.Paste")
			(net "GND")
		)
		(pad "2" smd rect
			(at 0.7 0 270)
			(size 1.1 1.05)
			(layers "F.Cu" "F.Mask" "F.Paste")
			(net "+3.3V")
		)
	)
	(footprint "Resistors:RESC2012X50N"
		(layer "F.Cu")
		(at 104.488595 65.3286 90)
		(property "Reference" "R20"
			(at -1.25 -6.406655 90)
			(unlocked yes)
			(layer "F.SilkS")
			(effects
				(font
					(size 0.762 0.762)
					(thickness 0.2286)
				)
				(justify left bottom)
			)
		)
		(property "Value" "CRCW080533R0FKEA"
			(at -3.52679 -1.5875 0)
			(unlocked yes)
			(layer "F.SilkS")
			(hide yes)
			(effects
				(font
					(size 1.524 1.524)
					(thickness 0.254)
				)
				(justify left bottom)
			)
		)
		(sheetname "PCIe_JTAG")
		(sheetfile "PCIe_JTAG.kicad_sch")
		(duplicate_pad_numbers_are_jumpers no)
		(fp_line
			(start 0 -0.762)
			(end 0 0.762)
			(stroke
				(width 0.1524)
				(type solid)
			)
			(layer "F.SilkS")
		)
		(pad "1" smd rect
			(at -1 0 180)
			(size 1.45 0.95)
			(layers "F.Cu" "F.Mask" "F.Paste")
			(net "FPGA_TMS")
		)
		(pad "2" smd rect
			(at 1 0 180)
			(size 1.45 0.95)
			(layers "F.Cu" "F.Mask" "F.Paste")
			(net "NetR20_2")
		)
	)
	(footprint "Vault:CAPC1608X87X45ML20T05"
		(layer "F.Cu")
		(at 191.238595 86.3286)
		(property "Reference" "C23"
			(at -2.7714 0.026931 0)
			(unlocked yes)
			(layer "F.SilkS")
			(effects
				(font
					(size 0.762 0.762)
					(thickness 0.2286)
				)
			)
		)
		(property "Value" "0.1uF"
			(at 2.09443 2.657602 0)
			(unlocked yes)
			(layer "F.SilkS")
			(hide yes)
			(effects
				(font
					(size 1.524 1.524)
					(thickness 0.254)
				)
			)
		)
		(sheetname "MAC")
		(sheetfile "MAC.kicad_sch")
		(duplicate_pad_numbers_are_jumpers no)
		(pad "1" smd rect
			(at -0.7 0 90)
			(size 1.1 1.05)
			(layers "F.Cu" "F.Mask" "F.Paste")
			(net "GND")
		)
		(pad "2" smd rect
			(at 0.7 0 90)
			(size 1.1 1.05)
			(layers "F.Cu" "F.Mask" "F.Paste")
			(net "+3.3V")
		)
	)
	(footprint "Vault:FP-318BQ-MFG"
		(layer "F.Cu")
		(at 86.488595 97.0786 180)
		(property "Reference" "U6"
			(at -1.228605 2.723069 0)
			(unlocked yes)
			(layer "F.SilkS")
			(effects
				(font
					(size 0.762 0.762)
					(thickness 0.2286)
				)
			)
		)
		(property "Value" "NC7SZ125M5"
			(at 5.03956 3.495802 180)
			(unlocked yes)
			(layer "F.SilkS")
			(hide yes)
			(effects
				(font
					(size 1.524 1.524)
					(thickness 0.254)
				)
			)
		)
		(sheetname "USER_IO")
		(sheetfile "USER_IO.kicad_sch")
		(duplicate_pad_numbers_are_jumpers no)
		(fp_line
			(start 0.825 -0.225)
			(end 0.825 0.225)
			(stroke
				(width 0.2)
				(type solid)
			)
			(layer "F.SilkS")
		)
		(fp_line
			(start 0.325 1.575)
			(end -0.325 1.575)
			(stroke
				(width 0.2)
				(type solid)
			)
			(layer "F.SilkS")
		)
		(fp_line
			(start 0.325 -1.575)
			(end -0.325 -1.575)
			(stroke
				(width 0.2)
				(type solid)
			)
			(layer "F.SilkS")
		)
		(fp_circle
			(center -2.45 -0.95)
			(end -2.45 -0.825)
			(stroke
				(width 0.25)
				(type solid)
			)
			(fill no)
			(layer "F.SilkS")
		)
		(fp_line
			(start 1.8 1.825)
			(end -1.8 1.825)
			(stroke
				(width 0.2)
				(type solid)
			)
			(layer "F.CrtYd")
		)
		(fp_line
			(start 1.8 -1.825)
			(end 1.8 1.825)
			(stroke
				(width 0.2)
				(type solid)
			)
			(layer "F.CrtYd")
		)
		(fp_line
			(start 1.8 -1.825)
			(end -1.8 -1.825)
			(stroke
				(width 0.2)
				(type solid)
			)
			(layer "F.CrtYd")
		)
		(fp_line
			(start -1.8 -1.825)
			(end -1.8 1.825)
			(stroke
				(width 0.2)
				(type solid)
			)
			(layer "F.CrtYd")
		)
		(fp_line
			(start 1.8 1.825)
			(end -1.8 1.825)
			(stroke
				(width 0.2)
				(type solid)
			)
			(layer "F.Fab")
		)
		(fp_line
			(start 1.8 -1.825)
			(end 1.8 1.825)
			(stroke
				(width 0.2)
				(type solid)
			)
			(layer "F.Fab")
		)
		(fp_line
			(start 1.8 -1.825)
			(end -1.8 -1.825)
			(stroke
				(width 0.2)
				(type solid)
			)
			(layer "F.Fab")
		)
		(fp_line
			(start 0.5 0)
			(end -0.5 0)
			(stroke
				(width 0.1)
				(type solid)
			)
			(layer "F.Fab")
		)
		(fp_line
			(start 0 -0.5)
			(end 0 0.5)
			(stroke
				(width 0.1)
				(type solid)
			)
			(layer "F.Fab")
		)
		(fp_line
			(start -1.8 -1.825)
			(end -1.8 1.825)
			(stroke
				(width 0.2)
				(type solid)
			)
			(layer "F.Fab")
		)
		(fp_text user "${REFERENCE}"
			(at 0 0.28494 180)
			(unlocked yes)
			(layer "F.Fab")
			(effects
				(font
					(face "Arial")
					(size 0.63 0.63)
					(thickness 0.1)
				)
				(justify left bottom)
			)
		)
		(pad "1" smd rect
			(at -1.2 -0.95 180)
			(size 1 0.7)
			(layers "F.Cu" "F.Mask" "F.Paste")
			(net "GND")
			(solder_mask_margin 0)
			(solder_paste_margin 0)
		)
		(pad "2" smd rect
			(at -1.2 0 180)
			(size 1 0.7)
			(layers "F.Cu" "F.Mask" "F.Paste")
			(net "ANT1")
			(solder_mask_margin 0)
			(solder_paste_margin 0)
		)
		(pad "3" smd rect
			(at -1.2 0.95 180)
			(size 1 0.7)
			(layers "F.Cu" "F.Mask" "F.Paste")
			(net "GND")
			(solder_mask_margin 0)
			(solder_paste_margin 0)
		)
		(pad "4" smd rect
			(at 1.2 0.95 180)
			(size 1 0.7)
			(layers "F.Cu" "F.Mask" "F.Paste")
			(net "NetR14_1")
			(solder_mask_margin 0)
			(solder_paste_margin 0)
		)
		(pad "5" smd rect
			(at 1.2 -0.95 180)
			(size 1 0.7)
			(layers "F.Cu" "F.Mask" "F.Paste")
			(net "+3.3V")
			(solder_mask_margin 0)
			(solder_paste_margin 0)
		)
	)
	(footprint "Vault:FP-5TS1-IPC_C"
		(layer "F.Cu")
		(at 134.238595 89.0786 -90)
		(property "Reference" "U7"
			(at -2.723069 0.771395 0)
			(unlocked yes)
			(layer "F.SilkS")
			(effects
				(font
					(size 0.762 0.762)
					(thickness 0.2286)
				)
			)
		)
		(property "Value" "AT24MAC402-STUM-T"
			(at 10.752795 3.216402 270)
			(unlocked yes)
			(layer "F.SilkS")
			(hide yes)
			(effects
				(font
					(size 1.524 1.524)
					(thickness 0.254)
				)
			)
		)
		(sheetname "GPS_IMU_SENSORS")
		(sheetfile "GPS_IMU_SENSORS.kicad_sch")
		(duplicate_pad_numbers_are_jumpers no)
		(fp_line
			(start 0.17208 1.45)
			(end -0.17207 1.45)
			(stroke
				(width 0.2)
				(type solid)
			)
			(layer "F.SilkS")
		)
		(fp_line
			(start 0.8 0.30893)
			(end 0.8 -0.30894)
			(stroke
				(width 0.2)
				(type solid)
			)
			(layer "F.SilkS")
		)
		(fp_line
			(start 0.17208 -1.45)
			(end -0.17207 -1.45)
			(stroke
				(width 0.2)
				(type solid)
			)
			(layer "F.SilkS")
		)
		(fp_circle
			(center -2.21035 -0.95)
			(end -2.33535 -0.95)
			(stroke
				(width 0.25)
				(type solid)
			)
			(fill no)
			(layer "F.SilkS")
		)
		(fp_line
			(start -1.68536 1.55)
			(end -1.68536 -1.55)
			(stroke
				(width 0.2)
				(type solid)
			)
			(layer "F.CrtYd")
		)
		(fp_line
			(start 1.68536 1.55)
			(end -1.68536 1.55)
			(stroke
				(width 0.2)
				(type solid)
			)
			(layer "F.CrtYd")
		)
		(fp_line
			(start 1.68536 1.55)
			(end 1.68536 -1.55)
			(stroke
				(width 0.2)
				(type solid)
			)
			(layer "F.CrtYd")
		)
		(fp_line
			(start 1.68536 -1.55)
			(end -1.68536 -1.55)
			(stroke
				(width 0.2)
				(type solid)
			)
			(layer "F.CrtYd")
		)
		(fp_line
			(start -1.68536 1.55)
			(end -1.68536 -1.55)
			(stroke
				(width 0.2)
				(type solid)
			)
			(layer "F.Fab")
		)
		(fp_line
			(start 1.68536 1.55)
			(end -1.68536 1.55)
			(stroke
				(width 0.2)
				(type solid)
			)
			(layer "F.Fab")
		)
		(fp_line
			(start 1.68536 1.55)
			(end 1.68536 -1.55)
			(stroke
				(width 0.2)
				(type solid)
			)
			(layer "F.Fab")
		)
		(fp_line
			(start 0 0.5)
			(end 0 -0.5)
			(stroke
				(width 0.1)
				(type solid)
			)
			(layer "F.Fab")
		)
		(fp_line
			(start 0.5 0)
			(end -0.5 0)
			(stroke
				(width 0.1)
				(type solid)
			)
			(layer "F.Fab")
		)
		(fp_line
			(start 1.68536 -1.55)
			(end -1.68536 -1.55)
			(stroke
				(width 0.2)
				(type solid)
			)
			(layer "F.Fab")
		)
		(fp_text user "${REFERENCE}"
			(at 0.00001 0.28494 270)
			(unlocked yes)
			(layer "F.Fab")
			(effects
				(font
					(face "Arial")
					(size 0.63 0.63)
					(thickness 0.1)
				)
				(justify left bottom)
			)
		)
		(pad "1" smd rect
			(at -1.06621 -0.95 270)
			(size 1.03828 0.53213)
			(layers "F.Cu" "F.Mask" "F.Paste")
			(net "SCL")
			(solder_mask_margin 0)
			(solder_paste_margin 0)
		)
		(pad "2" smd roundrect
			(at -1.06621 0 270)
			(size 1.03828 0.53213)
			(layers "F.Cu" "F.Mask" "F.Paste")
			(roundrect_rratio 0.5)
			(net "GND")
			(solder_mask_margin 0)
			(solder_paste_margin 0)
		)
		(pad "3" smd roundrect
			(at -1.06621 0.95 270)
			(size 1.03828 0.53213)
			(layers "F.Cu" "F.Mask" "F.Paste")
			(roundrect_rratio 0.5)
			(net "SDA")
			(solder_mask_margin 0)
			(solder_paste_margin 0)
		)
		(pad "4" smd roundrect
			(at 1.06621 0.95 270)
			(size 1.03828 0.53213)
			(layers "F.Cu" "F.Mask" "F.Paste")
			(roundrect_rratio 0.5)
			(net "+3.3V")
			(solder_mask_margin 0)
			(solder_paste_margin 0)
		)
		(pad "5" smd roundrect
			(at 1.06621 -0.95 270)
			(size 1.03828 0.53213)
			(layers "F.Cu" "F.Mask" "F.Paste")
			(roundrect_rratio 0.5)
			(net "EXT_EEPROM_WP")
			(solder_mask_margin 0)
			(solder_paste_margin 0)
		)
	)
	(footprint "Vault:CAPC1608X90X35NL10T15"
		(layer "F.Cu")
		(at 212.535595 100.6076 90)
		(property "Reference" "C22"
			(at 1.479 0.396345 90)
			(unlocked yes)
			(layer "F.SilkS")
			(effects
				(font
					(size 0.762 0.762)
					(thickness 0.2286)
				)
				(justify left bottom)
			)
		)
		(property "Value" "0.033uF"
			(at 8.20801 25.6159 0)
			(unlocked yes)
			(layer "F.SilkS")
			(hide yes)
			(effects
				(font
					(size 1.524 1.524)
					(thickness 0.254)
				)
				(justify left bottom)
			)
		)
		(sheetname "POWER")
		(sheetfile "POWER.kicad_sch")
		(duplicate_pad_numbers_are_jumpers no)
		(pad "1" smd rect
			(at -0.675 0 180)
			(size 0.95 0.85)
			(layers "F.Cu" "F.Mask" "F.Paste")
			(net "NetC22_1")
		)
		(pad "2" smd rect
			(at 0.675 0 180)
			(size 0.95 0.85)
			(layers "F.Cu" "F.Mask" "F.Paste")
			(net "NetC22_2")
		)
	)
	(footprint "Capacitors:CAPC2012X14N"
		(layer "F.Cu")
		(at 109.788595 143.6786 90)
		(property "Reference" "C1"
			(at 2.1 -0.456655 90)
			(unlocked yes)
			(layer "F.SilkS")
			(effects
				(font
					(size 0.762 0.762)
					(thickness 0.2286)
				)
				(justify left bottom)
			)
		)
		(property "Value" "CAP_0805_10UF_25V"
			(at -3.52679 -1.5875 0)
			(unlocked yes)
			(layer "F.SilkS")
			(hide yes)
			(effects
				(font
					(size 1.524 1.524)
					(thickness 0.254)
				)
				(justify left bottom)
			)
		)
		(sheetname "POWER")
		(sheetfile "POWER.kicad_sch")
		(duplicate_pad_numbers_are_jumpers no)
		(fp_line
			(start -0.762 -0.9652)
			(end 0.762 -0.9652)
			(stroke
				(width 0.1524)
				(type solid)
			)
			(layer "F.SilkS")
		)
		(fp_line
			(start -0.762 0.9652)
			(end 0.762 0.9652)
			(stroke
				(width 0.1524)
				(type solid)
			)
			(layer "F.SilkS")
		)
		(pad "1" smd rect
			(at -0.9 0 180)
			(size 1.45 1.15)
			(layers "F.Cu" "F.Mask" "F.Paste")
			(net "+12V")
		)
		(pad "2" smd rect
			(at 0.9 0 180)
			(size 1.45 1.15)
			(layers "F.Cu" "F.Mask" "F.Paste")
			(net "GND")
		)
	)
	(footprint "Vault:FP-318BQ-MFG"
		(layer "F.Cu")
		(at 86.188605 136.0286)
		(property "Reference" "U12"
			(at -0.97861 2.723069 180)
			(unlocked yes)
			(layer "F.SilkS")
			(effects
				(font
					(size 0.762 0.762)
					(thickness 0.2286)
				)
			)
		)
		(property "Value" "NC7SZ125M5"
			(at 5.03956 3.495802 0)
			(unlocked yes)
			(layer "F.SilkS")
			(hide yes)
			(effects
				(font
					(size 1.524 1.524)
					(thickness 0.254)
				)
			)
		)
		(sheetname "USER_IO")
		(sheetfile "USER_IO.kicad_sch")
		(duplicate_pad_numbers_are_jumpers no)
		(fp_line
			(start -0.325 -1.575)
			(end 0.325 -1.575)
			(stroke
				(width 0.2)
				(type solid)
			)
			(layer "F.SilkS")
		)
		(fp_line
			(start -0.325 1.575)
			(end 0.325 1.575)
			(stroke
				(width 0.2)
				(type solid)
			)
			(layer "F.SilkS")
		)
		(fp_line
			(start 0.825 0.225)
			(end 0.825 -0.225)
			(stroke
				(width 0.2)
				(type solid)
			)
			(layer "F.SilkS")
		)
		(fp_circle
			(center -2.45 -0.95)
			(end -2.45 -1.075)
			(stroke
				(width 0.25)
				(type solid)
			)
			(fill no)
			(layer "F.SilkS")
		)
		(fp_line
			(start -1.8 -1.825)
			(end 1.8 -1.825)
			(stroke
				(width 0.2)
				(type solid)
			)
			(layer "F.CrtYd")
		)
		(fp_line
			(start -1.8 1.825)
			(end -1.8 -1.825)
			(stroke
				(width 0.2)
				(type solid)
			)
			(layer "F.CrtYd")
		)
		(fp_line
			(start -1.8 1.825)
			(end 1.8 1.825)
			(stroke
				(width 0.2)
				(type solid)
			)
			(layer "F.CrtYd")
		)
		(fp_line
			(start 1.8 1.825)
			(end 1.8 -1.825)
			(stroke
				(width 0.2)
				(type solid)
			)
			(layer "F.CrtYd")
		)
		(fp_line
			(start -1.8 -1.825)
			(end 1.8 -1.825)
			(stroke
				(width 0.2)
				(type solid)
			)
			(layer "F.Fab")
		)
		(fp_line
			(start -1.8 1.825)
			(end -1.8 -1.825)
			(stroke
				(width 0.2)
				(type solid)
			)
			(layer "F.Fab")
		)
		(fp_line
			(start -1.8 1.825)
			(end 1.8 1.825)
			(stroke
				(width 0.2)
				(type solid)
			)
			(layer "F.Fab")
		)
		(fp_line
			(start -0.5 0)
			(end 0.5 0)
			(stroke
				(width 0.1)
				(type solid)
			)
			(layer "F.Fab")
		)
		(fp_line
			(start 0 0.5)
			(end 0 -0.5)
			(stroke
				(width 0.1)
				(type solid)
			)
			(layer "F.Fab")
		)
		(fp_line
			(start 1.8 1.825)
			(end 1.8 -1.825)
			(stroke
				(width 0.2)
				(type solid)
			)
			(layer "F.Fab")
		)
		(fp_text user "${REFERENCE}"
			(at 0 0.28494 360)
			(unlocked yes)
			(layer "F.Fab")
			(effects
				(font
					(face "Arial")
					(size 0.63 0.63)
					(thickness 0.1)
				)
				(justify left bottom)
			)
		)
		(pad "1" smd rect
			(at -1.2 -0.95)
			(size 1 0.7)
			(layers "F.Cu" "F.Mask" "F.Paste")
			(net "GND")
			(solder_mask_margin 0)
			(solder_paste_margin 0)
		)
		(pad "2" smd rect
			(at -1.2 0)
			(size 1 0.7)
			(layers "F.Cu" "F.Mask" "F.Paste")
			(net "NetR25_1")
			(solder_mask_margin 0)
			(solder_paste_margin 0)
		)
		(pad "3" smd rect
			(at -1.2 0.95)
			(size 1 0.7)
			(layers "F.Cu" "F.Mask" "F.Paste")
			(net "GND")
			(solder_mask_margin 0)
			(solder_paste_margin 0)
		)
		(pad "4" smd rect
			(at 1.2 0.95)
			(size 1 0.7)
			(layers "F.Cu" "F.Mask" "F.Paste")
			(net "ANT4")
			(solder_mask_margin 0)
			(solder_paste_margin 0)
		)
		(pad "5" smd rect
			(at 1.2 -0.95)
			(size 1 0.7)
			(layers "F.Cu" "F.Mask" "F.Paste")
			(net "+3.3V")
			(solder_mask_margin 0)
			(solder_paste_margin 0)
		)
	)
	(footprint "Vault:CAPC1608X87X45ML20T05"
		(layer "F.Cu")
		(at 219.588595 96.1786 180)
		(property "Reference" "C10"
			(at 4.1 1.006655 0)
			(unlocked yes)
			(layer "F.SilkS")
			(effects
				(font
					(size 0.762 0.762)
					(thickness 0.2286)
				)
				(justify left bottom)
			)
		)
		(property "Value" "0.1uF"
			(at -9.9949 -0.30099 0)
			(unlocked yes)
			(layer "F.SilkS")
			(hide yes)
			(effects
				(font
					(size 1.524 1.524)
					(thickness 0.254)
				)
				(justify left bottom)
			)
		)
		(sheetname "POWER")
		(sheetfile "POWER.kicad_sch")
		(duplicate_pad_numbers_are_jumpers no)
		(pad "1" smd rect
			(at -0.7 0 270)
			(size 1.1 1.05)
			(layers "F.Cu" "F.Mask" "F.Paste")
			(net "GND")
		)
		(pad "2" smd rect
			(at 0.7 0 270)
			(size 1.1 1.05)
			(layers "F.Cu" "F.Mask" "F.Paste")
			(net "+3.3V")
		)
	)
	(footprint "Vault:CAPC1608X87X45ML20T05"
		(layer "F.Cu")
		(at 140.288595 92.0786 180)
		(property "Reference" "C32"
			(at 3.0714 -0.026931 0)
			(unlocked yes)
			(layer "F.SilkS")
			(effects
				(font
					(size 0.762 0.762)
					(thickness 0.2286)
				)
			)
		)
		(property "Value" "0.1uF"
			(at 2.09443 2.657602 180)
			(unlocked yes)
			(layer "F.SilkS")
			(hide yes)
			(effects
				(font
					(size 1.524 1.524)
					(thickness 0.254)
				)
			)
		)
		(sheetname "GPS_IMU_SENSORS")
		(sheetfile "GPS_IMU_SENSORS.kicad_sch")
		(duplicate_pad_numbers_are_jumpers no)
		(pad "1" smd rect
			(at -0.7 0 270)
			(size 1.1 1.05)
			(layers "F.Cu" "F.Mask" "F.Paste")
			(net "GND")
		)
		(pad "2" smd rect
			(at 0.7 0 270)
			(size 1.1 1.05)
			(layers "F.Cu" "F.Mask" "F.Paste")
			(net "+3.3V")
		)
	)
	(footprint "IntegratedCircuits:SOIC127P600X175-8N"
		(layer "F.Cu")
		(at 217.361595 101.7506 180)
		(property "Reference" "U2"
			(at 6.13379 -2.264855 0)
			(unlocked yes)
			(layer "F.SilkS")
			(effects
				(font
					(size 0.762 0.762)
					(thickness 0.2286)
				)
				(justify left bottom)
			)
		)
		(property "Value" "MP1482DS-LF"
			(at -12.7381 8.69061 0)
			(unlocked yes)
			(layer "F.SilkS")
			(hide yes)
			(effects
				(font
					(size 1.524 1.524)
					(thickness 0.254)
				)
				(justify left bottom)
			)
		)
		(sheetname "POWER")
		(sheetfile "POWER.kicad_sch")
		(duplicate_pad_numbers_are_jumpers no)
		(fp_line
			(start 2 2.5)
			(end -2 2.5)
			(stroke
				(width 0.12)
				(type solid)
			)
			(layer "F.SilkS")
		)
		(fp_line
			(start 2 -2.5)
			(end -3.4 -2.5)
			(stroke
				(width 0.12)
				(type solid)
			)
			(layer "F.SilkS")
		)
		(pad "1" smd rect
			(at -2.475 -1.905 180)
			(size 1.97 0.57)
			(layers "F.Cu" "F.Mask" "F.Paste")
			(net "NetC3_1")
		)
		(pad "2" smd rect
			(at -2.475 -0.635 180)
			(size 1.97 0.57)
			(layers "F.Cu" "F.Mask" "F.Paste")
			(net "+12V")
		)
		(pad "3" smd rect
			(at -2.475 0.635 180)
			(size 1.97 0.57)
			(layers "F.Cu" "F.Mask" "F.Paste")
			(net "NetC3_2")
		)
		(pad "4" smd rect
			(at -2.475 1.905 180)
			(size 1.97 0.57)
			(layers "F.Cu" "F.Mask" "F.Paste")
			(net "GND")
		)
		(pad "5" smd rect
			(at 2.475 1.905 180)
			(size 1.97 0.57)
			(layers "F.Cu" "F.Mask" "F.Paste")
			(net "NetR5_1")
		)
		(pad "6" smd rect
			(at 2.475 0.635 180)
			(size 1.97 0.57)
			(layers "F.Cu" "F.Mask" "F.Paste")
			(net "NetC22_2")
		)
		(pad "7" smd rect
			(at 2.475 -0.635 180)
			(size 1.97 0.57)
			(layers "F.Cu" "F.Mask" "F.Paste")
			(net "NetR3_1")
		)
		(pad "8" smd rect
			(at 2.475 -1.905 180)
			(size 1.97 0.57)
			(layers "F.Cu" "F.Mask" "F.Paste")
			(net "NetC21_2")
		)
	)
	(footprint "Vault:FP-BMX160-MFG"
		(layer "F.Cu")
		(at 140.738595 88.8286)
		(property "Reference" "U13"
			(at -0.7714 -2.723079 0)
			(unlocked yes)
			(layer "F.SilkS")
			(effects
				(font
					(size 0.762 0.762)
					(thickness 0.2286)
				)
			)
		)
		(property "Value" "BMX160"
			(at 1.967145 3.521202 0)
			(unlocked yes)
			(layer "F.SilkS")
			(hide yes)
			(effects
				(font
					(size 1.524 1.524)
					(thickness 0.254)
				)
			)
		)
		(sheetname "GPS_IMU_SENSORS")
		(sheetfile "GPS_IMU_SENSORS.kicad_sch")
		(duplicate_pad_numbers_are_jumpers no)
		(fp_line
			(start -2.1 -1.85)
			(end 2.1 -1.85)
			(stroke
				(width 0.2)
				(type solid)
			)
			(layer "F.SilkS")
		)
		(fp_line
			(start -2.1 1.85)
			(end -2.1 -1.85)
			(stroke
				(width 0.2)
				(type solid)
			)
			(layer "F.SilkS")
		)
		(fp_line
			(start -2.1 1.85)
			(end 2.1 1.85)
			(stroke
				(width 0.2)
				(type solid)
			)
			(layer "F.SilkS")
		)
		(fp_line
			(start 2.1 1.85)
			(end 2.1 -1.85)
			(stroke
				(width 0.2)
				(type solid)
			)
			(layer "F.SilkS")
		)
		(fp_circle
			(center -2.475 -0.75)
			(end -2.475 -0.875)
			(stroke
				(width 0.25)
				(type solid)
			)
			(fill no)
			(layer "F.SilkS")
		)
		(fp_line
			(start -2.1 -1.85)
			(end 2.1 -1.85)
			(stroke
				(width 0.2)
				(type solid)
			)
			(layer "F.CrtYd")
		)
		(fp_line
			(start -2.1 1.85)
			(end -2.1 -1.85)
			(stroke
				(width 0.2)
				(type solid)
			)
			(layer "F.CrtYd")
		)
		(fp_line
			(start -2.1 1.85)
			(end 2.1 1.85)
			(stroke
				(width 0.2)
				(type solid)
			)
			(layer "F.CrtYd")
		)
		(fp_line
			(start 2.1 1.85)
			(end 2.1 -1.85)
			(stroke
				(width 0.2)
				(type solid)
			)
			(layer "F.CrtYd")
		)
		(fp_line
			(start -2.1 -1.85)
			(end 2.1 -1.85)
			(stroke
				(width 0.2)
				(type solid)
			)
			(layer "F.Fab")
		)
		(fp_line
			(start -2.1 1.85)
			(end -2.1 -1.85)
			(stroke
				(width 0.2)
				(type solid)
			)
			(layer "F.Fab")
		)
		(fp_line
			(start -2.1 1.85)
			(end 2.1 1.85)
			(stroke
				(width 0.2)
				(type solid)
			)
			(layer "F.Fab")
		)
		(fp_line
			(start -0.5 0)
			(end 0.5 0)
			(stroke
				(width 0.1)
				(type solid)
			)
			(layer "F.Fab")
		)
		(fp_line
			(start 0 0.5)
			(end 0 -0.5)
			(stroke
				(width 0.1)
				(type solid)
			)
			(layer "F.Fab")
		)
		(fp_line
			(start 2.1 1.85)
			(end 2.1 -1.85)
			(stroke
				(width 0.2)
				(type solid)
			)
			(layer "F.Fab")
		)
		(fp_text user "${REFERENCE}"
			(at -0.00001 0.09602 0)
			(unlocked yes)
			(layer "F.Fab")
			(effects
				(font
					(face "Arial")
					(size 0.63 0.63)
					(thickness 0.1)
				)
				(justify left bottom)
			)
		)
		(pad "1" smd rect
			(at -1.2625 -0.75)
			(size 0.675 0.25)
			(layers "F.Cu" "F.Mask" "F.Paste")
			(net "GND")
			(solder_mask_margin 0)
			(solder_paste_margin 0)
		)
		(pad "2" smd rect
			(at -1.2625 -0.25)
			(size 0.675 0.25)
			(layers "F.Cu" "F.Mask" "F.Paste")
			(net "GND")
			(solder_mask_margin 0)
			(solder_paste_margin 0)
		)
		(pad "3" smd rect
			(at -1.2625 0.25)
			(size 0.675 0.25)
			(layers "F.Cu" "F.Mask" "F.Paste")
			(net "GND")
			(solder_mask_margin 0)
			(solder_paste_margin 0)
		)
		(pad "4" smd rect
			(at -1.2625 0.75)
			(size 0.675 0.25)
			(layers "F.Cu" "F.Mask" "F.Paste")
			(solder_mask_margin 0)
			(solder_paste_margin 0)
		)
		(pad "5" smd rect
			(at -0.5 1.0125)
			(size 0.25 0.675)
			(layers "F.Cu" "F.Mask" "F.Paste")
			(net "+3.3V")
			(solder_mask_margin 0)
			(solder_paste_margin 0)
		)
		(pad "6" smd rect
			(at 0 1.0125)
			(size 0.25 0.675)
			(layers "F.Cu" "F.Mask" "F.Paste")
			(net "GND")
			(solder_mask_margin 0)
			(solder_paste_margin 0)
		)
		(pad "7" smd rect
			(at 0.5 1.0125)
			(size 0.25 0.675)
			(layers "F.Cu" "F.Mask" "F.Paste")
			(net "GND")
			(solder_mask_margin 0)
			(solder_paste_margin 0)
		)
		(pad "8" smd rect
			(at 1.2625 0.75)
			(size 0.675 0.25)
			(layers "F.Cu" "F.Mask" "F.Paste")
			(net "+3.3V")
			(solder_mask_margin 0)
			(solder_paste_margin 0)
		)
		(pad "9" smd rect
			(at 1.2625 0.25)
			(size 0.675 0.25)
			(layers "F.Cu" "F.Mask" "F.Paste")
			(solder_mask_margin 0)
			(solder_paste_margin 0)
		)
		(pad "10" smd rect
			(at 1.2625 -0.25)
			(size 0.675 0.25)
			(layers "F.Cu" "F.Mask" "F.Paste")
			(solder_mask_margin 0)
			(solder_paste_margin 0)
		)
		(pad "11" smd rect
			(at 1.2625 -0.75)
			(size 0.675 0.25)
			(layers "F.Cu" "F.Mask" "F.Paste")
			(solder_mask_margin 0)
			(solder_paste_margin 0)
		)
		(pad "12" smd rect
			(at 0.5 -1.0125)
			(size 0.25 0.675)
			(layers "F.Cu" "F.Mask" "F.Paste")
			(net "+3.3V")
			(solder_mask_margin 0)
			(solder_paste_margin 0)
		)
		(pad "13" smd rect
			(at 0 -1.0125)
			(size 0.25 0.675)
			(layers "F.Cu" "F.Mask" "F.Paste")
			(net "SCL")
			(solder_mask_margin 0)
			(solder_paste_margin 0)
		)
		(pad "14" smd rect
			(at -0.5 -1.0125)
			(size 0.25 0.675)
			(layers "F.Cu" "F.Mask" "F.Paste")
			(net "SDA")
			(solder_mask_margin 0)
			(solder_paste_margin 0)
		)
	)
	(footprint "Passives:SOT65P210X110-3N"
		(layer "F.Cu")
		(at 97.988595 69.0786 180)
		(property "Reference" "D5"
			(at 1.75 -2.593345 0)
			(unlocked yes)
			(layer "F.SilkS")
			(effects
				(font
					(size 0.762 0.762)
					(thickness 0.2286)
				)
				(justify left bottom)
			)
		)
		(property "Value" "BAT54SW"
			(at 1.5875 -3.88239 0)
			(unlocked yes)
			(layer "F.SilkS")
			(hide yes)
			(effects
				(font
					(size 1.524 1.524)
					(thickness 0.254)
				)
				(justify left bottom)
			)
		)
		(sheetname "PCIe_JTAG")
		(sheetfile "PCIe_JTAG.kicad_sch")
		(duplicate_pad_numbers_are_jumpers no)
		(fp_line
			(start 0.675 1.1)
			(end -0.325 1.1)
			(stroke
				(width 0.2)
				(type solid)
			)
			(layer "F.SilkS")
		)
		(fp_line
			(start 0.675 0.65)
			(end 0.675 1.1)
			(stroke
				(width 0.2)
				(type solid)
			)
			(layer "F.SilkS")
		)
		(fp_line
			(start 0.675 -1.1)
			(end 0.675 -0.65)
			(stroke
				(width 0.2)
				(type solid)
			)
			(layer "F.SilkS")
		)
		(fp_line
			(start 0.675 -1.1)
			(end -0.325 -1.1)
			(stroke
				(width 0.2)
				(type solid)
			)
			(layer "F.SilkS")
		)
		(fp_circle
			(center -1.125 -1.45)
			(end -1.125 -1.325)
			(stroke
				(width 0.25)
				(type solid)
			)
			(fill no)
			(layer "F.SilkS")
		)
		(pad "1" smd rect
			(at -1.125 -0.65 270)
			(size 0.5 0.9)
			(layers "F.Cu" "F.Mask" "F.Paste")
			(net "GND")
		)
		(pad "2" smd rect
			(at -1.125 0.65 270)
			(size 0.5 0.9)
			(layers "F.Cu" "F.Mask" "F.Paste")
			(net "+3.3V")
		)
		(pad "3" smd rect
			(at 1.125 0 270)
			(size 0.5 0.9)
			(layers "F.Cu" "F.Mask" "F.Paste")
			(net "FPGA_TCK")
		)
	)
	(footprint "Passives:SOT65P210X110-3N"
		(layer "F.Cu")
		(at 107.113595 69.0786 180)
		(property "Reference" "D7"
			(at 1.5 -2.593345 0)
			(unlocked yes)
			(layer "F.SilkS")
			(effects
				(font
					(size 0.762 0.762)
					(thickness 0.2286)
				)
				(justify left bottom)
			)
		)
		(property "Value" "BAT54SW"
			(at 1.1125 -2.10739 0)
			(unlocked yes)
			(layer "F.SilkS")
			(hide yes)
			(effects
				(font
					(size 1.524 1.524)
					(thickness 0.254)
				)
				(justify left bottom)
			)
		)
		(sheetname "PCIe_JTAG")
		(sheetfile "PCIe_JTAG.kicad_sch")
		(duplicate_pad_numbers_are_jumpers no)
		(fp_line
			(start 0.675 1.1)
			(end -0.325 1.1)
			(stroke
				(width 0.2)
				(type solid)
			)
			(layer "F.SilkS")
		)
		(fp_line
			(start 0.675 0.65)
			(end 0.675 1.1)
			(stroke
				(width 0.2)
				(type solid)
			)
			(layer "F.SilkS")
		)
		(fp_line
			(start 0.675 -1.1)
			(end 0.675 -0.65)
			(stroke
				(width 0.2)
				(type solid)
			)
			(layer "F.SilkS")
		)
		(fp_line
			(start 0.675 -1.1)
			(end -0.325 -1.1)
			(stroke
				(width 0.2)
				(type solid)
			)
			(layer "F.SilkS")
		)
		(fp_circle
			(center -1.125 -1.45)
			(end -1.125 -1.325)
			(stroke
				(width 0.25)
				(type solid)
			)
			(fill no)
			(layer "F.SilkS")
		)
		(pad "1" smd rect
			(at -1.125 -0.65 270)
			(size 0.5 0.9)
			(layers "F.Cu" "F.Mask" "F.Paste")
			(net "GND")
		)
		(pad "2" smd rect
			(at -1.125 0.65 270)
			(size 0.5 0.9)
			(layers "F.Cu" "F.Mask" "F.Paste")
			(net "+3.3V")
		)
		(pad "3" smd rect
			(at 1.125 0 270)
			(size 0.5 0.9)
			(layers "F.Cu" "F.Mask" "F.Paste")
			(net "FPGA_TMS")
		)
	)
	(footprint "Vault:CAPC1608X87X45ML20T05"
		(layer "F.Cu")
		(at 86.188595 132.5286 180)
		(property "Reference" "C28"
			(at -2.77141 0.026921 180)
			(unlocked yes)
			(layer "F.SilkS")
			(effects
				(font
					(size 0.762 0.762)
					(thickness 0.2286)
				)
			)
		)
		(property "Value" "0.1uF"
			(at 2.09443 2.657602 180)
			(unlocked yes)
			(layer "F.SilkS")
			(hide yes)
			(effects
				(font
					(size 1.524 1.524)
					(thickness 0.254)
				)
			)
		)
		(sheetname "USER_IO")
		(sheetfile "USER_IO.kicad_sch")
		(duplicate_pad_numbers_are_jumpers no)
		(pad "1" smd rect
			(at -0.70001 0 270)
			(size 1.1 1.05)
			(layers "F.Cu" "F.Mask" "F.Paste")
			(net "+3.3V")
		)
		(pad "2" smd rect
			(at 0.69999 0 270)
			(size 1.1 1.05)
			(layers "F.Cu" "F.Mask" "F.Paste")
			(net "GND")
		)
	)
	(footprint "Passives:SOT65P210X110-3N"
		(layer "F.Cu")
		(at 111.613595 69.0786 180)
		(property "Reference" "D8"
			(at 1.5 -2.593345 0)
			(unlocked yes)
			(layer "F.SilkS")
			(effects
				(font
					(size 0.762 0.762)
					(thickness 0.2286)
				)
				(justify left bottom)
			)
		)
		(property "Value" "BAT54SW"
			(at 1.5875 -3.88239 0)
			(unlocked yes)
			(layer "F.SilkS")
			(hide yes)
			(effects
				(font
					(size 1.524 1.524)
					(thickness 0.254)
				)
				(justify left bottom)
			)
		)
		(sheetname "PCIe_JTAG")
		(sheetfile "PCIe_JTAG.kicad_sch")
		(duplicate_pad_numbers_are_jumpers no)
		(fp_line
			(start 0.675 1.1)
			(end -0.325 1.1)
			(stroke
				(width 0.2)
				(type solid)
			)
			(layer "F.SilkS")
		)
		(fp_line
			(start 0.675 0.65)
			(end 0.675 1.1)
			(stroke
				(width 0.2)
				(type solid)
			)
			(layer "F.SilkS")
		)
		(fp_line
			(start 0.675 -1.1)
			(end 0.675 -0.65)
			(stroke
				(width 0.2)
				(type solid)
			)
			(layer "F.SilkS")
		)
		(fp_line
			(start 0.675 -1.1)
			(end -0.325 -1.1)
			(stroke
				(width 0.2)
				(type solid)
			)
			(layer "F.SilkS")
		)
		(fp_circle
			(center -1.125 -1.45)
			(end -1.125 -1.325)
			(stroke
				(width 0.25)
				(type solid)
			)
			(fill no)
			(layer "F.SilkS")
		)
		(pad "1" smd rect
			(at -1.125 -0.65 270)
			(size 0.5 0.9)
			(layers "F.Cu" "F.Mask" "F.Paste")
			(net "GND")
		)
		(pad "2" smd rect
			(at -1.125 0.65 270)
			(size 0.5 0.9)
			(layers "F.Cu" "F.Mask" "F.Paste")
			(net "+3.3V")
		)
		(pad "3" smd rect
			(at 1.125 0 270)
			(size 0.5 0.9)
			(layers "F.Cu" "F.Mask" "F.Paste")
			(net "FPGA_TDI")
		)
	)
	(footprint "Vault:CAPC1608X87X45ML20T05"
		(layer "F.Cu")
		(at 149.613595 144.1786)
		(property "Reference" "C63"
			(at -4.8 0.193345 0)
			(unlocked yes)
			(layer "F.SilkS")
			(effects
				(font
					(size 0.762 0.762)
					(thickness 0.2286)
				)
				(justify left bottom)
			)
		)
		(property "Value" "0.1uF"
			(at -0.2921 3.47599 0)
			(unlocked yes)
			(layer "F.SilkS")
			(hide yes)
			(effects
				(font
					(size 1.524 1.524)
					(thickness 0.254)
				)
				(justify left bottom)
			)
		)
		(sheetname "MAC")
		(sheetfile "MAC.kicad_sch")
		(duplicate_pad_numbers_are_jumpers no)
		(pad "1" smd rect
			(at -0.7 0 90)
			(size 1.1 1.05)
			(layers "F.Cu" "F.Mask" "F.Paste")
			(net "GND")
		)
		(pad "2" smd rect
			(at 0.7 0 90)
			(size 1.1 1.05)
			(layers "F.Cu" "F.Mask" "F.Paste")
			(net "+5.0V")
		)
	)
	(footprint "SA53:SA53"
		(layer "F.Cu")
		(at 179.238595 116.5786)
		(property "Reference" "U10"
			(at -23.0214 27.776921 0)
			(unlocked yes)
			(layer "F.SilkS")
			(effects
				(font
					(size 0.762 0.762)
					(thickness 0.2286)
				)
			)
		)
		(property "Value" "MAC-SA5X"
			(at -18.30259 28.464002 0)
			(unlocked yes)
			(layer "F.SilkS")
			(hide yes)
			(effects
				(font
					(size 1.524 1.524)
					(thickness 0.254)
				)
			)
		)
		(sheetname "MAC")
		(sheetfile "MAC.kicad_sch")
		(duplicate_pad_numbers_are_jumpers no)
		(fp_line
			(start -24.53252 -24.05)
			(end 26.26748 -24.05)
			(stroke
				(width 0.254)
				(type solid)
			)
			(layer "F.SilkS")
		)
		(fp_line
			(start -24.53252 26.75)
			(end -24.53252 -24.05)
			(stroke
				(width 0.254)
				(type solid)
			)
			(layer "F.SilkS")
		)
		(fp_line
			(start -24.53252 26.75)
			(end 26.26748 26.75)
			(stroke
				(width 0.254)
				(type solid)
			)
			(layer "F.SilkS")
		)
		(fp_line
			(start 26.26748 26.75)
			(end 26.26748 -24.05)
			(stroke
				(width 0.254)
				(type solid)
			)
			(layer "F.SilkS")
		)
		(fp_circle
			(center -15.74748 3.64128)
			(end -15.74748 3.51428)
			(stroke
				(width 0.254)
				(type solid)
			)
			(fill no)
			(layer "F.SilkS")
		)
		(pad "1" smd rect
			(at -17.16748 3.64128 90)
			(size 0.25 1.8)
			(layers "F.Cu" "F.Mask" "F.Paste")
			(net "MAC_PPS_IN1+")
		)
		(pad "2" smd rect
			(at -21.16748 3.64128 90)
			(size 0.25 1.8)
			(layers "F.Cu" "F.Mask" "F.Paste")
			(net "MAC_USB+")
		)
		(pad "3" smd rect
			(at -17.16748 3.13328 90)
			(size 0.25 1.8)
			(layers "F.Cu" "F.Mask" "F.Paste")
			(net "MAC_PPS_IN1-")
		)
		(pad "4" smd rect
			(at -21.16748 3.13328 90)
			(size 0.25 1.8)
			(layers "F.Cu" "F.Mask" "F.Paste")
			(net "MAC_USB-")
		)
		(pad "5" smd rect
			(at -17.16748 2.62528 90)
			(size 0.25 1.8)
			(layers "F.Cu" "F.Mask" "F.Paste")
			(net "MAC_PPS_IN0+")
		)
		(pad "6" smd rect
			(at -21.16748 2.62528 90)
			(size 0.25 1.8)
			(layers "F.Cu" "F.Mask" "F.Paste")
			(net "MAC_USB_PWR")
		)
		(pad "7" smd rect
			(at -17.16748 2.11728 90)
			(size 0.25 1.8)
			(layers "F.Cu" "F.Mask" "F.Paste")
			(net "MAC_PPS_IN0-")
		)
		(pad "8" smd rect
			(at -21.16748 2.11728 90)
			(size 0.25 1.8)
			(layers "F.Cu" "F.Mask" "F.Paste")
			(net "GND")
		)
		(pad "9" smd rect
			(at -17.16748 1.60928 90)
			(size 0.25 1.8)
			(layers "F.Cu" "F.Mask" "F.Paste")
			(net "GND")
		)
		(pad "10" smd rect
			(at -21.16748 1.60928 90)
			(size 0.25 1.8)
			(layers "F.Cu" "F.Mask" "F.Paste")
		)
		(pad "11" smd rect
			(at -17.16748 1.10128 90)
			(size 0.25 1.8)
			(layers "F.Cu" "F.Mask" "F.Paste")
		)
		(pad "12" smd rect
			(at -21.16748 1.10128 90)
			(size 0.25 1.8)
			(layers "F.Cu" "F.Mask" "F.Paste")
		)
		(pad "13" smd rect
			(at -17.16748 0.59328 90)
			(size 0.25 1.8)
			(layers "F.Cu" "F.Mask" "F.Paste")
		)
		(pad "14" smd rect
			(at -21.16748 0.59328 90)
			(size 0.25 1.8)
			(layers "F.Cu" "F.Mask" "F.Paste")
		)
		(pad "15" smd rect
			(at -17.16748 0.08528 90)
			(size 0.25 1.8)
			(layers "F.Cu" "F.Mask" "F.Paste")
			(net "GND")
		)
		(pad "16" smd rect
			(at -21.16748 0.08528 90)
			(size 0.25 1.8)
			(layers "F.Cu" "F.Mask" "F.Paste")
		)
		(pad "17" smd rect
			(at -17.16748 -0.42272 90)
			(size 0.25 1.8)
			(layers "F.Cu" "F.Mask" "F.Paste")
			(net "MAC_PPS_OUT+")
		)
		(pad "18" smd rect
			(at -21.16748 -0.42272 90)
			(size 0.25 1.8)
			(layers "F.Cu" "F.Mask" "F.Paste")
		)
		(pad "19" smd rect
			(at -17.16748 -0.93072 90)
			(size 0.25 1.8)
			(layers "F.Cu" "F.Mask" "F.Paste")
			(net "MAC_PPS_OUT-")
		)
		(pad "20" smd rect
			(at -21.16748 -0.93072 90)
			(size 0.25 1.8)
			(layers "F.Cu" "F.Mask" "F.Paste")
			(net "MAC_ALARM")
		)
		(pad "P1" thru_hole circle
			(at 21.16748 21.65 270)
			(size 1.905 1.905)
			(drill 1.27)
			(layers "*.Cu" "*.Mask")
			(remove_unused_layers no)
			(net "MAC_FREQ_CTRL")
			(thermal_bridge_angle 90)
		)
		(pad "P2" thru_hole circle
			(at 21.16748 1.35 270)
			(size 1.905 1.905)
			(drill 1.27)
			(layers "*.Cu" "*.Mask")
			(remove_unused_layers no)
			(net "GND")
			(thermal_bridge_angle 90)
		)
		(pad "P3" thru_hole circle
			(at 21.16748 -18.95 270)
			(size 1.905 1.905)
			(drill 1.27)
			(layers "*.Cu" "*.Mask")
			(remove_unused_layers no)
			(net "MAC_RF_OUT")
			(thermal_bridge_angle 90)
		)
		(pad "P4" thru_hole circle
			(at -19.43252 -18.95 270)
			(size 1.905 1.905)
			(drill 1.27)
			(layers "*.Cu" "*.Mask")
			(remove_unused_layers no)
			(net "GND")
			(thermal_bridge_angle 90)
		)
		(pad "P5" thru_hole circle
			(at -19.43252 21.65 270)
			(size 1.905 1.905)
			(drill 1.27)
			(layers "*.Cu" "*.Mask")
			(remove_unused_layers no)
			(net "+5.0V")
			(thermal_bridge_angle 90)
		)
		(pad "P6" thru_hole circle
			(at -17.33251 -21.65 270)
			(size 1.905 1.905)
			(drill 1.27)
			(layers "*.Cu" "*.Mask")
			(remove_unused_layers no)
			(net "MAC_BITE")
			(thermal_bridge_angle 90)
		)
		(pad "P7" thru_hole circle
			(at -14.33252 -21.65 270)
			(size 1.905 1.905)
			(drill 1.27)
			(layers "*.Cu" "*.Mask")
			(remove_unused_layers no)
			(net "MAC_RX")
			(thermal_bridge_angle 90)
		)
		(pad "P8" thru_hole circle
			(at -11.33252 -21.65 270)
			(size 1.905 1.905)
			(drill 1.27)
			(layers "*.Cu" "*.Mask")
			(remove_unused_layers no)
			(net "MAC_TX")
			(thermal_bridge_angle 90)
		)
		(zone
			(layer "F.Cu")
			(hatch edge 0.5)
			(connect_pads
				(clearance 0)
			)
			(min_thickness 0.25)
			(keepout
				(tracks allowed)
				(vias allowed)
				(pads allowed)
				(copperpour not_allowed)
				(footprints allowed)
			)
			(placement
				(enabled no)
				(sheetname "")
			)
			(fill
				(thermal_gap 0.5)
				(thermal_bridge_width 0.5)
				(island_removal_mode 0)
			)
			(polygon
				(pts
					(xy 163.738595 113.0786) (xy 163.738595 123.0786) (xy 156.238595 123.0786) (xy 156.238595 113.0786)
				)
			)
		)
		(zone
			(layer "F.Cu")
			(hatch edge 0.5)
			(connect_pads
				(clearance 0)
			)
			(min_thickness 0.25)
			(keepout
				(tracks allowed)
				(vias allowed)
				(pads allowed)
				(copperpour not_allowed)
				(footprints allowed)
			)
			(placement
				(enabled no)
				(sheetname "")
			)
			(fill
				(thermal_gap 0.5)
				(thermal_bridge_width 0.5)
				(island_removal_mode 0)
			)
			(polygon
				(pts
					(xy 169.738595 99.0786) (xy 158.238595 99.0786) (xy 158.238595 93.0786) (xy 169.738595 93.0786)
				)
			)
		)
	)
	(footprint "Vault:RESC1608X55X25LL10T15"
		(layer "F.Cu")
		(at 190.738595 90.0786)
		(property "Reference" "R11"
			(at -2.771395 0.026921 0)
			(unlocked yes)
			(layer "F.SilkS")
			(effects
				(font
					(size 0.762 0.762)
					(thickness 0.2286)
				)
			)
		)
		(property "Value" "4.7K"
			(at -2.657602 2.60264 270)
			(unlocked yes)
			(layer "F.SilkS")
			(hide yes)
			(effects
				(font
					(size 1.524 1.524)
					(thickness 0.254)
				)
			)
		)
		(sheetname "MAC")
		(sheetfile "MAC.kicad_sch")
		(duplicate_pad_numbers_are_jumpers no)
		(pad "1" smd rect
			(at -0.65 0 90)
			(size 0.8 0.6)
			(layers "F.Cu" "F.Mask" "F.Paste")
			(net "GND")
		)
		(pad "2" smd rect
			(at 0.65 0 90)
			(size 0.8 0.6)
			(layers "F.Cu" "F.Mask" "F.Paste")
			(net "FPGA_MAC_PPS_IN0-")
		)
	)
	(footprint "Passives:FUSM1608X60N"
		(layer "F.Cu")
		(at 107.888595 144.1886 -90)
		(property "Reference" "F1"
			(at -1.61 -0.193345 90)
			(unlocked yes)
			(layer "F.SilkS")
			(effects
				(font
					(size 0.762 0.762)
					(thickness 0.2286)
				)
				(justify left bottom)
			)
		)
		(property "Value" "FUSE_0603_2.00A"
			(at 5.08039 2.1929 0)
			(unlocked yes)
			(layer "F.SilkS")
			(hide yes)
			(effects
				(font
					(size 1.524 1.524)
					(thickness 0.254)
				)
				(justify left bottom)
			)
		)
		(sheetname "POWER")
		(sheetfile "POWER.kicad_sch")
		(duplicate_pad_numbers_are_jumpers no)
		(fp_line
			(start 0 0.5)
			(end 0 -0.5)
			(stroke
				(width 0.1524)
				(type solid)
			)
			(layer "F.SilkS")
		)
		(pad "1" smd rect
			(at -0.69 0)
			(size 1 0.72)
			(layers "F.Cu" "F.Mask" "F.Paste")
			(net "NetD3_1")
		)
		(pad "2" smd rect
			(at 0.69 0)
			(size 1 0.72)
			(layers "F.Cu" "F.Mask" "F.Paste")
			(net "+12V")
		)
	)
	(footprint "Vault:TECO-1909763-1_V"
		(layer "F.Cu")
		(at 71.838595 137.5786 90)
		(property "Reference" "J10"
			(at -1.0214 2.926931 90)
			(unlocked yes)
			(layer "F.SilkS")
			(effects
				(font
					(size 0.762 0.762)
					(thickness 0.2286)
				)
			)
		)
		(property "Value" "1909763-1"
			(at 4.608085 3.749802 90)
			(unlocked yes)
			(layer "F.SilkS")
			(hide yes)
			(effects
				(font
					(size 1.524 1.524)
					(thickness 0.254)
				)
			)
		)
		(sheetname "USER_IO")
		(sheetfile "USER_IO.kicad_sch")
		(duplicate_pad_numbers_are_jumpers no)
		(fp_line
			(start -0.55 -1.3)
			(end 0.55 -1.3)
			(stroke
				(width 0.2)
				(type solid)
			)
			(layer "F.SilkS")
		)
		(fp_circle
			(center -1.778 1.65)
			(end -1.653 1.65)
			(stroke
				(width 0.25)
				(type solid)
			)
			(fill no)
			(layer "F.SilkS")
		)
		(pad "1" smd rect
			(at -1.475 0 90)
			(size 1.05 2.2)
			(layers "F.Cu" "F.Mask" "F.Paste")
			(net "GND")
		)
		(pad "2" smd rect
			(at 0 1.525 90)
			(size 1 1.05)
			(layers "F.Cu" "F.Mask" "F.Paste")
			(net "NetAN4_1")
		)
		(pad "3" smd rect
			(at 1.475 0 90)
			(size 1.05 2.2)
			(layers "F.Cu" "F.Mask" "F.Paste")
			(net "GND")
		)
	)
	(footprint "Passives:DIOM1608X06N"
		(layer "F.Cu")
		(at 215.788595 88.1786 -90)
		(property "Reference" "D4"
			(at -2 -0.393345 90)
			(unlocked yes)
			(layer "F.SilkS")
			(effects
				(font
					(size 0.762 0.762)
					(thickness 0.2286)
				)
				(justify left bottom)
			)
		)
		(property "Value" "RED"
			(at 3.22199 1.4097 0)
			(unlocked yes)
			(layer "F.SilkS")
			(hide yes)
			(effects
				(font
					(size 1.524 1.524)
					(thickness 0.254)
				)
				(justify left bottom)
			)
		)
		(sheetname "POWER")
		(sheetfile "POWER.kicad_sch")
		(duplicate_pad_numbers_are_jumpers no)
		(fp_circle
			(center -1.275 -0.725)
			(end -1.325 -0.725)
			(stroke
				(width 0.1)
				(type solid)
			)
			(fill no)
			(layer "F.SilkS")
		)
		(pad "1" smd rect
			(at -0.725 0)
			(size 0.85 1)
			(layers "F.Cu" "F.Mask" "F.Paste")
			(net "NetD4_1")
		)
		(pad "2" smd rect
			(at 0.725 0)
			(size 0.85 1)
			(layers "F.Cu" "F.Mask" "F.Paste")
			(net "+3.3V")
		)
	)
	(footprint "Vault:CAPC1608X87X45ML20T05"
		(layer "F.Cu")
		(at 130.988595 89.0786 -90)
		(property "Reference" "C25"
			(at -2.723069 -0.2286 0)
			(unlocked yes)
			(layer "F.SilkS")
			(effects
				(font
					(size 0.762 0.762)
					(thickness 0.2286)
				)
			)
		)
		(property "Value" "0.1uF"
			(at 2.09443 2.657602 270)
			(unlocked yes)
			(layer "F.SilkS")
			(hide yes)
			(effects
				(font
					(size 1.524 1.524)
					(thickness 0.254)
				)
			)
		)
		(sheetname "GPS_IMU_SENSORS")
		(sheetfile "GPS_IMU_SENSORS.kicad_sch")
		(duplicate_pad_numbers_are_jumpers no)
		(pad "1" smd rect
			(at -0.7 0)
			(size 1.1 1.05)
			(layers "F.Cu" "F.Mask" "F.Paste")
			(net "GND")
		)
		(pad "2" smd rect
			(at 0.7 0)
			(size 1.1 1.05)
			(layers "F.Cu" "F.Mask" "F.Paste")
			(net "+3.3V")
		)
	)
	(footprint "Vault:CAPC1608X87X45ML20T05"
		(layer "F.Cu")
		(at 86.488595 113.8286)
		(property "Reference" "C27"
			(at -2.79344 0.114181 0)
			(unlocked yes)
			(layer "F.SilkS")
			(effects
				(font
					(size 0.762 0.762)
					(thickness 0.2286)
				)
			)
		)
		(property "Value" "0.1uF"
			(at 2.09443 2.657602 0)
			(unlocked yes)
			(layer "F.SilkS")
			(hide yes)
			(effects
				(font
					(size 1.524 1.524)
					(thickness 0.254)
				)
			)
		)
		(sheetname "USER_IO")
		(sheetfile "USER_IO.kicad_sch")
		(duplicate_pad_numbers_are_jumpers no)
		(pad "1" smd rect
			(at -0.7 0 90)
			(size 1.1 1.05)
			(layers "F.Cu" "F.Mask" "F.Paste")
			(net "+3.3V")
		)
		(pad "2" smd rect
			(at 0.7 0 90)
			(size 1.1 1.05)
			(layers "F.Cu" "F.Mask" "F.Paste")
			(net "GND")
		)
	)
	(footprint "Vault:RESC1608X55X30NL15T15"
		(layer "F.Cu")
		(at 85.088595 56.9786 90)
		(property "Reference" "R29"
			(at -1.2 -1.206655 90)
			(unlocked yes)
			(layer "F.SilkS")
			(effects
				(font
					(size 0.762 0.762)
					(thickness 0.2286)
				)
				(justify left bottom)
			)
		)
		(property "Value" "200 OHM"
			(at -3.72999 -0.4445 0)
			(unlocked yes)
			(layer "F.SilkS")
			(hide yes)
			(effects
				(font
					(size 1.524 1.524)
					(thickness 0.254)
				)
				(justify left bottom)
			)
		)
		(sheetname "USER_IO")
		(sheetfile "USER_IO.kicad_sch")
		(duplicate_pad_numbers_are_jumpers no)
		(pad "1" smd rect
			(at -0.675 0 180)
			(size 0.95 0.8)
			(layers "F.Cu" "F.Mask" "F.Paste")
			(net "LED3")
		)
		(pad "2" smd rect
			(at 0.675 0 180)
			(size 0.95 0.8)
			(layers "F.Cu" "F.Mask" "F.Paste")
			(net "NetD13_1")
		)
	)
	(footprint "Vault:CAPC1608X87X45ML20T05"
		(layer "F.Cu")
		(at 144.238595 91.3786 90)
		(property "Reference" "C33"
			(at 3.2786 0.026931 90)
			(unlocked yes)
			(layer "F.SilkS")
			(effects
				(font
					(size 0.762 0.762)
					(thickness 0.2286)
				)
			)
		)
		(property "Value" "0.1uF"
			(at 2.09443 2.657602 90)
			(unlocked yes)
			(layer "F.SilkS")
			(hide yes)
			(effects
				(font
					(size 1.524 1.524)
					(thickness 0.254)
				)
			)
		)
		(sheetname "GPS_IMU_SENSORS")
		(sheetfile "GPS_IMU_SENSORS.kicad_sch")
		(duplicate_pad_numbers_are_jumpers no)
		(pad "1" smd rect
			(at -0.7 0 180)
			(size 1.1 1.05)
			(layers "F.Cu" "F.Mask" "F.Paste")
			(net "GND")
		)
		(pad "2" smd rect
			(at 0.7 0 180)
			(size 1.1 1.05)
			(layers "F.Cu" "F.Mask" "F.Paste")
			(net "+3.3V")
		)
	)
	(footprint "IntegratedCircuits:SOIC127P600X175-8N"
		(layer "F.Cu")
		(at 229.553595 110.8946)
		(property "Reference" "U1"
			(at -4.415 -2.972655 0)
			(unlocked yes)
			(layer "F.SilkS")
			(effects
				(font
					(size 0.762 0.762)
					(thickness 0.2286)
				)
				(justify left bottom)
			)
		)
		(property "Value" "MP1482DS-LF"
			(at -6.9469 5.15239 0)
			(unlocked yes)
			(layer "F.SilkS")
			(hide yes)
			(effects
				(font
					(size 1.524 1.524)
					(thickness 0.254)
				)
				(justify left bottom)
			)
		)
		(sheetname "POWER")
		(sheetfile "POWER.kicad_sch")
		(duplicate_pad_numbers_are_jumpers no)
		(fp_line
			(start -3.4 -2.5)
			(end 2 -2.5)
			(stroke
				(width 0.12)
				(type solid)
			)
			(layer "F.SilkS")
		)
		(fp_line
			(start -2 2.5)
			(end 2 2.5)
			(stroke
				(width 0.12)
				(type solid)
			)
			(layer "F.SilkS")
		)
		(pad "1" smd rect
			(at -2.475 -1.905)
			(size 1.97 0.57)
			(layers "F.Cu" "F.Mask" "F.Paste")
			(net "NetC4_1")
		)
		(pad "2" smd rect
			(at -2.475 -0.635)
			(size 1.97 0.57)
			(layers "F.Cu" "F.Mask" "F.Paste")
			(net "+12V")
		)
		(pad "3" smd rect
			(at -2.475 0.635)
			(size 1.97 0.57)
			(layers "F.Cu" "F.Mask" "F.Paste")
			(net "NetC4_2")
		)
		(pad "4" smd rect
			(at -2.475 1.905)
			(size 1.97 0.57)
			(layers "F.Cu" "F.Mask" "F.Paste")
			(net "GND")
		)
		(pad "5" smd rect
			(at 2.475 1.905)
			(size 1.97 0.57)
			(layers "F.Cu" "F.Mask" "F.Paste")
			(net "NetR4_2")
		)
		(pad "6" smd rect
			(at 2.475 0.635)
			(size 1.97 0.57)
			(layers "F.Cu" "F.Mask" "F.Paste")
			(net "NetC20_2")
		)
		(pad "7" smd rect
			(at 2.475 -0.635)
			(size 1.97 0.57)
			(layers "F.Cu" "F.Mask" "F.Paste")
			(net "NetR2_1")
		)
		(pad "8" smd rect
			(at 2.475 -1.905)
			(size 1.97 0.57)
			(layers "F.Cu" "F.Mask" "F.Paste")
			(net "NetC19_2")
		)
	)
	(footprint "Vault:CAPC1608X87X45ML20T05"
		(layer "F.Cu")
		(at 127.238595 80.0786 90)
		(property "Reference" "C61"
			(at -1.25 3.593345 90)
			(unlocked yes)
			(layer "F.SilkS")
			(effects
				(font
					(size 0.762 0.762)
					(thickness 0.2286)
				)
				(justify left bottom)
			)
		)
		(property "Value" "0.1uF"
			(at -3.47599 -0.2921 0)
			(unlocked yes)
			(layer "F.SilkS")
			(hide yes)
			(effects
				(font
					(size 1.524 1.524)
					(thickness 0.254)
				)
				(justify left bottom)
			)
		)
		(sheetname "GPS_IMU_SENSORS")
		(sheetfile "GPS_IMU_SENSORS.kicad_sch")
		(duplicate_pad_numbers_are_jumpers no)
		(pad "1" smd rect
			(at -0.7 0 180)
			(size 1.1 1.05)
			(layers "F.Cu" "F.Mask" "F.Paste")
			(net "GND")
		)
		(pad "2" smd rect
			(at 0.7 0 180)
			(size 1.1 1.05)
			(layers "F.Cu" "F.Mask" "F.Paste")
			(net "+5.0V")
		)
	)
	(footprint "Capacitors:CAPC1608X10N"
		(layer "F.Cu")
		(at 224.092595 110.1326 -90)
		(property "Reference" "C4"
			(at -2.029 -0.364345 90)
			(unlocked yes)
			(layer "F.SilkS")
			(effects
				(font
					(size 0.762 0.762)
					(thickness 0.2286)
				)
				(justify left bottom)
			)
		)
		(property "Value" "CAP_0603_0.01UF_50V"
			(at 3.14579 4.7879 0)
			(unlocked yes)
			(layer "F.SilkS")
			(hide yes)
			(effects
				(font
					(size 1.524 1.524)
					(thickness 0.254)
				)
				(justify left bottom)
			)
		)
		(sheetname "POWER")
		(sheetfile "POWER.kicad_sch")
		(duplicate_pad_numbers_are_jumpers no)
		(fp_line
			(start 0.635 0.7112)
			(end -0.635 0.7112)
			(stroke
				(width 0.1524)
				(type solid)
			)
			(layer "F.SilkS")
		)
		(fp_line
			(start 0.635 -0.7112)
			(end -0.635 -0.7112)
			(stroke
				(width 0.1524)
				(type solid)
			)
			(layer "F.SilkS")
		)
		(pad "1" smd rect
			(at -0.8 0)
			(size 0.95 1)
			(layers "F.Cu" "F.Mask" "F.Paste")
			(net "NetC4_1")
		)
		(pad "2" smd rect
			(at 0.8 0)
			(size 0.95 1)
			(layers "F.Cu" "F.Mask" "F.Paste")
			(net "NetC4_2")
		)
	)
	(footprint "Vault:CAPC1608X87X45ML20T05"
		(layer "F.Cu")
		(at 86.288595 119.5786 180)
		(property "Reference" "C29"
			(at -2.9286 -0.026931 360)
			(unlocked yes)
			(layer "F.SilkS")
			(effects
				(font
					(size 0.762 0.762)
					(thickness 0.2286)
				)
			)
		)
		(property "Value" "0.1uF"
			(at 2.09443 2.657602 180)
			(unlocked yes)
			(layer "F.SilkS")
			(hide yes)
			(effects
				(font
					(size 1.524 1.524)
					(thickness 0.254)
				)
			)
		)
		(sheetname "USER_IO")
		(sheetfile "USER_IO.kicad_sch")
		(duplicate_pad_numbers_are_jumpers no)
		(pad "1" smd rect
			(at -0.7 0 270)
			(size 1.1 1.05)
			(layers "F.Cu" "F.Mask" "F.Paste")
			(net "+3.3V")
		)
		(pad "2" smd rect
			(at 0.7 0 270)
			(size 1.1 1.05)
			(layers "F.Cu" "F.Mask" "F.Paste")
			(net "GND")
		)
	)
	(footprint "Vault:CAPC1608X87X45ML20T05"
		(layer "F.Cu")
		(at 227.648595 115.4666)
		(property "Reference" "C18"
			(at 1.74 0.905345 0)
			(unlocked yes)
			(layer "F.SilkS")
			(effects
				(font
					(size 0.762 0.762)
					(thickness 0.2286)
				)
				(justify left bottom)
			)
		)
		(property "Value" "0.1uF"
			(at 3.0099 9.82599 0)
			(unlocked yes)
			(layer "F.SilkS")
			(hide yes)
			(effects
				(font
					(size 1.524 1.524)
					(thickness 0.254)
				)
				(justify left bottom)
			)
		)
		(sheetname "POWER")
		(sheetfile "POWER.kicad_sch")
		(duplicate_pad_numbers_are_jumpers no)
		(pad "1" smd rect
			(at -0.7 0 90)
			(size 1.1 1.05)
			(layers "F.Cu" "F.Mask" "F.Paste")
			(net "GND")
		)
		(pad "2" smd rect
			(at 0.7 0 90)
			(size 1.1 1.05)
			(layers "F.Cu" "F.Mask" "F.Paste")
			(net "+5.0V")
		)
	)
	(footprint "Resistors:RESC2012X50N"
		(layer "F.Cu")
		(at 101.988595 65.3286 90)
		(property "Reference" "R19"
			(at -1.25 -5.156655 90)
			(unlocked yes)
			(layer "F.SilkS")
			(effects
				(font
					(size 0.762 0.762)
					(thickness 0.2286)
				)
				(justify left bottom)
			)
		)
		(property "Value" "CRCW080533R0FKEA"
			(at -3.52679 -1.5875 0)
			(unlocked yes)
			(layer "F.SilkS")
			(hide yes)
			(effects
				(font
					(size 1.524 1.524)
					(thickness 0.254)
				)
				(justify left bottom)
			)
		)
		(sheetname "PCIe_JTAG")
		(sheetfile "PCIe_JTAG.kicad_sch")
		(duplicate_pad_numbers_are_jumpers no)
		(fp_line
			(start 0 -0.762)
			(end 0 0.762)
			(stroke
				(width 0.1524)
				(type solid)
			)
			(layer "F.SilkS")
		)
		(pad "1" smd rect
			(at -1 0 180)
			(size 1.45 0.95)
			(layers "F.Cu" "F.Mask" "F.Paste")
			(net "FPGA_TDO")
		)
		(pad "2" smd rect
			(at 1 0 180)
			(size 1.45 0.95)
			(layers "F.Cu" "F.Mask" "F.Paste")
			(net "NetR19_2")
		)
	)
	(footprint "Vault:CAPC1608X87X45ML20T05"
		(layer "F.Cu")
		(at 214.059595 105.4336)
		(property "Reference" "C21"
			(at -4.371 0.538345 0)
			(unlocked yes)
			(layer "F.SilkS")
			(effects
				(font
					(size 0.762 0.762)
					(thickness 0.2286)
				)
				(justify left bottom)
			)
		)
		(property "Value" "0.1uF"
			(at 21.5011 -18.06321 0)
			(unlocked yes)
			(layer "F.SilkS")
			(hide yes)
			(effects
				(font
					(size 1.524 1.524)
					(thickness 0.254)
				)
				(justify left bottom)
			)
		)
		(sheetname "POWER")
		(sheetfile "POWER.kicad_sch")
		(duplicate_pad_numbers_are_jumpers no)
		(pad "1" smd rect
			(at -0.7 0 90)
			(size 1.1 1.05)
			(layers "F.Cu" "F.Mask" "F.Paste")
			(net "GND")
		)
		(pad "2" smd rect
			(at 0.7 0 90)
			(size 1.1 1.05)
			(layers "F.Cu" "F.Mask" "F.Paste")
			(net "NetC21_2")
		)
	)
	(footprint "Vault:RESC1608X55X25NL10T15"
		(layer "F.Cu")
		(at 83.238595 123.5786 -90)
		(property "Reference" "R15"
			(at 2.2714 -0.026931 90)
			(unlocked yes)
			(layer "F.SilkS")
			(effects
				(font
					(size 0.762 0.762)
					(thickness 0.2286)
				)
			)
		)
		(property "Value" "49.9R"
			(at 2.835402 -4.98946 0)
			(unlocked yes)
			(layer "F.SilkS")
			(hide yes)
			(effects
				(font
					(size 1.524 1.524)
					(thickness 0.254)
				)
			)
		)
		(sheetname "USER_IO")
		(sheetfile "USER_IO.kicad_sch")
		(duplicate_pad_numbers_are_jumpers no)
		(pad "1" smd rect
			(at -0.7 0)
			(size 0.9 0.7)
			(layers "F.Cu" "F.Mask" "F.Paste")
			(net "NetR15_1")
		)
		(pad "2" smd rect
			(at 0.7 0)
			(size 0.9 0.7)
			(layers "F.Cu" "F.Mask" "F.Paste")
			(net "NetAN3_1")
		)
	)
	(footprint "Capacitors:CAPC2012X14N"
		(layer "F.Cu")
		(at 133.488595 75.1786 -90)
		(property "Reference" "C58"
			(at 4.4 -0.843345 90)
			(unlocked yes)
			(layer "F.SilkS")
			(effects
				(font
					(size 0.762 0.762)
					(thickness 0.2286)
				)
				(justify left bottom)
			)
		)
		(property "Value" "CAP_0805_10UF_25V"
			(at 5.32679 1.5875 0)
			(unlocked yes)
			(layer "F.SilkS")
			(hide yes)
			(effects
				(font
					(size 1.524 1.524)
					(thickness 0.254)
				)
				(justify left bottom)
			)
		)
		(sheetname "GPS_IMU_SENSORS")
		(sheetfile "GPS_IMU_SENSORS.kicad_sch")
		(duplicate_pad_numbers_are_jumpers no)
		(fp_line
			(start 0.762 0.9652)
			(end -0.762 0.9652)
			(stroke
				(width 0.1524)
				(type solid)
			)
			(layer "F.SilkS")
		)
		(fp_line
			(start 0.762 -0.9652)
			(end -0.762 -0.9652)
			(stroke
				(width 0.1524)
				(type solid)
			)
			(layer "F.SilkS")
		)
		(pad "1" smd rect
			(at -0.9 0)
			(size 1.45 1.15)
			(layers "F.Cu" "F.Mask" "F.Paste")
			(net "+3.3V")
		)
		(pad "2" smd rect
			(at 0.9 0)
			(size 1.45 1.15)
			(layers "F.Cu" "F.Mask" "F.Paste")
			(net "GND")
		)
	)
	(footprint "Passives:SODFL370X135-2N"
		(layer "F.Cu")
		(at 105.688595 145.2786 -90)
		(property "Reference" "D3"
			(at -2.6 -0.393345 90)
			(unlocked yes)
			(layer "F.SilkS")
			(effects
				(font
					(size 0.762 0.762)
					(thickness 0.2286)
				)
				(justify left bottom)
			)
		)
		(property "Value" "DFLZ39-TP"
			(at 3.62839 2.0955 0)
			(unlocked yes)
			(layer "F.SilkS")
			(hide yes)
			(effects
				(font
					(size 1.524 1.524)
					(thickness 0.254)
				)
				(justify left bottom)
			)
		)
		(sheetname "POWER")
		(sheetfile "POWER.kicad_sch")
		(duplicate_pad_numbers_are_jumpers no)
		(fp_line
			(start -1.55 0.95)
			(end -1.55 0.825)
			(stroke
				(width 0.2)
				(type solid)
			)
			(layer "F.SilkS")
		)
		(fp_line
			(start 1.55 0.95)
			(end -1.55 0.95)
			(stroke
				(width 0.2)
				(type solid)
			)
			(layer "F.SilkS")
		)
		(fp_line
			(start 1.55 0.95)
			(end 1.55 0.825)
			(stroke
				(width 0.2)
				(type solid)
			)
			(layer "F.SilkS")
		)
		(fp_line
			(start -1.55 -0.825)
			(end -1.55 -0.95)
			(stroke
				(width 0.2)
				(type solid)
			)
			(layer "F.SilkS")
		)
		(fp_line
			(start 1.55 -0.825)
			(end 1.55 -0.95)
			(stroke
				(width 0.2)
				(type solid)
			)
			(layer "F.SilkS")
		)
		(fp_line
			(start 1.55 -0.95)
			(end -1.55 -0.95)
			(stroke
				(width 0.2)
				(type solid)
			)
			(layer "F.SilkS")
		)
		(fp_circle
			(center -2.05 -0.825)
			(end -2.1 -0.825)
			(stroke
				(width 0.1)
				(type solid)
			)
			(fill no)
			(layer "F.SilkS")
		)
		(pad "1" smd rect
			(at -1.825 0)
			(size 1.05 0.65)
			(layers "F.Cu" "F.Mask" "F.Paste")
			(net "NetD3_1")
		)
		(pad "2" smd rect
			(at 1.825 0)
			(size 1.05 0.65)
			(layers "F.Cu" "F.Mask" "F.Paste")
			(net "+12V_PCIE")
		)
	)
	(footprint "Vault:CAPC1608X87X45ML20T05"
		(layer "F.Cu")
		(at 227.648595 116.8636)
		(property "Reference" "C17"
			(at 1.74 0.708345 0)
			(unlocked yes)
			(layer "F.SilkS")
			(effects
				(font
					(size 0.762 0.762)
					(thickness 0.2286)
				)
				(justify left bottom)
			)
		)
		(property "Value" "0.1uF"
			(at 1.6129 8.42899 0)
			(unlocked yes)
			(layer "F.SilkS")
			(hide yes)
			(effects
				(font
					(size 1.524 1.524)
					(thickness 0.254)
				)
				(justify left bottom)
			)
		)
		(sheetname "POWER")
		(sheetfile "POWER.kicad_sch")
		(duplicate_pad_numbers_are_jumpers no)
		(pad "1" smd rect
			(at -0.7 0 90)
			(size 1.1 1.05)
			(layers "F.Cu" "F.Mask" "F.Paste")
			(net "GND")
		)
		(pad "2" smd rect
			(at 0.7 0 90)
			(size 1.1 1.05)
			(layers "F.Cu" "F.Mask" "F.Paste")
			(net "+5.0V")
		)
	)
	(footprint "Vault:RESC1608X55X30NL15T15"
		(layer "F.Cu")
		(at 118.738595 90.5786 90)
		(property "Reference" "R27"
			(at 3.2286 0.026931 90)
			(unlocked yes)
			(layer "F.SilkS")
			(effects
				(font
					(size 0.762 0.762)
					(thickness 0.2286)
				)
			)
		)
		(property "Value" "4.7K"
			(at -3.114802 2.39944 0)
			(unlocked yes)
			(layer "F.SilkS")
			(hide yes)
			(effects
				(font
					(size 1.524 1.524)
					(thickness 0.254)
				)
			)
		)
		(sheetname "GPS_IMU_SENSORS")
		(sheetfile "GPS_IMU_SENSORS.kicad_sch")
		(duplicate_pad_numbers_are_jumpers no)
		(pad "1" smd rect
			(at -0.75 0 180)
			(size 0.95 0.95)
			(layers "F.Cu" "F.Mask" "F.Paste")
			(net "SCL")
		)
		(pad "2" smd rect
			(at 0.75 0 180)
			(size 0.95 0.95)
			(layers "F.Cu" "F.Mask" "F.Paste")
			(net "+3.3V")
		)
	)
	(footprint "Vault:RESC1608X55X25NL10T15"
		(layer "F.Cu")
		(at 183.738595 89.0786 -90)
		(property "Reference" "R13"
			(at -2.7286 -0.026931 90)
			(unlocked yes)
			(layer "F.SilkS")
			(effects
				(font
					(size 0.762 0.762)
					(thickness 0.2286)
				)
			)
		)
		(property "Value" "49.9R"
			(at -2.911602 3.21199 180)
			(unlocked yes)
			(layer "F.SilkS")
			(hide yes)
			(effects
				(font
					(size 1.524 1.524)
					(thickness 0.254)
				)
			)
		)
		(sheetname "MAC")
		(sheetfile "MAC.kicad_sch")
		(duplicate_pad_numbers_are_jumpers no)
		(pad "1" smd rect
			(at -0.7 0)
			(size 0.9 0.7)
			(layers "F.Cu" "F.Mask" "F.Paste")
			(net "NetR13_1")
		)
		(pad "2" smd rect
			(at 0.7 0)
			(size 0.9 0.7)
			(layers "F.Cu" "F.Mask" "F.Paste")
			(net "FPGA_MAC_PPS_OUT-")
		)
	)
	(footprint "Resistors:RESC1608X50N"
		(layer "F.Cu")
		(at 210.988595 100.5786 -90)
		(property "Reference" "R9"
			(at -2.427 -0.395345 90)
			(unlocked yes)
			(layer "F.SilkS")
			(effects
				(font
					(size 0.762 0.762)
					(thickness 0.2286)
				)
				(justify left bottom)
			)
		)
		(property "Value" "ERJ-3EKF2201V"
			(at -8.25881 -27.9527 0)
			(unlocked yes)
			(layer "F.SilkS")
			(hide yes)
			(effects
				(font
					(size 1.524 1.524)
					(thickness 0.254)
				)
				(justify left bottom)
			)
		)
		(sheetname "POWER")
		(sheetfile "POWER.kicad_sch")
		(duplicate_pad_numbers_are_jumpers no)
		(fp_line
			(start 0 0.5)
			(end 0 -0.5)
			(stroke
				(width 0.1524)
				(type solid)
			)
			(layer "F.SilkS")
		)
		(pad "1" smd rect
			(at -0.69 0)
			(size 1 0.72)
			(layers "F.Cu" "F.Mask" "F.Paste")
			(net "GND")
		)
		(pad "2" smd rect
			(at 0.69 0)
			(size 1 0.72)
			(layers "F.Cu" "F.Mask" "F.Paste")
			(net "NetC22_1")
		)
	)
	(footprint "Resistors:RESC2012X50N"
		(layer "F.Cu")
		(at 109.738595 65.3286 90)
		(property "Reference" "R21"
			(at -1.25 -1.406655 90)
			(unlocked yes)
			(layer "F.SilkS")
			(effects
				(font
					(size 0.762 0.762)
					(thickness 0.2286)
				)
				(justify left bottom)
			)
		)
		(property "Value" "CRCW080533R0FKEA"
			(at -3.52679 -1.5875 0)
			(unlocked yes)
			(layer "F.SilkS")
			(hide yes)
			(effects
				(font
					(size 1.524 1.524)
					(thickness 0.254)
				)
				(justify left bottom)
			)
		)
		(sheetname "PCIe_JTAG")
		(sheetfile "PCIe_JTAG.kicad_sch")
		(duplicate_pad_numbers_are_jumpers no)
		(fp_line
			(start 0 -0.762)
			(end 0 0.762)
			(stroke
				(width 0.1524)
				(type solid)
			)
			(layer "F.SilkS")
		)
		(pad "1" smd rect
			(at -1 0 180)
			(size 1.45 0.95)
			(layers "F.Cu" "F.Mask" "F.Paste")
			(net "FPGA_TDI")
		)
		(pad "2" smd rect
			(at 1 0 180)
			(size 1.45 0.95)
			(layers "F.Cu" "F.Mask" "F.Paste")
			(net "NetR21_2")
		)
	)
	(footprint "GNSS:GNSS"
		(layer "F.Cu")
		(at 123.266095 71.5786)
		(property "Reference" "U9"
			(at -0.7775 -5.406655 360)
			(unlocked yes)
			(layer "F.SilkS")
			(effects
				(font
					(size 0.762 0.762)
					(thickness 0.2286)
				)
				(justify left bottom)
			)
		)
		(property "Value" "RCB-F9T"
			(at -9.8007 23.16699 0)
			(unlocked yes)
			(layer "F.SilkS")
			(hide yes)
			(effects
				(font
					(size 1.524 1.524)
					(thickness 0.254)
				)
				(justify left bottom)
			)
		)
		(sheetname "GPS_IMU_SENSORS")
		(sheetfile "GPS_IMU_SENSORS.kicad_sch")
		(duplicate_pad_numbers_are_jumpers no)
		(fp_line
			(start -6.11 -20.47)
			(end 61.07 -20.47)
			(stroke
				(width 0.254)
				(type solid)
			)
			(layer "F.SilkS")
		)
		(fp_line
			(start -6.11 11.28)
			(end -6.11 -20.47)
			(stroke
				(width 0.254)
				(type solid)
			)
			(layer "F.SilkS")
		)
		(fp_line
			(start -6.11 11.28)
			(end 61.07 11.28)
			(stroke
				(width 0.254)
				(type solid)
			)
			(layer "F.SilkS")
		)
		(fp_line
			(start 61.07 11.28)
			(end 61.07 -20.47)
			(stroke
				(width 0.254)
				(type solid)
			)
			(layer "F.SilkS")
		)
		(pad "0" thru_hole circle
			(at 0 -2 270)
			(size 0 0)
			(drill 0.76)
			(layers "*.Cu" "*.Mask")
			(remove_unused_layers no)
			(thermal_bridge_angle 90)
		)
		(pad "0" thru_hole circle
			(at 0 2 270)
			(size 0 0)
			(drill 0.76)
			(layers "*.Cu" "*.Mask")
			(remove_unused_layers no)
			(thermal_bridge_angle 90)
		)
		(pad "1" smd rect
			(at -2.2225 3 270)
			(size 1.12 2.105)
			(layers "F.Cu" "F.Mask" "F.Paste")
			(net "+5.0V")
		)
		(pad "2" smd rect
			(at 2.2225 3 270)
			(size 1.12 2.105)
			(layers "F.Cu" "F.Mask" "F.Paste")
			(net "+3.3V")
		)
		(pad "3" smd rect
			(at -2.2225 1 270)
			(size 1.12 2.105)
			(layers "F.Cu" "F.Mask" "F.Paste")
			(net "GPS1_TX")
		)
		(pad "4" smd rect
			(at 2.2225 1 270)
			(size 1.12 2.105)
			(layers "F.Cu" "F.Mask" "F.Paste")
			(net "GPS1_RST")
		)
		(pad "5" smd rect
			(at -2.2225 -1 270)
			(size 1.12 2.105)
			(layers "F.Cu" "F.Mask" "F.Paste")
			(net "GPS1_RX")
		)
		(pad "6" smd rect
			(at 2.2225 -1 270)
			(size 1.12 2.105)
			(layers "F.Cu" "F.Mask" "F.Paste")
			(net "GPS1_TP1")
		)
		(pad "7" smd rect
			(at -2.2225 -3 270)
			(size 1.12 2.105)
			(layers "F.Cu" "F.Mask" "F.Paste")
			(net "GPS1_TP2")
		)
		(pad "8" smd rect
			(at 2.2225 -3 270)
			(size 1.12 2.105)
			(layers "F.Cu" "F.Mask" "F.Paste")
			(net "GND")
		)
	)
	(footprint "Vault:TECO-1909763-1_V"
		(layer "F.Cu")
		(at 71.838595 110.9786 90)
		(property "Reference" "J5"
			(at -1.371395 2.926931 90)
			(unlocked yes)
			(layer "F.SilkS")
			(effects
				(font
					(size 0.762 0.762)
					(thickness 0.2286)
				)
			)
		)
		(property "Value" "1909763-1"
			(at 4.608085 3.749802 90)
			(unlocked yes)
			(layer "F.SilkS")
			(hide yes)
			(effects
				(font
					(size 1.524 1.524)
					(thickness 0.254)
				)
			)
		)
		(sheetname "USER_IO")
		(sheetfile "USER_IO.kicad_sch")
		(duplicate_pad_numbers_are_jumpers no)
		(fp_line
			(start -0.55 -1.3)
			(end 0.55 -1.3)
			(stroke
				(width 0.2)
				(type solid)
			)
			(layer "F.SilkS")
		)
		(fp_circle
			(center -1.778 1.65)
			(end -1.653 1.65)
			(stroke
				(width 0.25)
				(type solid)
			)
			(fill no)
			(layer "F.SilkS")
		)
		(pad "1" smd rect
			(at -1.475 0 90)
			(size 1.05 2.2)
			(layers "F.Cu" "F.Mask" "F.Paste")
			(net "GND")
		)
		(pad "2" smd rect
			(at 0 1.525 90)
			(size 1 1.05)
			(layers "F.Cu" "F.Mask" "F.Paste")
			(net "NetAN2_1")
		)
		(pad "3" smd rect
			(at 1.475 0 90)
			(size 1.05 2.2)
			(layers "F.Cu" "F.Mask" "F.Paste")
			(net "GND")
		)
	)
	(footprint "Vault:SOT143-4L"
		(layer "F.Cu")
		(at 72.488595 130.8286 90)
		(property "Reference" "D1"
			(at -2.776931 1.478605 360)
			(unlocked yes)
			(layer "F.SilkS")
			(effects
				(font
					(size 0.762 0.762)
					(thickness 0.2286)
				)
			)
		)
		(property "Value" "8240136"
			(at 2.7035 3.368802 90)
			(unlocked yes)
			(layer "F.SilkS")
			(hide yes)
			(effects
				(font
					(size 1.524 1.524)
					(thickness 0.254)
				)
			)
		)
		(sheetname "USER_IO")
		(sheetfile "USER_IO.kicad_sch")
		(duplicate_pad_numbers_are_jumpers no)
		(fp_line
			(start 2.05 -1.7)
			(end 2.05 1.7)
			(stroke
				(width 0.2)
				(type solid)
			)
			(layer "F.SilkS")
		)
		(fp_line
			(start -2.05 -1.7)
			(end 2.05 -1.7)
			(stroke
				(width 0.2)
				(type solid)
			)
			(layer "F.SilkS")
		)
		(fp_line
			(start -2.05 -1.7)
			(end -2.05 1.675)
			(stroke
				(width 0.2)
				(type solid)
			)
			(layer "F.SilkS")
		)
		(fp_line
			(start -2.05 1.7)
			(end 2.05 1.7)
			(stroke
				(width 0.2)
				(type solid)
			)
			(layer "F.SilkS")
		)
		(fp_circle
			(center -2.404 -1.075)
			(end -2.15 -1.075)
			(stroke
				(width 0.2)
				(type solid)
			)
			(fill no)
			(layer "F.SilkS")
		)
		(pad "1" smd rect
			(at -1.1 -0.75 180)
			(size 1.4 1.4)
			(layers "F.Cu" "F.Mask" "F.Paste")
			(net "GND")
		)
		(pad "2" smd rect
			(at -1.1 0.95 180)
			(size 1 1.4)
			(layers "F.Cu" "F.Mask" "F.Paste")
			(net "NetAN4_1")
		)
		(pad "3" smd rect
			(at 1.1 0.95 180)
			(size 1 1.4)
			(layers "F.Cu" "F.Mask" "F.Paste")
			(net "NetAN3_1")
		)
		(pad "4" smd rect
			(at 1.1 -0.95 180)
			(size 1 1.4)
			(layers "F.Cu" "F.Mask" "F.Paste")
			(net "+3.3V")
		)
	)
	(footprint "Vault:CAPC1608X87X45ML20T05"
		(layer "F.Cu")
		(at 233.109595 107.3386 180)
		(property "Reference" "C19"
			(at 1.046 1.141655 0)
			(unlocked yes)
			(layer "F.SilkS")
			(effects
				(font
					(size 0.762 0.762)
					(thickness 0.2286)
				)
				(justify left bottom)
			)
		)
		(property "Value" "0.1uF"
			(at 3.9751 -3.95859 0)
			(unlocked yes)
			(layer "F.SilkS")
			(hide yes)
			(effects
				(font
					(size 1.524 1.524)
					(thickness 0.254)
				)
				(justify left bottom)
			)
		)
		(sheetname "POWER")
		(sheetfile "POWER.kicad_sch")
		(duplicate_pad_numbers_are_jumpers no)
		(pad "1" smd rect
			(at -0.7 0 270)
			(size 1.1 1.05)
			(layers "F.Cu" "F.Mask" "F.Paste")
			(net "GND")
		)
		(pad "2" smd rect
			(at 0.7 0 270)
			(size 1.1 1.05)
			(layers "F.Cu" "F.Mask" "F.Paste")
			(net "NetC19_2")
		)
	)
	(footprint "Vault:CAPC1608X87X45ML20T05"
		(layer "F.Cu")
		(at 219.588595 90.9786 180)
		(property "Reference" "C9"
			(at 4.2 -0.493345 0)
			(unlocked yes)
			(layer "F.SilkS")
			(effects
				(font
					(size 0.762 0.762)
					(thickness 0.2286)
				)
				(justify left bottom)
			)
		)
		(property "Value" "0.1uF"
			(at -10.9347 -6.32079 0)
			(unlocked yes)
			(layer "F.SilkS")
			(hide yes)
			(effects
				(font
					(size 1.524 1.524)
					(thickness 0.254)
				)
				(justify left bottom)
			)
		)
		(sheetname "POWER")
		(sheetfile "POWER.kicad_sch")
		(duplicate_pad_numbers_are_jumpers no)
		(pad "1" smd rect
			(at -0.7 0 270)
			(size 1.1 1.05)
			(layers "F.Cu" "F.Mask" "F.Paste")
			(net "GND")
		)
		(pad "2" smd rect
			(at 0.7 0 270)
			(size 1.1 1.05)
			(layers "F.Cu" "F.Mask" "F.Paste")
			(net "+3.3V")
		)
	)
	(footprint "Passives:DIOM1608X06N"
		(layer "F.Cu")
		(at 74.867595 53.2366 90)
		(property "Reference" "D11"
			(at -1.21245 -1.265735 90)
			(unlocked yes)
			(layer "F.SilkS")
			(effects
				(font
					(size 0.762 0.762)
					(thickness 0.2286)
				)
				(justify left bottom)
			)
		)
		(property "Value" "RED"
			(at -3.22199 -1.4097 0)
			(unlocked yes)
			(layer "F.SilkS")
			(hide yes)
			(effects
				(font
					(size 1.524 1.524)
					(thickness 0.254)
				)
				(justify left bottom)
			)
		)
		(sheetname "USER_IO")
		(sheetfile "USER_IO.kicad_sch")
		(duplicate_pad_numbers_are_jumpers no)
		(fp_circle
			(center -1.275 -0.725)
			(end -1.225 -0.725)
			(stroke
				(width 0.1)
				(type solid)
			)
			(fill no)
			(layer "F.SilkS")
		)
		(pad "1" smd rect
			(at -0.725 0 180)
			(size 0.85 1)
			(layers "F.Cu" "F.Mask" "F.Paste")
			(net "NetD11_1")
		)
		(pad "2" smd rect
			(at 0.725 0 180)
			(size 0.85 1)
			(layers "F.Cu" "F.Mask" "F.Paste")
			(net "+3.3V")
		)
	)
	(footprint "Vault:RESC1608X55X25NL10T15"
		(layer "F.Cu")
		(at 83.238595 136.8286 -90)
		(property "Reference" "R25"
			(at -2.9786 -0.026931 90)
			(unlocked yes)
			(layer "F.SilkS")
			(effects
				(font
					(size 0.762 0.762)
					(thickness 0.2286)
				)
			)
		)
		(property "Value" "49.9R"
			(at -2.911602 3.21199 180)
			(unlocked yes)
			(layer "F.SilkS")
			(hide yes)
			(effects
				(font
					(size 1.524 1.524)
					(thickness 0.254)
				)
			)
		)
		(sheetname "USER_IO")
		(sheetfile "USER_IO.kicad_sch")
		(duplicate_pad_numbers_are_jumpers no)
		(pad "1" smd rect
			(at -0.7 0)
			(size 0.9 0.7)
			(layers "F.Cu" "F.Mask" "F.Paste")
			(net "NetR25_1")
		)
		(pad "2" smd rect
			(at 0.7 0)
			(size 0.9 0.7)
			(layers "F.Cu" "F.Mask" "F.Paste")
			(net "NetAN4_1")
		)
	)
	(footprint "Vault:CAPC1608X87X45ML20T05"
		(layer "F.Cu")
		(at 148.288595 85.5786 180)
		(property "Reference" "C30"
			(at 2.8214 -0.026931 0)
			(unlocked yes)
			(layer "F.SilkS")
			(effects
				(font
					(size 0.762 0.762)
					(thickness 0.2286)
				)
			)
		)
		(property "Value" "0.1uF"
			(at 2.09443 2.657602 180)
			(unlocked yes)
			(layer "F.SilkS")
			(hide yes)
			(effects
				(font
					(size 1.524 1.524)
					(thickness 0.254)
				)
			)
		)
		(sheetname "GPS_IMU_SENSORS")
		(sheetfile "GPS_IMU_SENSORS.kicad_sch")
		(duplicate_pad_numbers_are_jumpers no)
		(pad "1" smd rect
			(at -0.7 0 270)
			(size 1.1 1.05)
			(layers "F.Cu" "F.Mask" "F.Paste")
			(net "GND")
		)
		(pad "2" smd rect
			(at 0.7 0 270)
			(size 1.1 1.05)
			(layers "F.Cu" "F.Mask" "F.Paste")
			(net "+3.3V")
		)
	)
	(footprint "Vault:CAPC1608X90X35NL10T15"
		(layer "F.Cu")
		(at 234.760595 112.1646 -90)
		(property "Reference" "C20"
			(at -1.336 -0.346345 90)
			(unlocked yes)
			(layer "F.SilkS")
			(effects
				(font
					(size 0.762 0.762)
					(thickness 0.2286)
				)
				(justify left bottom)
			)
		)
		(property "Value" "0.033uF"
			(at 3.34899 3.7211 0)
			(unlocked yes)
			(layer "F.SilkS")
			(hide yes)
			(effects
				(font
					(size 1.524 1.524)
					(thickness 0.254)
				)
				(justify left bottom)
			)
		)
		(sheetname "POWER")
		(sheetfile "POWER.kicad_sch")
		(duplicate_pad_numbers_are_jumpers no)
		(pad "1" smd rect
			(at -0.675 0)
			(size 0.95 0.85)
			(layers "F.Cu" "F.Mask" "F.Paste")
			(net "NetC20_1")
		)
		(pad "2" smd rect
			(at 0.675 0)
			(size 0.95 0.85)
			(layers "F.Cu" "F.Mask" "F.Paste")
			(net "NetC20_2")
		)
	)
	(footprint "Connectors:AMPHENOL-901-143-6RFX"
		(layer "F.Cu")
		(at 63.564595 124.2296 180)
		(property "Reference" "AN3"
			(at 4.076 -6.192345 0)
			(unlocked yes)
			(layer "F.SilkS")
			(effects
				(font
					(size 0.762 0.762)
					(thickness 0.2286)
				)
				(justify left bottom)
			)
		)
		(property "Value" "901-143-6RFX"
			(at 4.6101 -2.05359 0)
			(unlocked yes)
			(layer "F.SilkS")
			(hide yes)
			(effects
				(font
					(size 1.524 1.524)
					(thickness 0.254)
				)
				(justify left bottom)
			)
		)
		(sheetname "USER_IO")
		(sheetfile "USER_IO.kicad_sch")
		(duplicate_pad_numbers_are_jumpers no)
		(fp_line
			(start 4.318 3.556)
			(end 3.302 4.572)
			(stroke
				(width 0.1778)
				(type solid)
			)
			(layer "F.SilkS")
		)
		(fp_line
			(start 4.318 -3.556)
			(end 3.302 -4.572)
			(stroke
				(width 0.1778)
				(type solid)
			)
			(layer "F.SilkS")
		)
		(fp_line
			(start 3.302 4.572)
			(end 2.54 4.572)
			(stroke
				(width 0.1778)
				(type solid)
			)
			(layer "F.SilkS")
		)
		(fp_line
			(start 3.302 -4.572)
			(end 2.54 -4.572)
			(stroke
				(width 0.1778)
				(type solid)
			)
			(layer "F.SilkS")
		)
		(fp_line
			(start 2.54 4.572)
			(end -4.572 4.572)
			(stroke
				(width 0.1778)
				(type solid)
			)
			(layer "F.SilkS")
		)
		(fp_line
			(start 2.54 -4.572)
			(end -4.572 -4.572)
			(stroke
				(width 0.1778)
				(type solid)
			)
			(layer "F.SilkS")
		)
		(fp_line
			(start -4.572 2.54)
			(end -4.572 4.572)
			(stroke
				(width 0.1778)
				(type solid)
			)
			(layer "F.SilkS")
		)
		(fp_line
			(start -4.572 -4.572)
			(end -4.572 -2.54)
			(stroke
				(width 0.1778)
				(type solid)
			)
			(layer "F.SilkS")
		)
		(pad "1" thru_hole circle
			(at 0 0 180)
			(size 2.8448 2.8448)
			(drill 1.524)
			(layers "*.Cu" "*.Mask")
			(remove_unused_layers no)
			(net "NetAN3_1")
			(thermal_bridge_angle 90)
		)
		(pad "2" thru_hole circle
			(at -2.54 2.54 180)
			(size 3.048 3.048)
			(drill 1.7272)
			(layers "*.Cu" "*.Mask")
			(remove_unused_layers no)
			(net "GND")
			(thermal_bridge_angle 90)
		)
		(pad "3" thru_hole circle
			(at -2.54 -2.54 180)
			(size 3.048 3.048)
			(drill 1.7272)
			(layers "*.Cu" "*.Mask")
			(remove_unused_layers no)
			(net "GND")
			(thermal_bridge_angle 90)
		)
		(pad "4" thru_hole circle
			(at 2.54 -2.54 180)
			(size 3.048 3.048)
			(drill 1.7272)
			(layers "*.Cu" "*.Mask")
			(remove_unused_layers no)
			(net "GND")
			(thermal_bridge_angle 90)
		)
		(pad "5" thru_hole circle
			(at 2.54 2.54 180)
			(size 3.048 3.048)
			(drill 1.7272)
			(layers "*.Cu" "*.Mask")
			(remove_unused_layers no)
			(net "GND")
			(thermal_bridge_angle 90)
		)
	)
	(footprint "Vault:RESC1608X55X30NL15T15"
		(layer "F.Cu")
		(at 90.188595 56.9786 90)
		(property "Reference" "R30"
			(at -1.3 -1.206655 90)
			(unlocked yes)
			(layer "F.SilkS")
			(effects
				(font
					(size 0.762 0.762)
					(thickness 0.2286)
				)
				(justify left bottom)
			)
		)
		(property "Value" "200 OHM"
			(at -3.72999 -0.4445 0)
			(unlocked yes)
			(layer "F.SilkS")
			(hide yes)
			(effects
				(font
					(size 1.524 1.524)
					(thickness 0.254)
				)
				(justify left bottom)
			)
		)
		(sheetname "USER_IO")
		(sheetfile "USER_IO.kicad_sch")
		(duplicate_pad_numbers_are_jumpers no)
		(pad "1" smd rect
			(at -0.675 0 180)
			(size 0.95 0.8)
			(layers "F.Cu" "F.Mask" "F.Paste")
			(net "LED4")
		)
		(pad "2" smd rect
			(at 0.675 0 180)
			(size 0.95 0.8)
			(layers "F.Cu" "F.Mask" "F.Paste")
			(net "NetD14_1")
		)
	)
	(footprint "Vault:M08A_N"
		(layer "F.Cu")
		(at 196.888595 88.7136)
		(property "Reference" "U3"
			(at 1.578605 -3.608069 0)
			(unlocked yes)
			(layer "F.SilkS")
			(effects
				(font
					(size 0.762 0.762)
					(thickness 0.2286)
				)
			)
		)
		(property "Value" "DS90LV027AQMA"
			(at 6.38498 4.359402 0)
			(unlocked yes)
			(layer "F.SilkS")
			(hide yes)
			(effects
				(font
					(size 1.524 1.524)
					(thickness 0.254)
				)
			)
		)
		(sheetname "MAC")
		(sheetfile "MAC.kicad_sch")
		(duplicate_pad_numbers_are_jumpers no)
		(fp_line
			(start -0.9 -2.5)
			(end 0.9 -2.5)
			(stroke
				(width 0.2)
				(type solid)
			)
			(layer "F.SilkS")
		)
		(fp_line
			(start -0.9 2.5)
			(end -0.9 -2.5)
			(stroke
				(width 0.2)
				(type solid)
			)
			(layer "F.SilkS")
		)
		(fp_line
			(start -0.9 2.5)
			(end 0.9 2.5)
			(stroke
				(width 0.2)
				(type solid)
			)
			(layer "F.SilkS")
		)
		(fp_line
			(start 0.9 2.5)
			(end 0.9 -2.5)
			(stroke
				(width 0.2)
				(type solid)
			)
			(layer "F.SilkS")
		)
		(fp_circle
			(center -2.4 -2.755)
			(end -2.4 -2.88)
			(stroke
				(width 0.25)
				(type solid)
			)
			(fill no)
			(layer "F.SilkS")
		)
		(fp_circle
			(center -0.1 -1.7)
			(end -0.1 -1.9)
			(stroke
				(width 0.4)
				(type solid)
			)
			(fill no)
			(layer "F.SilkS")
		)
		(pad "1" smd oval
			(at -2.4 -1.905 90)
			(size 0.6 2.2)
			(layers "F.Cu" "F.Mask" "F.Paste")
			(net "+3.3V")
		)
		(pad "2" smd oval
			(at -2.4 -0.635 90)
			(size 0.6 2.2)
			(layers "F.Cu" "F.Mask" "F.Paste")
			(net "FPGA_MAC_PPS_IN1-")
		)
		(pad "3" smd oval
			(at -2.4 0.635 90)
			(size 0.6 2.2)
			(layers "F.Cu" "F.Mask" "F.Paste")
			(net "FPGA_MAC_PPS_IN0-")
		)
		(pad "4" smd oval
			(at -2.4 1.905 90)
			(size 0.6 2.2)
			(layers "F.Cu" "F.Mask" "F.Paste")
			(net "GND")
		)
		(pad "5" smd oval
			(at 2.4 1.905 90)
			(size 0.6 2.2)
			(layers "F.Cu" "F.Mask" "F.Paste")
			(net "MAC_PPS_IN0-")
		)
		(pad "6" smd oval
			(at 2.4 0.635 90)
			(size 0.6 2.2)
			(layers "F.Cu" "F.Mask" "F.Paste")
			(net "MAC_PPS_IN0+")
		)
		(pad "7" smd oval
			(at 2.4 -0.635 90)
			(size 0.6 2.2)
			(layers "F.Cu" "F.Mask" "F.Paste")
			(net "MAC_PPS_IN1+")
		)
		(pad "8" smd oval
			(at 2.4 -1.905 90)
			(size 0.6 2.2)
			(layers "F.Cu" "F.Mask" "F.Paste")
			(net "MAC_PPS_IN1-")
		)
	)
	(footprint "Connectors:PCIE_4LANE_EDGE"
		(layer "F.Cu")
		(at 120.638465 154.3547)
		(property "Reference" "P2"
			(at -12.64987 -0.282755 0)
			(unlocked yes)
			(layer "F.SilkS")
			(hide yes)
			(effects
				(font
					(size 0.762 0.762)
					(thickness 0.2286)
				)
				(justify left bottom)
			)
		)
		(property "Value" "PCIex4"
			(at -5.44907 18.65122 0)
			(unlocked yes)
			(layer "F.SilkS")
			(hide yes)
			(effects
				(font
					(size 1.524 1.524)
					(thickness 0.254)
				)
				(justify left bottom)
			)
		)
		(sheetname "PCIe_JTAG")
		(sheetfile "PCIe_JTAG.kicad_sch")
		(duplicate_pad_numbers_are_jumpers no)
		(pad "A1" smd rect
			(at -16.49984 2.2286)
			(size 0.7112 3.2004)
			(layers "B.Cu" "B.Mask" "B.Paste")
			(net "PRSNT")
		)
		(pad "A2" smd rect
			(at -15.49985 2.7239)
			(size 0.7112 4.191)
			(layers "B.Cu" "B.Mask" "B.Paste")
			(net "+12V_PCIE")
		)
		(pad "A3" smd rect
			(at -14.49985 2.7239)
			(size 0.7112 4.191)
			(layers "B.Cu" "B.Mask" "B.Paste")
			(net "+12V_PCIE")
		)
		(pad "A4" smd rect
			(at -13.49985 2.7239)
			(size 0.7112 4.191)
			(layers "B.Cu" "B.Mask" "B.Paste")
			(net "GND")
		)
		(pad "A5" smd rect
			(at -12.49985 2.7239)
			(size 0.7112 4.191)
			(layers "B.Cu" "B.Mask" "B.Paste")
		)
		(pad "A6" smd rect
			(at -11.49985 2.7239)
			(size 0.7112 4.191)
			(layers "B.Cu" "B.Mask" "B.Paste")
		)
		(pad "A7" smd rect
			(at -10.49986 2.7239)
			(size 0.7112 4.191)
			(layers "B.Cu" "B.Mask" "B.Paste")
		)
		(pad "A8" smd rect
			(at -9.49986 2.7239)
			(size 0.7112 4.191)
			(layers "B.Cu" "B.Mask" "B.Paste")
		)
		(pad "A9" smd rect
			(at -8.49986 2.7239)
			(size 0.7112 4.191)
			(layers "B.Cu" "B.Mask" "B.Paste")
			(net "+3.3V_PCIE")
		)
		(pad "A10" smd rect
			(at -7.49986 2.7239)
			(size 0.7112 4.191)
			(layers "B.Cu" "B.Mask" "B.Paste")
			(net "+3.3V_PCIE")
		)
		(pad "A11" smd rect
			(at -6.49986 2.7239)
			(size 0.7112 4.191)
			(layers "B.Cu" "B.Mask" "B.Paste")
			(net "PCIE_PERST")
		)
		(pad "A12" smd rect
			(at -3.49987 2.7239)
			(size 0.7112 4.191)
			(layers "B.Cu" "B.Mask" "B.Paste")
			(net "GND")
		)
		(pad "A13" smd rect
			(at -2.49987 2.7239)
			(size 0.7112 4.191)
			(layers "B.Cu" "B.Mask" "B.Paste")
			(net "NetC44_1")
		)
		(pad "A14" smd rect
			(at -1.49987 2.7239)
			(size 0.7112 4.191)
			(layers "B.Cu" "B.Mask" "B.Paste")
			(net "NetC45_1")
		)
		(pad "A15" smd rect
			(at -0.49988 2.7239)
			(size 0.7112 4.191)
			(layers "B.Cu" "B.Mask" "B.Paste")
			(net "GND")
		)
		(pad "A16" smd rect
			(at 0.50012 2.7239)
			(size 0.7112 4.191)
			(layers "B.Cu" "B.Mask" "B.Paste")
			(net "NetC46_1")
		)
		(pad "A17" smd rect
			(at 1.50012 2.7239)
			(size 0.7112 4.191)
			(layers "B.Cu" "B.Mask" "B.Paste")
			(net "NetC47_1")
		)
		(pad "A18" smd rect
			(at 2.50012 2.7239)
			(size 0.7112 4.191)
			(layers "B.Cu" "B.Mask" "B.Paste")
			(net "GND")
		)
		(pad "A19" smd rect
			(at 3.50012 2.7239)
			(size 0.7112 4.191)
			(layers "B.Cu" "B.Mask" "B.Paste")
		)
		(pad "A20" smd rect
			(at 4.50011 2.7239)
			(size 0.7112 4.191)
			(layers "B.Cu" "B.Mask" "B.Paste")
			(net "GND")
		)
		(pad "A21" smd rect
			(at 5.50011 2.7239)
			(size 0.7112 4.191)
			(layers "B.Cu" "B.Mask" "B.Paste")
			(net "NetC48_1")
		)
		(pad "A22" smd rect
			(at 6.50011 2.7239)
			(size 0.7112 4.191)
			(layers "B.Cu" "B.Mask" "B.Paste")
			(net "NetC49_1")
		)
		(pad "A23" smd rect
			(at 7.50011 2.7239)
			(size 0.7112 4.191)
			(layers "B.Cu" "B.Mask" "B.Paste")
			(net "GND")
		)
		(pad "A24" smd rect
			(at 8.50011 2.7239)
			(size 0.7112 4.191)
			(layers "B.Cu" "B.Mask" "B.Paste")
			(net "GND")
		)
		(pad "A25" smd rect
			(at 9.5001 2.7239)
			(size 0.7112 4.191)
			(layers "B.Cu" "B.Mask" "B.Paste")
			(net "NetC50_1")
		)
		(pad "A26" smd rect
			(at 10.5001 2.7239)
			(size 0.7112 4.191)
			(layers "B.Cu" "B.Mask" "B.Paste")
			(net "NetC51_1")
		)
		(pad "A27" smd rect
			(at 11.5001 2.7239)
			(size 0.7112 4.191)
			(layers "B.Cu" "B.Mask" "B.Paste")
			(net "GND")
		)
		(pad "A28" smd rect
			(at 12.5001 2.7239)
			(size 0.7112 4.191)
			(layers "B.Cu" "B.Mask" "B.Paste")
			(net "GND")
		)
		(pad "A29" smd rect
			(at 13.5001 2.7239)
			(size 0.7112 4.191)
			(layers "B.Cu" "B.Mask" "B.Paste")
			(net "NetC52_1")
		)
		(pad "A30" smd rect
			(at 14.50009 2.7239)
			(size 0.7112 4.191)
			(layers "B.Cu" "B.Mask" "B.Paste")
			(net "NetC53_1")
		)
		(pad "A31" smd rect
			(at 15.50009 2.7239)
			(size 0.7112 4.191)
			(layers "B.Cu" "B.Mask" "B.Paste")
			(net "GND")
		)
		(pad "A32" smd rect
			(at 16.50009 2.7239)
			(size 0.7112 4.191)
			(layers "B.Cu" "B.Mask" "B.Paste")
		)
		(pad "B1" smd rect
			(at -16.49984 2.7239)
			(size 0.7112 4.191)
			(layers "F.Cu" "F.Mask" "F.Paste")
			(net "+12V_PCIE")
		)
		(pad "B2" smd rect
			(at -15.49985 2.7239)
			(size 0.7112 4.191)
			(layers "F.Cu" "F.Mask" "F.Paste")
			(net "+12V_PCIE")
		)
		(pad "B3" smd rect
			(at -14.49985 2.7239)
			(size 0.7112 4.191)
			(layers "F.Cu" "F.Mask" "F.Paste")
			(net "+12V_PCIE")
		)
		(pad "B4" smd rect
			(at -13.49985 2.7239)
			(size 0.7112 4.191)
			(layers "F.Cu" "F.Mask" "F.Paste")
			(net "GND")
		)
		(pad "B5" smd rect
			(at -12.49985 2.7239)
			(size 0.7112 4.191)
			(layers "F.Cu" "F.Mask" "F.Paste")
		)
		(pad "B6" smd rect
			(at -11.49985 2.7239)
			(size 0.7112 4.191)
			(layers "F.Cu" "F.Mask" "F.Paste")
		)
		(pad "B7" smd rect
			(at -10.49986 2.7239)
			(size 0.7112 4.191)
			(layers "F.Cu" "F.Mask" "F.Paste")
			(net "GND")
		)
		(pad "B8" smd rect
			(at -9.49986 2.7239)
			(size 0.7112 4.191)
			(layers "F.Cu" "F.Mask" "F.Paste")
			(net "+3.3V_PCIE")
		)
		(pad "B9" smd rect
			(at -8.49986 2.7239)
			(size 0.7112 4.191)
			(layers "F.Cu" "F.Mask" "F.Paste")
		)
		(pad "B10" smd rect
			(at -7.49986 2.7239)
			(size 0.7112 4.191)
			(layers "F.Cu" "F.Mask" "F.Paste")
		)
		(pad "B11" smd rect
			(at -6.49986 2.7239)
			(size 0.7112 4.191)
			(layers "F.Cu" "F.Mask" "F.Paste")
		)
		(pad "B12" smd rect
			(at -3.49987 2.7239)
			(size 0.7112 4.191)
			(layers "F.Cu" "F.Mask" "F.Paste")
		)
		(pad "B13" smd rect
			(at -2.49987 2.7239)
			(size 0.7112 4.191)
			(layers "F.Cu" "F.Mask" "F.Paste")
			(net "GND")
		)
		(pad "B14" smd rect
			(at -1.49987 2.7239)
			(size 0.7112 4.191)
			(layers "F.Cu" "F.Mask" "F.Paste")
			(net "PCIE_RX0_P")
		)
		(pad "B15" smd rect
			(at -0.49988 2.7239)
			(size 0.7112 4.191)
			(layers "F.Cu" "F.Mask" "F.Paste")
			(net "PCIE_RX0_N")
		)
		(pad "B16" smd rect
			(at 0.50012 2.7239)
			(size 0.7112 4.191)
			(layers "F.Cu" "F.Mask" "F.Paste")
			(net "GND")
		)
		(pad "B17" smd rect
			(at 1.50012 2.7239)
			(size 0.7112 4.191)
			(layers "F.Cu" "F.Mask" "F.Paste")
			(net "NetP2_B17")
		)
		(pad "B18" smd rect
			(at 2.50012 2.7239)
			(size 0.7112 4.191)
			(layers "F.Cu" "F.Mask" "F.Paste")
			(net "GND")
		)
		(pad "B19" smd rect
			(at 3.50012 2.7239)
			(size 0.7112 4.191)
			(layers "F.Cu" "F.Mask" "F.Paste")
			(net "PCIE_RX1_P")
		)
		(pad "B20" smd rect
			(at 4.50011 2.7239)
			(size 0.7112 4.191)
			(layers "F.Cu" "F.Mask" "F.Paste")
			(net "PCIE_RX1_N")
		)
		(pad "B21" smd rect
			(at 5.50011 2.7239)
			(size 0.7112 4.191)
			(layers "F.Cu" "F.Mask" "F.Paste")
			(net "GND")
		)
		(pad "B22" smd rect
			(at 6.50011 2.7239)
			(size 0.7112 4.191)
			(layers "F.Cu" "F.Mask" "F.Paste")
			(net "GND")
		)
		(pad "B23" smd rect
			(at 7.50011 2.7239)
			(size 0.7112 4.191)
			(layers "F.Cu" "F.Mask" "F.Paste")
			(net "PCIE_RX2_P")
		)
		(pad "B24" smd rect
			(at 8.50011 2.7239)
			(size 0.7112 4.191)
			(layers "F.Cu" "F.Mask" "F.Paste")
			(net "PCIE_RX2_N")
		)
		(pad "B25" smd rect
			(at 9.5001 2.7239)
			(size 0.7112 4.191)
			(layers "F.Cu" "F.Mask" "F.Paste")
			(net "GND")
		)
		(pad "B26" smd rect
			(at 10.5001 2.7239)
			(size 0.7112 4.191)
			(layers "F.Cu" "F.Mask" "F.Paste")
			(net "GND")
		)
		(pad "B27" smd rect
			(at 11.5001 2.7239)
			(size 0.7112 4.191)
			(layers "F.Cu" "F.Mask" "F.Paste")
			(net "PCIE_RX3_P")
		)
		(pad "B28" smd rect
			(at 12.5001 2.7239)
			(size 0.7112 4.191)
			(layers "F.Cu" "F.Mask" "F.Paste")
			(net "PCIE_RX3_N")
		)
		(pad "B29" smd rect
			(at 13.5001 2.7239)
			(size 0.7112 4.191)
			(layers "F.Cu" "F.Mask" "F.Paste")
			(net "GND")
		)
		(pad "B30" smd rect
			(at 14.50009 2.7239)
			(size 0.7112 4.191)
			(layers "F.Cu" "F.Mask" "F.Paste")
		)
		(pad "B31" smd rect
			(at 15.50009 2.2286)
			(size 0.7112 3.2004)
			(layers "F.Cu" "F.Mask" "F.Paste")
			(net "NetP2_B31")
		)
		(pad "B32" smd rect
			(at 16.50009 2.7239)
			(size 0.7112 4.191)
			(layers "F.Cu" "F.Mask" "F.Paste")
			(net "GND")
		)
	)
	(footprint "Vault:FP-BME280-MFG"
		(layer "F.Cu")
		(at 148.238595 88.8286)
		(property "Reference" "U14"
			(at -0.5214 2.776931 0)
			(unlocked yes)
			(layer "F.SilkS")
			(effects
				(font
					(size 0.762 0.762)
					(thickness 0.2286)
				)
			)
		)
		(property "Value" "BME280"
			(at 2.932305 3.470402 0)
			(unlocked yes)
			(layer "F.SilkS")
			(hide yes)
			(effects
				(font
					(size 1.524 1.524)
					(thickness 0.254)
				)
			)
		)
		(sheetname "GPS_IMU_SENSORS")
		(sheetfile "GPS_IMU_SENSORS.kicad_sch")
		(duplicate_pad_numbers_are_jumpers no)
		(fp_line
			(start -1.3 -1.55)
			(end 1.3 -1.55)
			(stroke
				(width 0.2)
				(type solid)
			)
			(layer "F.SilkS")
		)
		(fp_line
			(start -1.3 1.55)
			(end 1.3 1.55)
			(stroke
				(width 0.2)
				(type solid)
			)
			(layer "F.SilkS")
		)
		(fp_circle
			(center 1.85 -0.975)
			(end 1.85 -1.1)
			(stroke
				(width 0.25)
				(type solid)
			)
			(fill no)
			(layer "F.SilkS")
		)
		(fp_line
			(start -1.8 -1.8)
			(end 1.8 -1.8)
			(stroke
				(width 0.2)
				(type solid)
			)
			(layer "F.CrtYd")
		)
		(fp_line
			(start -1.8 1.8)
			(end -1.8 -1.8)
			(stroke
				(width 0.2)
				(type solid)
			)
			(layer "F.CrtYd")
		)
		(fp_line
			(start -1.8 1.8)
			(end 1.8 1.8)
			(stroke
				(width 0.2)
				(type solid)
			)
			(layer "F.CrtYd")
		)
		(fp_line
			(start 1.8 1.8)
			(end 1.8 -1.8)
			(stroke
				(width 0.2)
				(type solid)
			)
			(layer "F.CrtYd")
		)
		(fp_line
			(start -1.8 -1.8)
			(end 1.8 -1.8)
			(stroke
				(width 0.2)
				(type solid)
			)
			(layer "F.Fab")
		)
		(fp_line
			(start -1.8 1.8)
			(end -1.8 -1.8)
			(stroke
				(width 0.2)
				(type solid)
			)
			(layer "F.Fab")
		)
		(fp_line
			(start -1.8 1.8)
			(end 1.8 1.8)
			(stroke
				(width 0.2)
				(type solid)
			)
			(layer "F.Fab")
		)
		(fp_line
			(start -0.5 0)
			(end 0.5 0)
			(stroke
				(width 0.1)
				(type solid)
			)
			(layer "F.Fab")
		)
		(fp_line
			(start 0 0.5)
			(end 0 -0.5)
			(stroke
				(width 0.1)
				(type solid)
			)
			(layer "F.Fab")
		)
		(fp_line
			(start 1.8 1.8)
			(end 1.8 -1.8)
			(stroke
				(width 0.2)
				(type solid)
			)
			(layer "F.Fab")
		)
		(fp_text user "${REFERENCE}"
			(at 0 0.28494 0)
			(unlocked yes)
			(layer "F.Fab")
			(effects
				(font
					(face "Arial")
					(size 0.63 0.63)
					(thickness 0.1)
				)
				(justify left bottom)
			)
		)
		(pad "1" smd rect
			(at 1.025 -0.975)
			(size 0.5 0.35)
			(layers "F.Cu" "F.Mask" "F.Paste")
			(net "GND")
			(solder_mask_margin 0)
			(solder_paste_margin 0)
		)
		(pad "2" smd rect
			(at 1.025 -0.325)
			(size 0.5 0.35)
			(layers "F.Cu" "F.Mask" "F.Paste")
			(net "+3.3V")
			(solder_mask_margin 0)
			(solder_paste_margin 0)
		)
		(pad "3" smd rect
			(at 1.025 0.325)
			(size 0.5 0.35)
			(layers "F.Cu" "F.Mask" "F.Paste")
			(net "SDA")
			(solder_mask_margin 0)
			(solder_paste_margin 0)
		)
		(pad "4" smd rect
			(at 1.025 0.975)
			(size 0.5 0.35)
			(layers "F.Cu" "F.Mask" "F.Paste")
			(net "SCL")
			(solder_mask_margin 0)
			(solder_paste_margin 0)
		)
		(pad "5" smd rect
			(at -1.025 0.975)
			(size 0.5 0.35)
			(layers "F.Cu" "F.Mask" "F.Paste")
			(net "GND")
			(solder_mask_margin 0)
			(solder_paste_margin 0)
		)
		(pad "6" smd rect
			(at -1.025 0.325)
			(size 0.5 0.35)
			(layers "F.Cu" "F.Mask" "F.Paste")
			(net "+3.3V")
			(solder_mask_margin 0)
			(solder_paste_margin 0)
		)
		(pad "7" smd rect
			(at -1.025 -0.325)
			(size 0.5 0.35)
			(layers "F.Cu" "F.Mask" "F.Paste")
			(net "GND")
			(solder_mask_margin 0)
			(solder_paste_margin 0)
		)
		(pad "8" smd rect
			(at -1.025 -0.975)
			(size 0.5 0.35)
			(layers "F.Cu" "F.Mask" "F.Paste")
			(net "+3.3V")
			(solder_mask_margin 0)
			(solder_paste_margin 0)
		)
	)
	(footprint "Resistors:RESC1005X04N"
		(layer "F.Cu")
		(at 136.088595 145.5786 -90)
		(property "Reference" "R24"
			(at 1.35111 0.884735 90)
			(unlocked yes)
			(layer "F.SilkS")
			(effects
				(font
					(size 0.762 0.762)
					(thickness 0.2286)
				)
				(justify left bottom)
			)
		)
		(property "Value" "ERJ-2GE0R00X"
			(at 3.42519 0.2413 0)
			(unlocked yes)
			(layer "F.SilkS")
			(hide yes)
			(effects
				(font
					(size 1.524 1.524)
					(thickness 0.254)
				)
				(justify left bottom)
			)
		)
		(sheetname "PCIe_JTAG")
		(sheetfile "PCIe_JTAG.kicad_sch")
		(duplicate_pad_numbers_are_jumpers no)
		(pad "1" smd rect
			(at -0.425 0)
			(size 0.6 0.65)
			(layers "F.Cu" "F.Mask" "F.Paste")
			(net "PRSNT")
		)
		(pad "2" smd rect
			(at 0.425 0)
			(size 0.6 0.65)
			(layers "F.Cu" "F.Mask" "F.Paste")
			(net "NetP2_B31")
		)
	)
	(footprint "Capacitors:CAPC2012X14N"
		(layer "F.Cu")
		(at 217.888595 87.9786 90)
		(property "Reference" "C7"
			(at 3 0.393345 90)
			(unlocked yes)
			(layer "F.SilkS")
			(effects
				(font
					(size 0.762 0.762)
					(thickness 0.2286)
				)
				(justify left bottom)
			)
		)
		(property "Value" "CAP_0805_10UF_25V"
			(at -15.71879 10.0965 0)
			(unlocked yes)
			(layer "F.SilkS")
			(hide yes)
			(effects
				(font
					(size 1.524 1.524)
					(thickness 0.254)
				)
				(justify left bottom)
			)
		)
		(sheetname "POWER")
		(sheetfile "POWER.kicad_sch")
		(duplicate_pad_numbers_are_jumpers no)
		(fp_line
			(start -0.762 -0.9652)
			(end 0.762 -0.9652)
			(stroke
				(width 0.1524)
				(type solid)
			)
			(layer "F.SilkS")
		)
		(fp_line
			(start -0.762 0.9652)
			(end 0.762 0.9652)
			(stroke
				(width 0.1524)
				(type solid)
			)
			(layer "F.SilkS")
		)
		(pad "1" smd rect
			(at -0.9 0 180)
			(size 1.45 1.15)
			(layers "F.Cu" "F.Mask" "F.Paste")
			(net "+3.3V")
		)
		(pad "2" smd rect
			(at 0.9 0 180)
			(size 1.45 1.15)
			(layers "F.Cu" "F.Mask" "F.Paste")
			(net "GND")
		)
	)
	(footprint "Miscellaneous Connectors:HDR1X4"
		(layer "F.Cu")
		(at 188.948595 52.3286)
		(property "Reference" "P3"
			(at 9.763069 0.228605 270)
			(unlocked yes)
			(layer "F.SilkS")
			(effects
				(font
					(size 0.762 0.762)
					(thickness 0.2286)
				)
			)
		)
		(property "Value" "AUX Sensor"
			(at -2.937002 6.38576 270)
			(unlocked yes)
			(layer "F.SilkS")
			(hide yes)
			(effects
				(font
					(size 1.524 1.524)
					(thickness 0.254)
				)
			)
		)
		(sheetname "GPS_IMU_SENSORS")
		(sheetfile "GPS_IMU_SENSORS.kicad_sch")
		(duplicate_pad_numbers_are_jumpers no)
		(fp_line
			(start -1.27 -1.27)
			(end 8.89 -1.27)
			(stroke
				(width 0.2)
				(type solid)
			)
			(layer "F.SilkS")
		)
		(fp_line
			(start -1.27 1.27)
			(end -1.27 -1.27)
			(stroke
				(width 0.2)
				(type solid)
			)
			(layer "F.SilkS")
		)
		(fp_line
			(start -1.27 1.27)
			(end 8.89 1.27)
			(stroke
				(width 0.2)
				(type solid)
			)
			(layer "F.SilkS")
		)
		(fp_line
			(start 8.89 1.27)
			(end 8.89 -1.27)
			(stroke
				(width 0.2)
				(type solid)
			)
			(layer "F.SilkS")
		)
		(pad "1" thru_hole rect
			(at 0 0)
			(size 1.5 1.5)
			(drill 0.9)
			(layers "*.Cu" "*.Mask")
			(remove_unused_layers no)
			(net "GND")
		)
		(pad "2" thru_hole circle
			(at 2.54 0)
			(size 1.5 1.5)
			(drill 0.9)
			(layers "*.Cu" "*.Mask")
			(remove_unused_layers no)
			(net "+3.3V")
			(thermal_bridge_angle 90)
		)
		(pad "3" thru_hole circle
			(at 5.08 0)
			(size 1.5 1.5)
			(drill 0.9)
			(layers "*.Cu" "*.Mask")
			(remove_unused_layers no)
			(net "SCL")
			(thermal_bridge_angle 90)
		)
		(pad "4" thru_hole circle
			(at 7.62 0)
			(size 1.5 1.5)
			(drill 0.9)
			(layers "*.Cu" "*.Mask")
			(remove_unused_layers no)
			(net "SDA")
			(thermal_bridge_angle 90)
		)
	)
	(footprint "Vault:RESC1608X55X25NL10T15"
		(layer "F.Cu")
		(at 83.238595 96.8286 -90)
		(property "Reference" "R14"
			(at -2.9786 -0.026931 90)
			(unlocked yes)
			(layer "F.SilkS")
			(effects
				(font
					(size 0.762 0.762)
					(thickness 0.2286)
				)
			)
		)
		(property "Value" "49.9R"
			(at 2.835402 -4.73554 0)
			(unlocked yes)
			(layer "F.SilkS")
			(hide yes)
			(effects
				(font
					(size 1.524 1.524)
					(thickness 0.254)
				)
			)
		)
		(sheetname "USER_IO")
		(sheetfile "USER_IO.kicad_sch")
		(duplicate_pad_numbers_are_jumpers no)
		(pad "1" smd rect
			(at -0.7 0)
			(size 0.9 0.7)
			(layers "F.Cu" "F.Mask" "F.Paste")
			(net "NetR14_1")
		)
		(pad "2" smd rect
			(at 0.7 0)
			(size 0.9 0.7)
			(layers "F.Cu" "F.Mask" "F.Paste")
			(net "NetAN1_1")
		)
	)
	(footprint "Capacitors:CAPC1608X10N"
		(layer "F.Cu")
		(at 222.822595 102.8936 90)
		(property "Reference" "C3"
			(at -3.16 0.509345 90)
			(unlocked yes)
			(layer "F.SilkS")
			(effects
				(font
					(size 0.762 0.762)
					(thickness 0.2286)
				)
				(justify left bottom)
			)
		)
		(property "Value" "CAP_0603_0.01UF_50V"
			(at 12.98321 3.9751 0)
			(unlocked yes)
			(layer "F.SilkS")
			(hide yes)
			(effects
				(font
					(size 1.524 1.524)
					(thickness 0.254)
				)
				(justify left bottom)
			)
		)
		(sheetname "POWER")
		(sheetfile "POWER.kicad_sch")
		(duplicate_pad_numbers_are_jumpers no)
		(fp_line
			(start -0.635 -0.7112)
			(end 0.635 -0.7112)
			(stroke
				(width 0.1524)
				(type solid)
			)
			(layer "F.SilkS")
		)
		(fp_line
			(start -0.635 0.7112)
			(end 0.635 0.7112)
			(stroke
				(width 0.1524)
				(type solid)
			)
			(layer "F.SilkS")
		)
		(pad "1" smd rect
			(at -0.8 0 180)
			(size 0.95 1)
			(layers "F.Cu" "F.Mask" "F.Paste")
			(net "NetC3_1")
		)
		(pad "2" smd rect
			(at 0.8 0 180)
			(size 0.95 1)
			(layers "F.Cu" "F.Mask" "F.Paste")
			(net "NetC3_2")
		)
	)
	(footprint "Capacitors:CAPC2012X14N"
		(layer "F.Cu")
		(at 124.988595 79.8286 -90)
		(property "Reference" "C60"
			(at 1.5 -4.593345 90)
			(unlocked yes)
			(layer "F.SilkS")
			(effects
				(font
					(size 0.762 0.762)
					(thickness 0.2286)
				)
				(justify left bottom)
			)
		)
		(property "Value" "CAP_0805_10UF_25V"
			(at 3.52679 1.5875 0)
			(unlocked yes)
			(layer "F.SilkS")
			(hide yes)
			(effects
				(font
					(size 1.524 1.524)
					(thickness 0.254)
				)
				(justify left bottom)
			)
		)
		(sheetname "GPS_IMU_SENSORS")
		(sheetfile "GPS_IMU_SENSORS.kicad_sch")
		(duplicate_pad_numbers_are_jumpers no)
		(fp_line
			(start 0.762 0.9652)
			(end -0.762 0.9652)
			(stroke
				(width 0.1524)
				(type solid)
			)
			(layer "F.SilkS")
		)
		(fp_line
			(start 0.762 -0.9652)
			(end -0.762 -0.9652)
			(stroke
				(width 0.1524)
				(type solid)
			)
			(layer "F.SilkS")
		)
		(pad "1" smd rect
			(at -0.9 0)
			(size 1.45 1.15)
			(layers "F.Cu" "F.Mask" "F.Paste")
			(net "+5.0V")
		)
		(pad "2" smd rect
			(at 0.9 0)
			(size 1.45 1.15)
			(layers "F.Cu" "F.Mask" "F.Paste")
			(net "GND")
		)
	)
	(footprint "Capacitors:CAPC1005X06N"
		(layer "B.Cu")
		(at 119.190595 151.7886 90)
		(property "Reference" "C45"
			(at 2.835 -0.445345 270)
			(unlocked yes)
			(layer "B.SilkS")
			(effects
				(font
					(size 0.762 0.762)
					(thickness 0.2286)
				)
				(justify left bottom mirror)
			)
		)
		(property "Value" "CAP_0402_0.1UF_50V"
			(at -3.47599 0.2921 0)
			(unlocked yes)
			(layer "B.SilkS")
			(hide yes)
			(effects
				(font
					(size 1.524 1.524)
					(thickness 0.254)
				)
				(justify left bottom mirror)
			)
		)
		(sheetname "PCIe_JTAG")
		(sheetfile "PCIe_JTAG.kicad_sch")
		(duplicate_pad_numbers_are_jumpers no)
		(pad "1" smd rect
			(at -0.43 0)
			(size 0.64 0.68)
			(layers "B.Cu" "B.Mask" "B.Paste")
			(net "NetC45_1")
		)
		(pad "2" smd rect
			(at 0.43 0)
			(size 0.64 0.68)
			(layers "B.Cu" "B.Mask" "B.Paste")
			(net "PCIE_CLK_N")
		)
	)
	(footprint "Capacitors:CAPC1005X06N"
		(layer "B.Cu")
		(at 135.192595 151.7886 90)
		(property "Reference" "C53"
			(at 2.41349 0.046545 270)
			(unlocked yes)
			(layer "B.SilkS")
			(effects
				(font
					(size 0.762 0.762)
					(thickness 0.2286)
				)
				(justify left bottom mirror)
			)
		)
		(property "Value" "CAP_0402_0.1UF_50V"
			(at -3.47599 0.2921 0)
			(unlocked yes)
			(layer "B.SilkS")
			(hide yes)
			(effects
				(font
					(size 1.524 1.524)
					(thickness 0.254)
				)
				(justify left bottom mirror)
			)
		)
		(sheetname "PCIe_JTAG")
		(sheetfile "PCIe_JTAG.kicad_sch")
		(duplicate_pad_numbers_are_jumpers no)
		(pad "1" smd rect
			(at -0.43 0)
			(size 0.64 0.68)
			(layers "B.Cu" "B.Mask" "B.Paste")
			(net "NetC53_1")
		)
		(pad "2" smd rect
			(at 0.43 0)
			(size 0.64 0.68)
			(layers "B.Cu" "B.Mask" "B.Paste")
			(net "PCIE_TX3_N")
		)
	)
	(footprint "Capacitors:CAPC1005X06N"
		(layer "B.Cu")
		(at 130.112595 151.7886 90)
		(property "Reference" "C50"
			(at 2.41349 -0.766255 270)
			(unlocked yes)
			(layer "B.SilkS")
			(effects
				(font
					(size 0.762 0.762)
					(thickness 0.2286)
				)
				(justify left bottom mirror)
			)
		)
		(property "Value" "CAP_0402_0.1UF_50V"
			(at -3.47599 0.2921 0)
			(unlocked yes)
			(layer "B.SilkS")
			(hide yes)
			(effects
				(font
					(size 1.524 1.524)
					(thickness 0.254)
				)
				(justify left bottom mirror)
			)
		)
		(sheetname "PCIe_JTAG")
		(sheetfile "PCIe_JTAG.kicad_sch")
		(duplicate_pad_numbers_are_jumpers no)
		(pad "1" smd rect
			(at -0.43 0)
			(size 0.64 0.68)
			(layers "B.Cu" "B.Mask" "B.Paste")
			(net "NetC50_1")
		)
		(pad "2" smd rect
			(at 0.43 0)
			(size 0.64 0.68)
			(layers "B.Cu" "B.Mask" "B.Paste")
			(net "PCIE_TX2_P")
		)
	)
	(footprint "Capacitors:CAPC1005X06N"
		(layer "B.Cu")
		(at 131.001595 151.7886 90)
		(property "Reference" "C51"
			(at 2.41349 0.148145 270)
			(unlocked yes)
			(layer "B.SilkS")
			(effects
				(font
					(size 0.762 0.762)
					(thickness 0.2286)
				)
				(justify left bottom mirror)
			)
		)
		(property "Value" "CAP_0402_0.1UF_50V"
			(at -3.47599 0.2921 0)
			(unlocked yes)
			(layer "B.SilkS")
			(hide yes)
			(effects
				(font
					(size 1.524 1.524)
					(thickness 0.254)
				)
				(justify left bottom mirror)
			)
		)
		(sheetname "PCIe_JTAG")
		(sheetfile "PCIe_JTAG.kicad_sch")
		(duplicate_pad_numbers_are_jumpers no)
		(pad "1" smd rect
			(at -0.43 0)
			(size 0.64 0.68)
			(layers "B.Cu" "B.Mask" "B.Paste")
			(net "NetC51_1")
		)
		(pad "2" smd rect
			(at 0.43 0)
			(size 0.64 0.68)
			(layers "B.Cu" "B.Mask" "B.Paste")
			(net "PCIE_TX2_N")
		)
	)
	(footprint "Capacitors:CAPC1005X06N"
		(layer "B.Cu")
		(at 118.174595 151.7886 90)
		(property "Reference" "C44"
			(at 2.885 -1.204345 270)
			(unlocked yes)
			(layer "B.SilkS")
			(effects
				(font
					(size 0.762 0.762)
					(thickness 0.2286)
				)
				(justify left bottom mirror)
			)
		)
		(property "Value" "CAP_0402_0.1UF_50V"
			(at -3.47599 0.2921 0)
			(unlocked yes)
			(layer "B.SilkS")
			(hide yes)
			(effects
				(font
					(size 1.524 1.524)
					(thickness 0.254)
				)
				(justify left bottom mirror)
			)
		)
		(sheetname "PCIe_JTAG")
		(sheetfile "PCIe_JTAG.kicad_sch")
		(duplicate_pad_numbers_are_jumpers no)
		(pad "1" smd rect
			(at -0.43 0)
			(size 0.64 0.68)
			(layers "B.Cu" "B.Mask" "B.Paste")
			(net "NetC44_1")
		)
		(pad "2" smd rect
			(at 0.43 0)
			(size 0.64 0.68)
			(layers "B.Cu" "B.Mask" "B.Paste")
			(net "PCIE_CLK_P")
		)
	)
	(footprint "Capacitors:CAPC1005X06N"
		(layer "B.Cu")
		(at 127.191595 151.7886 90)
		(property "Reference" "C49"
			(at 2.41349 -0.156655 270)
			(unlocked yes)
			(layer "B.SilkS")
			(effects
				(font
					(size 0.762 0.762)
					(thickness 0.2286)
				)
				(justify left bottom mirror)
			)
		)
		(property "Value" "CAP_0402_0.1UF_50V"
			(at -3.47599 0.2921 0)
			(unlocked yes)
			(layer "B.SilkS")
			(hide yes)
			(effects
				(font
					(size 1.524 1.524)
					(thickness 0.254)
				)
				(justify left bottom mirror)
			)
		)
		(sheetname "PCIe_JTAG")
		(sheetfile "PCIe_JTAG.kicad_sch")
		(duplicate_pad_numbers_are_jumpers no)
		(pad "1" smd rect
			(at -0.43 0)
			(size 0.64 0.68)
			(layers "B.Cu" "B.Mask" "B.Paste")
			(net "NetC49_1")
		)
		(pad "2" smd rect
			(at 0.43 0)
			(size 0.64 0.68)
			(layers "B.Cu" "B.Mask" "B.Paste")
			(net "PCIE_TX1_N")
		)
	)
	(footprint "Capacitors:CAPC1005X06N"
		(layer "B.Cu")
		(at 134.176595 151.7886 90)
		(property "Reference" "C52"
			(at 2.41349 -0.613855 270)
			(unlocked yes)
			(layer "B.SilkS")
			(effects
				(font
					(size 0.762 0.762)
					(thickness 0.2286)
				)
				(justify left bottom mirror)
			)
		)
		(property "Value" "CAP_0402_0.1UF_50V"
			(at -3.47599 0.2921 0)
			(unlocked yes)
			(layer "B.SilkS")
			(hide yes)
			(effects
				(font
					(size 1.524 1.524)
					(thickness 0.254)
				)
				(justify left bottom mirror)
			)
		)
		(sheetname "PCIe_JTAG")
		(sheetfile "PCIe_JTAG.kicad_sch")
		(duplicate_pad_numbers_are_jumpers no)
		(pad "1" smd rect
			(at -0.43 0)
			(size 0.64 0.68)
			(layers "B.Cu" "B.Mask" "B.Paste")
			(net "NetC52_1")
		)
		(pad "2" smd rect
			(at 0.43 0)
			(size 0.64 0.68)
			(layers "B.Cu" "B.Mask" "B.Paste")
			(net "PCIE_TX3_P")
		)
	)
	(footprint "Capacitors:CAPC1005X06N"
		(layer "B.Cu")
		(at 126.175595 151.7886 90)
		(property "Reference" "C48"
			(at 2.41349 -0.867855 270)
			(unlocked yes)
			(layer "B.SilkS")
			(effects
				(font
					(size 0.762 0.762)
					(thickness 0.2286)
				)
				(justify left bottom mirror)
			)
		)
		(property "Value" "CAP_0402_0.1UF_50V"
			(at -3.47599 0.2921 0)
			(unlocked yes)
			(layer "B.SilkS")
			(hide yes)
			(effects
				(font
					(size 1.524 1.524)
					(thickness 0.254)
				)
				(justify left bottom mirror)
			)
		)
		(sheetname "PCIe_JTAG")
		(sheetfile "PCIe_JTAG.kicad_sch")
		(duplicate_pad_numbers_are_jumpers no)
		(pad "1" smd rect
			(at -0.43 0)
			(size 0.64 0.68)
			(layers "B.Cu" "B.Mask" "B.Paste")
			(net "NetC48_1")
		)
		(pad "2" smd rect
			(at 0.43 0)
			(size 0.64 0.68)
			(layers "B.Cu" "B.Mask" "B.Paste")
			(net "PCIE_TX1_P")
		)
	)
	(footprint "Capacitors:CAPC1005X06N"
		(layer "B.Cu")
		(at 122.289395 151.7886 90)
		(property "Reference" "C47"
			(at 2.41349 0.097345 270)
			(unlocked yes)
			(layer "B.SilkS")
			(effects
				(font
					(size 0.762 0.762)
					(thickness 0.2286)
				)
				(justify left bottom mirror)
			)
		)
		(property "Value" "CAP_0402_0.1UF_50V"
			(at -3.47599 0.2921 0)
			(unlocked yes)
			(layer "B.SilkS")
			(hide yes)
			(effects
				(font
					(size 1.524 1.524)
					(thickness 0.254)
				)
				(justify left bottom mirror)
			)
		)
		(sheetname "PCIe_JTAG")
		(sheetfile "PCIe_JTAG.kicad_sch")
		(duplicate_pad_numbers_are_jumpers no)
		(pad "1" smd rect
			(at -0.43 0)
			(size 0.64 0.68)
			(layers "B.Cu" "B.Mask" "B.Paste")
			(net "NetC47_1")
		)
		(pad "2" smd rect
			(at 0.43 0)
			(size 0.64 0.68)
			(layers "B.Cu" "B.Mask" "B.Paste")
			(net "PCIE_TX0_N")
		)
	)
	(footprint "Capacitors:CAPC1005X06N"
		(layer "B.Cu")
		(at 121.197195 151.7886 90)
		(property "Reference" "C46"
			(at 2.41349 -0.563055 270)
			(unlocked yes)
			(layer "B.SilkS")
			(effects
				(font
					(size 0.762 0.762)
					(thickness 0.2286)
				)
				(justify left bottom mirror)
			)
		)
		(property "Value" "CAP_0402_0.1UF_50V"
			(at -3.47599 0.2921 0)
			(unlocked yes)
			(layer "B.SilkS")
			(hide yes)
			(effects
				(font
					(size 1.524 1.524)
					(thickness 0.254)
				)
				(justify left bottom mirror)
			)
		)
		(sheetname "PCIe_JTAG")
		(sheetfile "PCIe_JTAG.kicad_sch")
		(duplicate_pad_numbers_are_jumpers no)
		(pad "1" smd rect
			(at -0.43 0)
			(size 0.64 0.68)
			(layers "B.Cu" "B.Mask" "B.Paste")
			(net "NetC46_1")
		)
		(pad "2" smd rect
			(at 0.43 0)
			(size 0.64 0.68)
			(layers "B.Cu" "B.Mask" "B.Paste")
			(net "PCIE_TX0_P")
		)
	)
	(gr_poly
		(pts
			(xy 221.308615 137.9755) (xy 221.308615 137.98923) (xy 221.308615 138.00296) (xy 221.308615 138.0167)
			(xy 221.308615 138.03043) (xy 221.308615 138.04416) (xy 221.308615 138.05789) (xy 221.308615 138.07162)
			(xy 221.308615 138.08536) (xy 221.308615 138.09909) (xy 221.308615 138.11282) (xy 221.308615 138.12655)
			(xy 221.308615 138.14028) (xy 221.308615 138.15401) (xy 221.308615 138.16775) (xy 221.308615 138.18148)
			(xy 221.308615 138.19521) (xy 221.308615 138.20894) (xy 221.308615 138.22267) (xy 221.308615 138.2364)
			(xy 221.308615 138.25014) (xy 221.308615 138.26387) (xy 221.308615 138.2776) (xy 221.308615 138.29133)
			(xy 221.308615 138.30506) (xy 221.308615 138.31879) (xy 221.308615 138.33253) (xy 221.308615 138.34626)
			(xy 221.308615 138.35999) (xy 221.308615 138.37372) (xy 221.308615 138.38745) (xy 221.308615 138.40118)
			(xy 221.308615 138.41492) (xy 221.308615 138.42865) (xy 221.308615 138.44238) (xy 221.308615 138.45611)
			(xy 221.308615 138.46984) (xy 221.308615 138.48358) (xy 221.308615 138.49731) (xy 221.308615 138.51104)
			(xy 221.308615 138.52477) (xy 221.308615 138.5385) (xy 221.308615 138.55224) (xy 221.308615 138.56597)
			(xy 221.308615 138.5797) (xy 221.308615 138.59343) (xy 221.308615 138.60716) (xy 221.308615 138.62089)
			(xy 221.308615 138.63463) (xy 221.308615 138.64836) (xy 221.308615 138.66209) (xy 221.308615 138.67582)
			(xy 221.308615 138.68955) (xy 220.278735 138.68955) (xy 220.278735 138.67582) (xy 220.278735 138.66209)
			(xy 220.278735 138.64836) (xy 220.278735 138.63463) (xy 220.278735 138.62089) (xy 220.278735 138.60716)
			(xy 220.278735 138.59343) (xy 220.278735 138.5797) (xy 220.278735 138.56597) (xy 220.278735 138.55224)
			(xy 220.278735 138.5385) (xy 220.278735 138.52477) (xy 220.278735 138.51104) (xy 220.278735 138.49731)
			(xy 220.278735 138.48358) (xy 220.278735 138.46984) (xy 220.278735 138.45611) (xy 220.278735 138.44238)
			(xy 220.278735 138.42865) (xy 220.278735 138.41492) (xy 220.278735 138.40118) (xy 220.278735 138.38745)
			(xy 220.278735 138.37372) (xy 220.278735 138.35999) (xy 220.278735 138.34626) (xy 220.278735 138.33253)
			(xy 220.278735 138.31879) (xy 220.278735 138.30506) (xy 220.278735 138.29133) (xy 220.278735 138.2776)
			(xy 220.278735 138.26387) (xy 220.278735 138.25014) (xy 220.278735 138.2364) (xy 220.278735 138.22267)
			(xy 220.278735 138.20894) (xy 220.278735 138.19521) (xy 220.278735 138.18148) (xy 220.278735 138.16775)
			(xy 220.278735 138.15401) (xy 220.278735 138.14028) (xy 220.278735 138.12655) (xy 220.278735 138.11282)
			(xy 220.278735 138.09909) (xy 220.278735 138.08536) (xy 220.278735 138.07162) (xy 220.278735 138.05789)
			(xy 220.278735 138.04416) (xy 220.278735 138.03043) (xy 220.278735 138.0167) (xy 220.278735 138.00296)
			(xy 220.278735 137.98923) (xy 220.278735 137.9755) (xy 220.278735 137.96177) (xy 221.308615 137.96177)
		)
		(stroke
			(width 0)
			(type default)
		)
		(fill yes)
		(layer "F.Cu")
	)
	(gr_poly
		(pts
			(xy 210.213365 141.9989) (xy 210.268295 141.9989) (xy 210.268295 142.01263) (xy 210.295755 142.01263)
			(xy 210.295755 142.02637) (xy 210.323215 142.02637) (xy 210.323215 142.0401) (xy 210.350685 142.0401)
			(xy 210.350685 142.05383) (xy 210.378145 142.05383) (xy 210.378145 142.06756) (xy 210.391875 142.06756)
			(xy 210.391875 142.08129) (xy 210.419345 142.08129) (xy 210.419345 142.09502) (xy 210.433075 142.09502)
			(xy 210.433075 142.10876) (xy 210.446805 142.10876) (xy 210.446805 142.12249) (xy 210.460535 142.12249)
			(xy 210.460535 142.13622) (xy 210.474265 142.13622) (xy 210.474265 142.14995) (xy 210.487995 142.14995)
			(xy 210.487995 142.16368) (xy 210.501735 142.16368) (xy 210.501735 142.17742) (xy 210.515465 142.17742)
			(xy 210.515465 142.19115) (xy 210.515465 142.20488) (xy 210.529195 142.20488) (xy 210.529195 142.21861)
			(xy 210.542925 142.21861) (xy 210.542925 142.23234) (xy 210.542925 142.24608) (xy 210.556655 142.24608)
			(xy 210.556655 142.25981) (xy 210.556655 142.27354) (xy 210.570385 142.27354) (xy 210.570385 142.28727)
			(xy 210.570385 142.301) (xy 210.584125 142.301) (xy 210.584125 142.31473) (xy 210.584125 142.32847)
			(xy 210.584125 142.3422) (xy 210.597855 142.3422) (xy 210.597855 142.35593) (xy 210.597855 142.36966)
			(xy 210.597855 142.38339) (xy 210.597855 142.39712) (xy 210.597855 142.41086) (xy 210.611585 142.41086)
			(xy 210.611585 142.42459) (xy 210.611585 142.43832) (xy 210.611585 142.45205) (xy 210.611585 142.46578)
			(xy 210.611585 142.47951) (xy 210.611585 142.49325) (xy 210.611585 142.50698) (xy 210.611585 142.52071)
			(xy 210.611585 142.53444) (xy 210.611585 142.54817) (xy 210.611585 142.5619) (xy 210.611585 142.57564)
			(xy 210.597855 142.57564) (xy 210.597855 142.58937) (xy 210.597855 142.6031) (xy 210.597855 142.61683)
			(xy 210.597855 142.63056) (xy 210.597855 142.64429) (xy 210.584125 142.64429) (xy 210.584125 142.65803)
			(xy 210.584125 142.67176) (xy 210.584125 142.68549) (xy 210.570385 142.68549) (xy 210.570385 142.69922)
			(xy 210.570385 142.71295) (xy 210.556655 142.71295) (xy 210.556655 142.72669) (xy 210.556655 142.74042)
			(xy 210.542925 142.74042) (xy 210.542925 142.75415) (xy 210.542925 142.76788) (xy 210.529195 142.76788)
			(xy 210.529195 142.78161) (xy 210.515465 142.78161) (xy 210.515465 142.79535) (xy 210.515465 142.80908)
			(xy 210.501735 142.80908) (xy 210.501735 142.82281) (xy 210.487995 142.82281) (xy 210.487995 142.83654)
			(xy 210.474265 142.83654) (xy 210.474265 142.85027) (xy 210.460535 142.85027) (xy 210.460535 142.864)
			(xy 210.446805 142.864) (xy 210.446805 142.87774) (xy 210.433075 142.87774) (xy 210.433075 142.89147)
			(xy 210.419345 142.89147) (xy 210.419345 142.9052) (xy 210.391875 142.9052) (xy 210.391875 142.91893)
			(xy 210.378145 142.91893) (xy 210.378145 142.93266) (xy 210.350685 142.93266) (xy 210.350685 142.94639)
			(xy 210.323215 142.94639) (xy 210.323215 142.96013) (xy 210.295755 142.96013) (xy 210.295755 142.97386)
			(xy 210.254565 142.97386) (xy 210.254565 142.98759) (xy 210.213365 142.98759) (xy 210.213365 143.00132)
			(xy 209.979925 143.00132) (xy 209.979925 142.98759) (xy 209.938725 142.98759) (xy 209.938725 142.97386)
			(xy 209.897535 142.97386) (xy 209.897535 142.96013) (xy 209.870075 142.96013) (xy 209.870075 142.94639)
			(xy 209.842605 142.94639) (xy 209.842605 142.93266) (xy 209.815145 142.93266) (xy 209.815145 142.91893)
			(xy 209.801415 142.91893) (xy 209.801415 142.9052) (xy 209.787685 142.9052) (xy 209.787685 142.89147)
			(xy 209.760215 142.89147) (xy 209.760215 142.87774) (xy 209.746485 142.87774) (xy 209.746485 142.864)
			(xy 209.732755 142.864) (xy 209.732755 142.85027) (xy 209.719025 142.85027) (xy 209.719025 142.83654)
			(xy 209.705285 142.83654) (xy 209.705285 142.82281) (xy 209.691555 142.82281) (xy 209.691555 142.80908)
			(xy 209.691555 142.79535) (xy 209.677825 142.79535) (xy 209.677825 142.78161) (xy 209.664095 142.78161)
			(xy 209.664095 142.76788) (xy 209.664095 142.75415) (xy 209.650365 142.75415) (xy 209.650365 142.74042)
			(xy 209.650365 142.72669) (xy 209.636635 142.72669) (xy 209.636635 142.71295) (xy 209.636635 142.69922)
			(xy 209.622895 142.69922) (xy 209.622895 142.68549) (xy 209.622895 142.67176) (xy 209.609165 142.67176)
			(xy 209.609165 142.65803) (xy 209.609165 142.64429) (xy 209.609165 142.63056) (xy 209.595435 142.63056)
			(xy 209.595435 142.61683) (xy 209.595435 142.6031) (xy 209.595435 142.58937) (xy 209.595435 142.57564)
			(xy 209.595435 142.5619) (xy 209.581705 142.5619) (xy 209.581705 142.54817) (xy 209.581705 142.53444)
			(xy 209.581705 142.52071) (xy 209.581705 142.50698) (xy 209.581705 142.49325) (xy 209.581705 142.47951)
			(xy 209.581705 142.46578) (xy 209.581705 142.45205) (xy 209.581705 142.43832) (xy 209.581705 142.42459)
			(xy 209.595435 142.42459) (xy 209.595435 142.41086) (xy 209.595435 142.39712) (xy 209.595435 142.38339)
			(xy 209.595435 142.36966) (xy 209.595435 142.35593) (xy 209.609165 142.35593) (xy 209.609165 142.3422)
			(xy 209.609165 142.32847) (xy 209.609165 142.31473) (xy 209.622895 142.31473) (xy 209.622895 142.301)
			(xy 209.622895 142.28727) (xy 209.636635 142.28727) (xy 209.636635 142.27354) (xy 209.636635 142.25981)
			(xy 209.650365 142.25981) (xy 209.650365 142.24608) (xy 209.650365 142.23234) (xy 209.664095 142.23234)
			(xy 209.664095 142.21861) (xy 209.664095 142.20488) (xy 209.677825 142.20488) (xy 209.677825 142.19115)
			(xy 209.691555 142.19115) (xy 209.691555 142.17742) (xy 209.691555 142.16368) (xy 209.705285 142.16368)
			(xy 209.705285 142.14995) (xy 209.719025 142.14995) (xy 209.719025 142.13622) (xy 209.732755 142.13622)
			(xy 209.732755 142.12249) (xy 209.746485 142.12249) (xy 209.746485 142.10876) (xy 209.760215 142.10876)
			(xy 209.760215 142.09502) (xy 209.773945 142.09502) (xy 209.773945 142.08129) (xy 209.801415 142.08129)
			(xy 209.801415 142.06756) (xy 209.815145 142.06756) (xy 209.815145 142.05383) (xy 209.842605 142.05383)
			(xy 209.842605 142.0401) (xy 209.870075 142.0401) (xy 209.870075 142.02637) (xy 209.897535 142.02637)
			(xy 209.897535 142.01263) (xy 209.938725 142.01263) (xy 209.938725 141.9989) (xy 209.979925 141.9989)
			(xy 209.979925 141.98517) (xy 210.213365 141.98517)
		)
		(stroke
			(width 0)
			(type default)
		)
		(fill yes)
		(layer "F.Cu")
	)
	(gr_poly
		(pts
			(xy 224.206015 138.00296) (xy 224.233485 138.00296) (xy 224.233485 138.0167) (xy 224.233485 138.03043)
			(xy 224.233485 138.04416) (xy 224.233485 138.05789) (xy 224.233485 138.07162) (xy 224.233485 138.08536)
			(xy 224.233485 138.09909) (xy 224.233485 138.11282) (xy 224.233485 138.12655) (xy 224.233485 138.14028)
			(xy 224.233485 138.15401) (xy 224.233485 138.16775) (xy 224.233485 138.18148) (xy 224.233485 138.19521)
			(xy 224.233485 138.20894) (xy 224.233485 138.22267) (xy 224.233485 138.2364) (xy 224.233485 138.25014)
			(xy 224.233485 138.26387) (xy 224.233485 138.2776) (xy 224.233485 138.29133) (xy 224.233485 138.30506)
			(xy 224.233485 138.31879) (xy 224.233485 138.33253) (xy 224.233485 138.34626) (xy 224.233485 138.35999)
			(xy 224.233485 138.37372) (xy 224.233485 138.38745) (xy 224.233485 138.40118) (xy 224.233485 138.41492)
			(xy 224.233485 138.42865) (xy 224.233485 138.44238) (xy 224.233485 138.45611) (xy 224.233485 138.46984)
			(xy 224.233485 138.48358) (xy 224.233485 138.49731) (xy 224.233485 138.51104) (xy 224.233485 138.52477)
			(xy 224.233485 138.5385) (xy 224.233485 138.55224) (xy 224.233485 138.56597) (xy 224.233485 138.5797)
			(xy 224.233485 138.59343) (xy 224.233485 138.60716) (xy 224.233485 138.62089) (xy 224.233485 138.63463)
			(xy 224.233485 138.64836) (xy 224.233485 138.66209) (xy 224.233485 138.67582) (xy 224.233485 138.68955)
			(xy 224.233485 138.70328) (xy 224.233485 138.71702) (xy 224.233485 138.73075) (xy 224.233485 138.74448)
			(xy 224.233485 138.75821) (xy 224.233485 138.77194) (xy 224.233485 138.78567) (xy 224.233485 138.79941)
			(xy 224.233485 138.81314) (xy 224.233485 138.82687) (xy 224.233485 138.8406) (xy 224.233485 138.85433)
			(xy 224.233485 138.86806) (xy 224.233485 138.8818) (xy 224.233485 138.89553) (xy 224.233485 138.90926)
			(xy 224.233485 138.92299) (xy 224.233485 138.93672) (xy 224.233485 138.95045) (xy 224.233485 138.96419)
			(xy 224.233485 138.97792) (xy 224.233485 138.99165) (xy 224.233485 139.00538) (xy 224.233485 139.01911)
			(xy 224.233485 139.03285) (xy 224.233485 139.04658) (xy 224.233485 139.06031) (xy 224.233485 139.07404)
			(xy 224.233485 139.08777) (xy 224.233485 139.10151) (xy 224.233485 139.11524) (xy 224.233485 139.12897)
			(xy 224.233485 139.1427) (xy 224.233485 139.15643) (xy 224.233485 139.17016) (xy 224.233485 139.1839)
			(xy 224.233485 139.19763) (xy 224.233485 139.21136) (xy 224.233485 139.22509) (xy 224.233485 139.23882)
			(xy 224.233485 139.25255) (xy 224.233485 139.26629) (xy 224.233485 139.28002) (xy 224.233485 139.29375)
			(xy 224.233485 139.30748) (xy 224.233485 139.32121) (xy 224.233485 139.33494) (xy 224.233485 139.34868)
			(xy 224.233485 139.36241) (xy 224.233485 139.37614) (xy 224.233485 139.38987) (xy 224.233485 139.4036)
			(xy 224.233485 139.41733) (xy 224.233485 139.43107) (xy 224.233485 139.4448) (xy 224.233485 139.45853)
			(xy 224.233485 139.47226) (xy 224.233485 139.48599) (xy 224.233485 139.49972) (xy 224.233485 139.51346)
			(xy 224.233485 139.52719) (xy 223.231065 139.52719) (xy 223.231065 139.51346) (xy 223.231065 139.49972)
			(xy 223.231065 139.48599) (xy 223.231065 139.47226) (xy 223.231065 139.45853) (xy 223.231065 139.4448)
			(xy 223.231065 139.43107) (xy 223.231065 139.41733) (xy 223.231065 139.4036) (xy 223.231065 139.38987)
			(xy 223.231065 139.37614) (xy 223.231065 139.36241) (xy 223.231065 139.34868) (xy 223.231065 139.33494)
			(xy 223.231065 139.32121) (xy 223.231065 139.30748) (xy 223.231065 139.29375) (xy 223.231065 139.28002)
			(xy 223.231065 139.26629) (xy 223.231065 139.25255) (xy 223.231065 139.23882) (xy 223.231065 139.22509)
			(xy 223.231065 139.21136) (xy 223.231065 139.19763) (xy 223.231065 139.1839) (xy 223.231065 139.17016)
			(xy 223.231065 139.15643) (xy 223.231065 139.1427) (xy 223.231065 139.12897) (xy 223.231065 139.11524)
			(xy 223.231065 139.10151) (xy 223.231065 139.08777) (xy 223.231065 139.07404) (xy 223.231065 139.06031)
			(xy 223.231065 139.04658) (xy 223.231065 139.03285) (xy 223.231065 139.01911) (xy 223.231065 139.00538)
			(xy 223.231065 138.99165) (xy 223.231065 138.97792) (xy 223.231065 138.96419) (xy 223.231065 138.95045)
			(xy 223.231065 138.93672) (xy 223.231065 138.92299) (xy 223.231065 138.90926) (xy 223.231065 138.89553)
			(xy 223.231065 138.8818) (xy 223.231065 138.86806) (xy 223.231065 138.85433) (xy 223.231065 138.8406)
			(xy 223.231065 138.82687) (xy 223.231065 138.81314) (xy 223.231065 138.79941) (xy 223.231065 138.78567)
			(xy 223.231065 138.77194) (xy 223.231065 138.75821) (xy 223.231065 138.74448) (xy 223.231065 138.73075)
			(xy 223.231065 138.71702) (xy 223.231065 138.70328) (xy 223.231065 138.68955) (xy 223.231065 138.67582)
			(xy 223.231065 138.66209) (xy 223.231065 138.64836) (xy 223.231065 138.63463) (xy 223.231065 138.62089)
			(xy 223.231065 138.60716) (xy 223.231065 138.59343) (xy 223.231065 138.5797) (xy 223.231065 138.56597)
			(xy 223.231065 138.55224) (xy 223.231065 138.5385) (xy 223.231065 138.52477) (xy 223.231065 138.51104)
			(xy 223.231065 138.49731) (xy 223.231065 138.48358) (xy 223.231065 138.46984) (xy 223.231065 138.45611)
			(xy 223.231065 138.44238) (xy 223.231065 138.42865) (xy 223.231065 138.41492) (xy 223.231065 138.40118)
			(xy 223.231065 138.38745) (xy 223.231065 138.37372) (xy 223.231065 138.35999) (xy 223.231065 138.34626)
			(xy 223.231065 138.33253) (xy 223.231065 138.31879) (xy 223.231065 138.30506) (xy 223.231065 138.29133)
			(xy 223.231065 138.2776) (xy 223.231065 138.26387) (xy 223.231065 138.25014) (xy 223.231065 138.2364)
			(xy 223.231065 138.22267) (xy 223.231065 138.20894) (xy 223.231065 138.19521) (xy 223.231065 138.18148)
			(xy 223.231065 138.16775) (xy 223.231065 138.15401) (xy 223.231065 138.14028) (xy 223.231065 138.12655)
			(xy 223.231065 138.11282) (xy 223.231065 138.09909) (xy 223.231065 138.08536) (xy 223.231065 138.07162)
			(xy 223.231065 138.05789) (xy 223.231065 138.04416) (xy 223.231065 138.03043) (xy 223.231065 138.0167)
			(xy 223.231065 138.00296) (xy 223.244795 138.00296) (xy 223.244795 137.98923) (xy 223.258525 137.98923)
			(xy 223.258525 138.00296) (xy 224.151095 138.00296) (xy 224.151095 137.98923) (xy 224.164825 137.98923)
			(xy 224.164825 138.00296) (xy 224.192285 138.00296) (xy 224.192285 137.98923) (xy 224.206015 137.98923)
		)
		(stroke
			(width 0)
			(type default)
		)
		(fill yes)
		(layer "F.Cu")
	)
	(gr_poly
		(pts
			(xy 210.158435 140.13139) (xy 210.227095 140.13139) (xy 210.227095 140.14512) (xy 210.268295 140.14512)
			(xy 210.268295 140.15885) (xy 210.309485 140.15885) (xy 210.309485 140.17258) (xy 210.336955 140.17258)
			(xy 210.336955 140.18631) (xy 210.364415 140.18631) (xy 210.364415 140.20005) (xy 210.378145 140.20005)
			(xy 210.378145 140.21378) (xy 210.405605 140.21378) (xy 210.405605 140.22751) (xy 210.419345 140.22751)
			(xy 210.419345 140.24124) (xy 210.433075 140.24124) (xy 210.433075 140.25497) (xy 210.446805 140.25497)
			(xy 210.446805 140.2687) (xy 210.460535 140.2687) (xy 210.460535 140.28244) (xy 210.474265 140.28244)
			(xy 210.474265 140.29617) (xy 210.487995 140.29617) (xy 210.487995 140.3099) (xy 210.501735 140.3099)
			(xy 210.501735 140.32363) (xy 210.515465 140.32363) (xy 210.515465 140.33736) (xy 210.515465 140.35109)
			(xy 210.529195 140.35109) (xy 210.529195 140.36483) (xy 210.542925 140.36483) (xy 210.542925 140.37856)
			(xy 210.542925 140.39229) (xy 210.556655 140.39229) (xy 210.556655 140.40602) (xy 210.556655 140.41975)
			(xy 210.570385 140.41975) (xy 210.570385 140.43348) (xy 210.570385 140.44722) (xy 210.584125 140.44722)
			(xy 210.584125 140.46095) (xy 210.584125 140.47468) (xy 210.584125 140.48841) (xy 210.597855 140.48841)
			(xy 210.597855 140.50214) (xy 210.597855 140.51587) (xy 210.597855 140.5296) (xy 210.597855 140.54334)
			(xy 210.611585 140.54334) (xy 210.611585 140.55707) (xy 210.611585 140.5708) (xy 210.611585 140.58453)
			(xy 210.611585 140.59827) (xy 210.611585 140.612) (xy 210.611585 140.62573) (xy 210.611585 140.63946)
			(xy 210.611585 140.65319) (xy 210.611585 140.66693) (xy 210.611585 140.68066) (xy 210.611585 140.69439)
			(xy 210.611585 140.70812) (xy 210.611585 140.72185) (xy 210.597855 140.72185) (xy 210.597855 140.73558)
			(xy 210.597855 140.74931) (xy 210.597855 140.76305) (xy 210.597855 140.77678) (xy 210.584125 140.77678)
			(xy 210.584125 140.79051) (xy 210.584125 140.80424) (xy 210.584125 140.81797) (xy 210.570385 140.81797)
			(xy 210.570385 140.8317) (xy 210.570385 140.84544) (xy 210.570385 140.85917) (xy 210.556655 140.85917)
			(xy 210.556655 140.8729) (xy 210.556655 140.88663) (xy 210.542925 140.88663) (xy 210.542925 140.90036)
			(xy 210.529195 140.90036) (xy 210.529195 140.91409) (xy 210.529195 140.92783) (xy 210.515465 140.92783)
			(xy 210.515465 140.94156) (xy 210.501735 140.94156) (xy 210.501735 140.95529) (xy 210.501735 140.96902)
			(xy 210.487995 140.96902) (xy 210.487995 140.98275) (xy 210.474265 140.98275) (xy 210.474265 140.99648)
			(xy 210.460535 140.99648) (xy 210.460535 141.01022) (xy 210.446805 141.01022) (xy 210.446805 141.02395)
			(xy 210.433075 141.02395) (xy 210.433075 141.03768) (xy 210.405605 141.03768) (xy 210.405605 141.05141)
			(xy 210.391875 141.05141) (xy 210.391875 141.06514) (xy 210.364415 141.06514) (xy 210.364415 141.07888)
			(xy 210.350685 141.07888) (xy 210.350685 141.09261) (xy 210.323215 141.09261) (xy 210.323215 141.10634)
			(xy 210.282025 141.10634) (xy 210.282025 141.12007) (xy 210.254565 141.12007) (xy 210.254565 141.1338)
			(xy 210.199635 141.1338) (xy 210.199635 141.14754) (xy 209.993655 141.14754) (xy 209.993655 141.1338)
			(xy 209.952465 141.1338) (xy 209.952465 141.12007) (xy 209.911265 141.12007) (xy 209.911265 141.10634)
			(xy 209.870075 141.10634) (xy 209.870075 141.09261) (xy 209.856345 141.09261) (xy 209.856345 141.07888)
			(xy 209.828875 141.07888) (xy 209.828875 141.06514) (xy 209.801415 141.06514) (xy 209.801415 141.05141)
			(xy 209.787685 141.05141) (xy 209.787685 141.03768) (xy 209.773945 141.03768) (xy 209.773945 141.02395)
			(xy 209.746485 141.02395) (xy 209.746485 141.01022) (xy 209.732755 141.01022) (xy 209.732755 140.99648)
			(xy 209.719025 140.99648) (xy 209.719025 140.98275) (xy 209.705285 140.98275) (xy 209.705285 140.96902)
			(xy 209.705285 140.95529) (xy 209.691555 140.95529) (xy 209.691555 140.94156) (xy 209.677825 140.94156)
			(xy 209.677825 140.92783) (xy 209.664095 140.92783) (xy 209.664095 140.91409) (xy 209.664095 140.90036)
			(xy 209.650365 140.90036) (xy 209.650365 140.88663) (xy 209.650365 140.8729) (xy 209.636635 140.8729)
			(xy 209.636635 140.85917) (xy 209.636635 140.84544) (xy 209.622895 140.84544) (xy 209.622895 140.8317)
			(xy 209.622895 140.81797) (xy 209.609165 140.81797) (xy 209.609165 140.80424) (xy 209.609165 140.79051)
			(xy 209.609165 140.77678) (xy 209.595435 140.77678) (xy 209.595435 140.76305) (xy 209.595435 140.74931)
			(xy 209.595435 140.73558) (xy 209.595435 140.72185) (xy 209.595435 140.70812) (xy 209.581705 140.70812)
			(xy 209.581705 140.69439) (xy 209.581705 140.68066) (xy 209.581705 140.66693) (xy 209.581705 140.65319)
			(xy 209.581705 140.63946) (xy 209.581705 140.62573) (xy 209.581705 140.612) (xy 209.581705 140.59827)
			(xy 209.581705 140.58453) (xy 209.581705 140.5708) (xy 209.595435 140.5708) (xy 209.595435 140.55707)
			(xy 209.595435 140.54334) (xy 209.595435 140.5296) (xy 209.595435 140.51587) (xy 209.595435 140.50214)
			(xy 209.609165 140.50214) (xy 209.609165 140.48841) (xy 209.609165 140.47468) (xy 209.609165 140.46095)
			(xy 209.622895 140.46095) (xy 209.622895 140.44722) (xy 209.622895 140.43348) (xy 209.622895 140.41975)
			(xy 209.636635 140.41975) (xy 209.636635 140.40602) (xy 209.636635 140.39229) (xy 209.650365 140.39229)
			(xy 209.650365 140.37856) (xy 209.650365 140.36483) (xy 209.664095 140.36483) (xy 209.664095 140.35109)
			(xy 209.677825 140.35109) (xy 209.677825 140.33736) (xy 209.677825 140.32363) (xy 209.691555 140.32363)
			(xy 209.691555 140.3099) (xy 209.705285 140.3099) (xy 209.705285 140.29617) (xy 209.719025 140.29617)
			(xy 209.719025 140.28244) (xy 209.732755 140.28244) (xy 209.732755 140.2687) (xy 209.746485 140.2687)
			(xy 209.746485 140.25497) (xy 209.760215 140.25497) (xy 209.760215 140.24124) (xy 209.773945 140.24124)
			(xy 209.773945 140.22751) (xy 209.787685 140.22751) (xy 209.787685 140.21378) (xy 209.815145 140.21378)
			(xy 209.815145 140.20005) (xy 209.842605 140.20005) (xy 209.842605 140.18631) (xy 209.856345 140.18631)
			(xy 209.856345 140.17258) (xy 209.883805 140.17258) (xy 209.883805 140.15885) (xy 209.924995 140.15885)
			(xy 209.924995 140.14512) (xy 209.966195 140.14512) (xy 209.966195 140.13139) (xy 210.034855 140.13139)
			(xy 210.034855 140.11765) (xy 210.158435 140.11765)
		)
		(stroke
			(width 0)
			(type default)
		)
		(fill yes)
		(layer "F.Cu")
	)
	(gr_poly
		(pts
			(xy 210.185905 138.2776) (xy 210.240825 138.2776) (xy 210.240825 138.29133) (xy 210.282025 138.29133)
			(xy 210.282025 138.30506) (xy 210.309485 138.30506) (xy 210.309485 138.31879) (xy 210.336955 138.31879)
			(xy 210.336955 138.33253) (xy 210.364415 138.33253) (xy 210.364415 138.34626) (xy 210.391875 138.34626)
			(xy 210.391875 138.35999) (xy 210.405605 138.35999) (xy 210.405605 138.37372) (xy 210.419345 138.37372)
			(xy 210.419345 138.38745) (xy 210.446805 138.38745) (xy 210.446805 138.40118) (xy 210.460535 138.40118)
			(xy 210.460535 138.41492) (xy 210.474265 138.41492) (xy 210.474265 138.42865) (xy 210.487995 138.42865)
			(xy 210.487995 138.44238) (xy 210.487995 138.45611) (xy 210.501735 138.45611) (xy 210.501735 138.46984)
			(xy 210.515465 138.46984) (xy 210.515465 138.48358) (xy 210.529195 138.48358) (xy 210.529195 138.49731)
			(xy 210.529195 138.51104) (xy 210.542925 138.51104) (xy 210.542925 138.52477) (xy 210.542925 138.5385)
			(xy 210.556655 138.5385) (xy 210.556655 138.55224) (xy 210.556655 138.56597) (xy 210.570385 138.56597)
			(xy 210.570385 138.5797) (xy 210.570385 138.59343) (xy 210.584125 138.59343) (xy 210.584125 138.60716)
			(xy 210.584125 138.62089) (xy 210.584125 138.63463) (xy 210.597855 138.63463) (xy 210.597855 138.64836)
			(xy 210.597855 138.66209) (xy 210.597855 138.67582) (xy 210.597855 138.68955) (xy 210.611585 138.68955)
			(xy 210.611585 138.70328) (xy 210.611585 138.71702) (xy 210.611585 138.73075) (xy 210.611585 138.74448)
			(xy 210.611585 138.75821) (xy 210.611585 138.77194) (xy 210.611585 138.78567) (xy 210.611585 138.79941)
			(xy 210.611585 138.81314) (xy 210.611585 138.82687) (xy 210.611585 138.8406) (xy 210.611585 138.85433)
			(xy 210.611585 138.86806) (xy 210.597855 138.86806) (xy 210.597855 138.8818) (xy 210.597855 138.89553)
			(xy 210.597855 138.90926) (xy 210.597855 138.92299) (xy 210.584125 138.92299) (xy 210.584125 138.93672)
			(xy 210.584125 138.95045) (xy 210.584125 138.96419) (xy 210.570385 138.96419) (xy 210.570385 138.97792)
			(xy 210.570385 138.99165) (xy 210.556655 138.99165) (xy 210.556655 139.00538) (xy 210.556655 139.01911)
			(xy 210.542925 139.01911) (xy 210.542925 139.03285) (xy 210.542925 139.04658) (xy 210.529195 139.04658)
			(xy 210.529195 139.06031) (xy 210.529195 139.07404) (xy 210.515465 139.07404) (xy 210.515465 139.08777)
			(xy 210.501735 139.08777) (xy 210.501735 139.10151) (xy 210.487995 139.10151) (xy 210.487995 139.11524)
			(xy 210.487995 139.12897) (xy 210.474265 139.12897) (xy 210.474265 139.1427) (xy 210.460535 139.1427)
			(xy 210.460535 139.15643) (xy 210.433075 139.15643) (xy 210.433075 139.17016) (xy 210.419345 139.17016)
			(xy 210.419345 139.1839) (xy 210.405605 139.1839) (xy 210.405605 139.19763) (xy 210.391875 139.19763)
			(xy 210.391875 139.21136) (xy 210.364415 139.21136) (xy 210.364415 139.22509) (xy 210.336955 139.22509)
			(xy 210.336955 139.23882) (xy 210.309485 139.23882) (xy 210.309485 139.25255) (xy 210.282025 139.25255)
			(xy 210.282025 139.26629) (xy 210.240825 139.26629) (xy 210.240825 139.28002) (xy 210.172165 139.28002)
			(xy 210.172165 139.29375) (xy 210.021115 139.29375) (xy 210.021115 139.28002) (xy 209.952465 139.28002)
			(xy 209.952465 139.26629) (xy 209.911265 139.26629) (xy 209.911265 139.25255) (xy 209.883805 139.25255)
			(xy 209.883805 139.23882) (xy 209.856345 139.23882) (xy 209.856345 139.22509) (xy 209.828875 139.22509)
			(xy 209.828875 139.21136) (xy 209.815145 139.21136) (xy 209.815145 139.19763) (xy 209.787685 139.19763)
			(xy 209.787685 139.1839) (xy 209.773945 139.1839) (xy 209.773945 139.17016) (xy 209.760215 139.17016)
			(xy 209.760215 139.15643) (xy 209.746485 139.15643) (xy 209.746485 139.1427) (xy 209.732755 139.1427)
			(xy 209.732755 139.12897) (xy 209.719025 139.12897) (xy 209.719025 139.11524) (xy 209.705285 139.11524)
			(xy 209.705285 139.10151) (xy 209.691555 139.10151) (xy 209.691555 139.08777) (xy 209.677825 139.08777)
			(xy 209.677825 139.07404) (xy 209.677825 139.06031) (xy 209.664095 139.06031) (xy 209.664095 139.04658)
			(xy 209.650365 139.04658) (xy 209.650365 139.03285) (xy 209.650365 139.01911) (xy 209.636635 139.01911)
			(xy 209.636635 139.00538) (xy 209.636635 138.99165) (xy 209.622895 138.99165) (xy 209.622895 138.97792)
			(xy 209.622895 138.96419) (xy 209.622895 138.95045) (xy 209.609165 138.95045) (xy 209.609165 138.93672)
			(xy 209.609165 138.92299) (xy 209.609165 138.90926) (xy 209.595435 138.90926) (xy 209.595435 138.89553)
			(xy 209.595435 138.8818) (xy 209.595435 138.86806) (xy 209.595435 138.85433) (xy 209.581705 138.85433)
			(xy 209.581705 138.8406) (xy 209.581705 138.82687) (xy 209.581705 138.81314) (xy 209.581705 138.79941)
			(xy 209.581705 138.78567) (xy 209.581705 138.77194) (xy 209.581705 138.75821) (xy 209.581705 138.74448)
			(xy 209.581705 138.73075) (xy 209.581705 138.71702) (xy 209.581705 138.70328) (xy 209.595435 138.70328)
			(xy 209.595435 138.68955) (xy 209.595435 138.67582) (xy 209.595435 138.66209) (xy 209.595435 138.64836)
			(xy 209.609165 138.64836) (xy 209.609165 138.63463) (xy 209.609165 138.62089) (xy 209.609165 138.60716)
			(xy 209.609165 138.59343) (xy 209.622895 138.59343) (xy 209.622895 138.5797) (xy 209.622895 138.56597)
			(xy 209.636635 138.56597) (xy 209.636635 138.55224) (xy 209.636635 138.5385) (xy 209.650365 138.5385)
			(xy 209.650365 138.52477) (xy 209.650365 138.51104) (xy 209.664095 138.51104) (xy 209.664095 138.49731)
			(xy 209.677825 138.49731) (xy 209.677825 138.48358) (xy 209.677825 138.46984) (xy 209.691555 138.46984)
			(xy 209.691555 138.45611) (xy 209.705285 138.45611) (xy 209.705285 138.44238) (xy 209.719025 138.44238)
			(xy 209.719025 138.42865) (xy 209.732755 138.42865) (xy 209.732755 138.41492) (xy 209.746485 138.41492)
			(xy 209.746485 138.40118) (xy 209.760215 138.40118) (xy 209.760215 138.38745) (xy 209.773945 138.38745)
			(xy 209.773945 138.37372) (xy 209.787685 138.37372) (xy 209.787685 138.35999) (xy 209.815145 138.35999)
			(xy 209.815145 138.34626) (xy 209.828875 138.34626) (xy 209.828875 138.33253) (xy 209.856345 138.33253)
			(xy 209.856345 138.31879) (xy 209.883805 138.31879) (xy 209.883805 138.30506) (xy 209.911265 138.30506)
			(xy 209.911265 138.29133) (xy 209.952465 138.29133) (xy 209.952465 138.2776) (xy 210.021115 138.2776)
			(xy 210.021115 138.26387) (xy 210.185905 138.26387)
		)
		(stroke
			(width 0)
			(type default)
		)
		(fill yes)
		(layer "F.Cu")
	)
	(gr_poly
		(pts
			(xy 210.199635 136.42381) (xy 210.254565 136.42381) (xy 210.254565 136.43755) (xy 210.295755 136.43755)
			(xy 210.295755 136.45128) (xy 210.323215 136.45128) (xy 210.323215 136.46501) (xy 210.350685 136.46501)
			(xy 210.350685 136.47874) (xy 210.364415 136.47874) (xy 210.364415 136.49247) (xy 210.391875 136.49247)
			(xy 210.391875 136.5062) (xy 210.405605 136.5062) (xy 210.405605 136.51994) (xy 210.433075 136.51994)
			(xy 210.433075 136.53367) (xy 210.446805 136.53367) (xy 210.446805 136.5474) (xy 210.460535 136.5474)
			(xy 210.460535 136.56113) (xy 210.474265 136.56113) (xy 210.474265 136.57486) (xy 210.487995 136.57486)
			(xy 210.487995 136.58859) (xy 210.501735 136.58859) (xy 210.501735 136.60233) (xy 210.501735 136.61606)
			(xy 210.515465 136.61606) (xy 210.515465 136.62979) (xy 210.529195 136.62979) (xy 210.529195 136.64352)
			(xy 210.529195 136.65725) (xy 210.542925 136.65725) (xy 210.542925 136.67098) (xy 210.556655 136.67098)
			(xy 210.556655 136.68472) (xy 210.556655 136.69845) (xy 210.570385 136.69845) (xy 210.570385 136.71218)
			(xy 210.570385 136.72591) (xy 210.570385 136.73964) (xy 210.584125 136.73964) (xy 210.584125 136.75337)
			(xy 210.584125 136.76711) (xy 210.584125 136.78084) (xy 210.597855 136.78084) (xy 210.597855 136.79457)
			(xy 210.597855 136.8083) (xy 210.597855 136.82203) (xy 210.597855 136.83576) (xy 210.611585 136.83576)
			(xy 210.611585 136.8495) (xy 210.611585 136.86323) (xy 210.611585 136.87696) (xy 210.611585 136.89069)
			(xy 210.611585 136.90442) (xy 210.611585 136.91816) (xy 210.611585 136.93189) (xy 210.611585 136.94562)
			(xy 210.611585 136.95935) (xy 210.611585 136.97308) (xy 210.611585 136.98682) (xy 210.611585 137.00055)
			(xy 210.611585 137.01428) (xy 210.597855 137.01428) (xy 210.597855 137.02801) (xy 210.597855 137.04174)
			(xy 210.597855 137.05547) (xy 210.597855 137.06921) (xy 210.584125 137.06921) (xy 210.584125 137.08294)
			(xy 210.584125 137.09667) (xy 210.584125 137.1104) (xy 210.570385 137.1104) (xy 210.570385 137.12413)
			(xy 210.570385 137.13786) (xy 210.556655 137.13786) (xy 210.556655 137.1516) (xy 210.556655 137.16533)
			(xy 210.542925 137.16533) (xy 210.542925 137.17906) (xy 210.542925 137.19279) (xy 210.529195 137.19279)
			(xy 210.529195 137.20652) (xy 210.515465 137.20652) (xy 210.515465 137.22025) (xy 210.515465 137.23399)
			(xy 210.501735 137.23399) (xy 210.501735 137.24772) (xy 210.487995 137.24772) (xy 210.487995 137.26145)
			(xy 210.474265 137.26145) (xy 210.474265 137.27518) (xy 210.460535 137.27518) (xy 210.460535 137.28891)
			(xy 210.446805 137.28891) (xy 210.446805 137.30264) (xy 210.433075 137.30264) (xy 210.433075 137.31638)
			(xy 210.419345 137.31638) (xy 210.419345 137.33011) (xy 210.405605 137.33011) (xy 210.405605 137.34384)
			(xy 210.378145 137.34384) (xy 210.378145 137.35757) (xy 210.364415 137.35757) (xy 210.364415 137.3713)
			(xy 210.336955 137.3713) (xy 210.336955 137.38503) (xy 210.309485 137.38503) (xy 210.309485 137.39877)
			(xy 210.268295 137.39877) (xy 210.268295 137.4125) (xy 210.227095 137.4125) (xy 210.227095 137.42623)
			(xy 210.144705 137.42623) (xy 210.144705 137.43996) (xy 210.048585 137.43996) (xy 210.048585 137.42623)
			(xy 209.966195 137.42623) (xy 209.966195 137.4125) (xy 209.924995 137.4125) (xy 209.924995 137.39877)
			(xy 209.897535 137.39877) (xy 209.897535 137.38503) (xy 209.856345 137.38503) (xy 209.856345 137.3713)
			(xy 209.842605 137.3713) (xy 209.842605 137.35757) (xy 209.815145 137.35757) (xy 209.815145 137.34384)
			(xy 209.801415 137.34384) (xy 209.801415 137.33011) (xy 209.773945 137.33011) (xy 209.773945 137.31638)
			(xy 209.760215 137.31638) (xy 209.760215 137.30264) (xy 209.746485 137.30264) (xy 209.746485 137.28891)
			(xy 209.732755 137.28891) (xy 209.732755 137.27518) (xy 209.719025 137.27518) (xy 209.719025 137.26145)
			(xy 209.705285 137.26145) (xy 209.705285 137.24772) (xy 209.691555 137.24772) (xy 209.691555 137.23399)
			(xy 209.677825 137.23399) (xy 209.677825 137.22025) (xy 209.677825 137.20652) (xy 209.664095 137.20652)
			(xy 209.664095 137.19279) (xy 209.664095 137.17906) (xy 209.650365 137.17906) (xy 209.650365 137.16533)
			(xy 209.636635 137.16533) (xy 209.636635 137.1516) (xy 209.636635 137.13786) (xy 209.622895 137.13786)
			(xy 209.622895 137.12413) (xy 209.622895 137.1104) (xy 209.622895 137.09667) (xy 209.609165 137.09667)
			(xy 209.609165 137.08294) (xy 209.609165 137.06921) (xy 209.609165 137.05547) (xy 209.595435 137.05547)
			(xy 209.595435 137.04174) (xy 209.595435 137.02801) (xy 209.595435 137.01428) (xy 209.595435 137.00055)
			(xy 209.595435 136.98682) (xy 209.581705 136.98682) (xy 209.581705 136.97308) (xy 209.581705 136.95935)
			(xy 209.581705 136.94562) (xy 209.581705 136.93189) (xy 209.581705 136.91816) (xy 209.581705 136.90442)
			(xy 209.581705 136.89069) (xy 209.581705 136.87696) (xy 209.581705 136.86323) (xy 209.581705 136.8495)
			(xy 209.595435 136.8495) (xy 209.595435 136.83576) (xy 209.595435 136.82203) (xy 209.595435 136.8083)
			(xy 209.595435 136.79457) (xy 209.595435 136.78084) (xy 209.609165 136.78084) (xy 209.609165 136.76711)
			(xy 209.609165 136.75337) (xy 209.609165 136.73964) (xy 209.622895 136.73964) (xy 209.622895 136.72591)
			(xy 209.622895 136.71218) (xy 209.636635 136.71218) (xy 209.636635 136.69845) (xy 209.636635 136.68472)
			(xy 209.650365 136.68472) (xy 209.650365 136.67098) (xy 209.650365 136.65725) (xy 209.664095 136.65725)
			(xy 209.664095 136.64352) (xy 209.664095 136.62979) (xy 209.677825 136.62979) (xy 209.677825 136.61606)
			(xy 209.691555 136.61606) (xy 209.691555 136.60233) (xy 209.705285 136.60233) (xy 209.705285 136.58859)
			(xy 209.705285 136.57486) (xy 209.719025 136.57486) (xy 209.719025 136.56113) (xy 209.732755 136.56113)
			(xy 209.732755 136.5474) (xy 209.746485 136.5474) (xy 209.746485 136.53367) (xy 209.773945 136.53367)
			(xy 209.773945 136.51994) (xy 209.787685 136.51994) (xy 209.787685 136.5062) (xy 209.801415 136.5062)
			(xy 209.801415 136.49247) (xy 209.828875 136.49247) (xy 209.828875 136.47874) (xy 209.842605 136.47874)
			(xy 209.842605 136.46501) (xy 209.870075 136.46501) (xy 209.870075 136.45128) (xy 209.911265 136.45128)
			(xy 209.911265 136.43755) (xy 209.938725 136.43755) (xy 209.938725 136.42381) (xy 209.993655 136.42381)
			(xy 209.993655 136.41008) (xy 210.199635 136.41008)
		)
		(stroke
			(width 0)
			(type default)
		)
		(fill yes)
		(layer "F.Cu")
	)
	(gr_poly
		(pts
			(xy 231.003235 130.68394) (xy 231.140555 130.68394) (xy 231.140555 130.69767) (xy 231.209215 130.69767)
			(xy 231.209215 130.71141) (xy 231.264135 130.71141) (xy 231.264135 130.72514) (xy 231.291605 130.72514)
			(xy 231.291605 130.73887) (xy 231.332795 130.73887) (xy 231.332795 130.7526) (xy 231.360265 130.7526)
			(xy 231.360265 130.76633) (xy 231.401455 130.76633) (xy 231.401455 130.78006) (xy 231.415185 130.78006)
			(xy 231.415185 130.7938) (xy 231.442655 130.7938) (xy 231.442655 130.80753) (xy 231.470115 130.80753)
			(xy 231.470115 130.82126) (xy 231.483845 130.82126) (xy 231.483845 130.83499) (xy 231.511315 130.83499)
			(xy 231.511315 130.84872) (xy 231.525045 130.84872) (xy 231.525045 130.86245) (xy 231.552505 130.86245)
			(xy 231.552505 130.87619) (xy 231.566235 130.87619) (xy 231.566235 130.88992) (xy 231.579965 130.88992)
			(xy 231.579965 130.90365) (xy 231.593705 130.90365) (xy 231.593705 130.91738) (xy 231.607435 130.91738)
			(xy 231.607435 130.93111) (xy 231.621165 130.93111) (xy 231.621165 130.94484) (xy 231.634895 130.94484)
			(xy 231.634895 130.95858) (xy 231.648625 130.95858) (xy 231.648625 130.97231) (xy 231.662355 130.97231)
			(xy 231.662355 130.98604) (xy 231.676095 130.98604) (xy 231.676095 130.99977) (xy 231.689825 130.99977)
			(xy 231.689825 131.0135) (xy 231.703555 131.0135) (xy 231.703555 131.02723) (xy 231.703555 131.04097)
			(xy 231.717285 131.04097) (xy 231.717285 131.0547) (xy 231.731015 131.0547) (xy 231.731015 131.06843)
			(xy 231.731015 131.08216) (xy 231.744745 131.08216) (xy 231.744745 131.09589) (xy 231.758485 131.09589)
			(xy 231.758485 131.10962) (xy 231.758485 131.12336) (xy 231.772215 131.12336) (xy 231.772215 131.13709)
			(xy 231.772215 131.15082) (xy 231.785945 131.15082) (xy 231.785945 131.16455) (xy 231.799675 131.16455)
			(xy 231.799675 131.17828) (xy 231.799675 131.19202) (xy 231.813405 131.19202) (xy 231.813405 131.20575)
			(xy 231.813405 131.21948) (xy 231.813405 131.23321) (xy 231.827145 131.23321) (xy 231.827145 131.24694)
			(xy 231.827145 131.26068) (xy 231.840875 131.26068) (xy 231.840875 131.27441) (xy 231.840875 131.28814)
			(xy 231.840875 131.30187) (xy 231.854605 131.30187) (xy 231.854605 131.3156) (xy 231.854605 131.32933)
			(xy 231.854605 131.34307) (xy 231.854605 131.3568) (xy 231.868335 131.3568) (xy 231.868335 131.37053)
			(xy 231.868335 131.38426) (xy 231.868335 131.39799) (xy 231.868335 131.41172) (xy 231.882065 131.41172)
			(xy 231.882065 131.42546) (xy 231.882065 131.43919) (xy 231.882065 131.45292) (xy 231.882065 131.46665)
			(xy 231.882065 131.48038) (xy 231.882065 131.49411) (xy 231.882065 131.50785) (xy 231.882065 131.52158)
			(xy 231.882065 131.53531) (xy 231.882065 131.54904) (xy 231.895805 131.54904) (xy 231.895805 131.56277)
			(xy 231.895805 131.5765) (xy 231.895805 131.59024) (xy 231.895805 131.60397) (xy 231.882065 131.60397)
			(xy 231.882065 131.6177) (xy 231.882065 131.63143) (xy 231.882065 131.64516) (xy 231.882065 131.6589)
			(xy 231.882065 131.67263) (xy 231.882065 131.68636) (xy 231.882065 131.70009) (xy 231.882065 131.71382)
			(xy 231.882065 131.72756) (xy 231.868335 131.72756) (xy 231.868335 131.74129) (xy 231.868335 131.75502)
			(xy 231.868335 131.76875) (xy 231.868335 131.78248) (xy 231.868335 131.79621) (xy 231.854605 131.79621)
			(xy 231.854605 131.80995) (xy 231.854605 131.82368) (xy 231.854605 131.83741) (xy 231.840875 131.83741)
			(xy 231.840875 131.85114) (xy 231.840875 131.86487) (xy 231.840875 131.8786) (xy 231.827145 131.8786)
			(xy 231.827145 131.89233) (xy 231.827145 131.90607) (xy 231.827145 131.9198) (xy 231.813405 131.9198)
			(xy 231.813405 131.93353) (xy 231.813405 131.94726) (xy 231.799675 131.94726) (xy 231.799675 131.96099)
			(xy 231.799675 131.97472) (xy 231.785945 131.97472) (xy 231.785945 131.98846) (xy 231.785945 132.00219)
			(xy 231.772215 132.00219) (xy 231.772215 132.01592) (xy 231.772215 132.02965) (xy 231.758485 132.02965)
			(xy 231.758485 132.04338) (xy 231.758485 132.05711) (xy 231.744745 132.05711) (xy 231.744745 132.07085)
			(xy 231.731015 132.07085) (xy 231.731015 132.08458) (xy 231.731015 132.09831) (xy 231.717285 132.09831)
			(xy 231.717285 132.11204) (xy 231.703555 132.11204) (xy 231.703555 132.12577) (xy 231.689825 132.12577)
			(xy 231.689825 132.13951) (xy 231.689825 132.15324) (xy 231.676095 132.15324) (xy 231.676095 132.16697)
			(xy 231.662355 132.16697) (xy 231.662355 132.1807) (xy 231.648625 132.1807) (xy 231.648625 132.19443)
			(xy 231.634895 132.19443) (xy 231.634895 132.20817) (xy 231.621165 132.20817) (xy 231.621165 132.2219)
			(xy 231.607435 132.2219) (xy 231.607435 132.23563) (xy 231.593705 132.23563) (xy 231.593705 132.24936)
			(xy 231.579965 132.24936) (xy 231.579965 132.26309) (xy 231.552505 132.26309) (xy 231.552505 132.27682)
			(xy 231.538775 132.27682) (xy 231.538775 132.29056) (xy 231.525045 132.29056) (xy 231.525045 132.30429)
			(xy 231.511315 132.30429) (xy 231.511315 132.31802) (xy 231.483845 132.31802) (xy 231.483845 132.33175)
			(xy 231.470115 132.33175) (xy 231.470115 132.34548) (xy 231.442655 132.34548) (xy 231.442655 132.35921)
			(xy 231.415185 132.35921) (xy 231.415185 132.37295) (xy 231.387725 132.37295) (xy 231.387725 132.38668)
			(xy 231.360265 132.38668) (xy 231.360265 132.40041) (xy 231.332795 132.40041) (xy 231.332795 132.41414)
			(xy 231.291605 132.41414) (xy 231.291605 132.42787) (xy 231.250405 132.42787) (xy 231.250405 132.4416)
			(xy 231.195475 132.4416) (xy 231.195475 132.45534) (xy 231.126825 132.45534) (xy 231.126825 132.46907)
			(xy 229.794845 132.46907) (xy 229.794845 132.45534) (xy 229.726185 132.45534) (xy 229.726185 132.4416)
			(xy 229.684985 132.4416) (xy 229.684985 132.42787) (xy 229.643795 132.42787) (xy 229.643795 132.41414)
			(xy 229.602595 132.41414) (xy 229.602595 132.40041) (xy 229.575135 132.40041) (xy 229.575135 132.38668)
			(xy 229.533935 132.38668) (xy 229.533935 132.37295) (xy 229.520205 132.37295) (xy 229.520205 132.35921)
			(xy 229.492745 132.35921) (xy 229.492745 132.34548) (xy 229.465275 132.34548) (xy 229.465275 132.33175)
			(xy 229.451545 132.33175) (xy 229.451545 132.31802) (xy 229.424085 132.31802) (xy 229.424085 132.30429)
			(xy 229.410355 132.30429) (xy 229.410355 132.29056) (xy 229.382885 132.29056) (xy 229.382885 132.27682)
			(xy 229.369155 132.27682) (xy 229.369155 132.26309) (xy 229.355425 132.26309) (xy 229.355425 132.24936)
			(xy 229.341695 132.24936) (xy 229.341695 132.23563) (xy 229.327965 132.23563) (xy 229.327965 132.2219)
			(xy 229.314235 132.2219) (xy 229.314235 132.20817) (xy 229.300495 132.20817) (xy 229.300495 132.19443)
			(xy 229.286765 132.19443) (xy 229.286765 132.1807) (xy 229.273035 132.1807) (xy 229.273035 132.16697)
			(xy 229.259305 132.16697) (xy 229.259305 132.15324) (xy 229.245575 132.15324) (xy 229.245575 132.13951)
			(xy 229.231845 132.13951) (xy 229.231845 132.12577) (xy 229.231845 132.11204) (xy 229.218105 132.11204)
			(xy 229.218105 132.09831) (xy 229.204375 132.09831) (xy 229.204375 132.08458) (xy 229.190645 132.08458)
			(xy 229.190645 132.07085) (xy 229.190645 132.05711) (xy 229.176915 132.05711) (xy 229.176915 132.04338)
			(xy 229.176915 132.02965) (xy 229.163185 132.02965) (xy 229.163185 132.01592) (xy 229.149445 132.01592)
			(xy 229.149445 132.00219) (xy 229.149445 131.98846) (xy 229.135715 131.98846) (xy 229.135715 131.97472)
			(xy 229.135715 131.96099) (xy 229.121985 131.96099) (xy 229.121985 131.94726) (xy 229.121985 131.93353)
			(xy 229.108255 131.93353) (xy 229.108255 131.9198) (xy 229.108255 131.90607) (xy 229.108255 131.89233)
			(xy 229.094525 131.89233) (xy 229.094525 131.8786) (xy 229.094525 131.86487) (xy 229.094525 131.85114)
			(xy 229.080785 131.85114) (xy 229.080785 131.83741) (xy 229.080785 131.82368) (xy 229.080785 131.80995)
			(xy 229.067055 131.80995) (xy 229.067055 131.79621) (xy 229.067055 131.78248) (xy 229.067055 131.76875)
			(xy 229.067055 131.75502) (xy 229.067055 131.74129) (xy 229.053325 131.74129) (xy 229.053325 131.72756)
			(xy 229.053325 131.71382) (xy 229.053325 131.70009) (xy 229.053325 131.68636) (xy 229.053325 131.67263)
			(xy 229.039595 131.67263) (xy 229.039595 131.6589) (xy 229.039595 131.64516) (xy 229.039595 131.63143)
			(xy 229.039595 131.6177) (xy 229.039595 131.60397) (xy 229.039595 131.59024) (xy 229.039595 131.5765)
			(xy 229.039595 131.56277) (xy 229.039595 131.54904) (xy 229.039595 131.53531) (xy 229.039595 131.52158)
			(xy 229.039595 131.50785) (xy 229.039595 131.49411) (xy 229.053325 131.49411) (xy 229.053325 131.48038)
			(xy 229.053325 131.46665) (xy 229.053325 131.45292) (xy 229.053325 131.43919) (xy 229.053325 131.42546)
			(xy 229.053325 131.41172) (xy 229.053325 131.39799) (xy 229.067055 131.39799) (xy 229.067055 131.38426)
			(xy 229.067055 131.37053) (xy 229.067055 131.3568) (xy 229.067055 131.34307) (xy 229.080785 131.34307)
			(xy 229.080785 131.32933) (xy 229.080785 131.3156) (xy 229.080785 131.30187) (xy 229.080785 131.28814)
			(xy 229.094525 131.28814) (xy 229.094525 131.27441) (xy 229.094525 131.26068) (xy 229.108255 131.26068)
			(xy 229.108255 131.24694) (xy 229.108255 131.23321) (xy 229.108255 131.21948) (xy 229.121985 131.21948)
			(xy 229.121985 131.20575) (xy 229.121985 131.19202) (xy 229.135715 131.19202) (xy 229.135715 131.17828)
			(xy 229.135715 131.16455) (xy 229.149445 131.16455) (xy 229.149445 131.15082) (xy 229.149445 131.13709)
			(xy 229.163185 131.13709) (xy 229.163185 131.12336) (xy 229.163185 131.10962) (xy 229.176915 131.10962)
			(xy 229.176915 131.09589) (xy 229.190645 131.09589) (xy 229.190645 131.08216) (xy 229.190645 131.06843)
			(xy 229.204375 131.06843) (xy 229.204375 131.0547) (xy 229.218105 131.0547) (xy 229.218105 131.04097)
			(xy 229.218105 131.02723) (xy 229.231845 131.02723) (xy 229.231845 131.0135) (xy 229.245575 131.0135)
			(xy 229.245575 130.99977) (xy 229.259305 130.99977) (xy 229.259305 130.98604) (xy 229.273035 130.98604)
			(xy 229.273035 130.97231) (xy 229.286765 130.97231) (xy 229.286765 130.95858) (xy 229.300495 130.95858)
			(xy 229.300495 130.94484) (xy 229.314235 130.94484) (xy 229.314235 130.93111) (xy 229.327965 130.93111)
			(xy 229.327965 130.91738) (xy 229.341695 130.91738) (xy 229.341695 130.90365) (xy 229.355425 130.90365)
			(xy 229.355425 130.88992) (xy 229.369155 130.88992) (xy 229.369155 130.87619) (xy 229.382885 130.87619)
			(xy 229.382885 130.86245) (xy 229.396625 130.86245) (xy 229.396625 130.84872) (xy 229.424085 130.84872)
			(xy 229.424085 130.83499) (xy 229.437815 130.83499) (xy 229.437815 130.82126) (xy 229.465275 130.82126)
			(xy 229.465275 130.80753) (xy 229.479015 130.80753) (xy 229.479015 130.7938) (xy 229.506475 130.7938)
			(xy 229.506475 130.78006) (xy 229.533935 130.78006) (xy 229.533935 130.76633) (xy 229.561405 130.76633)
			(xy 229.561405 130.7526) (xy 229.602595 130.7526) (xy 229.602595 130.73887) (xy 229.630055 130.73887)
			(xy 229.630055 130.72514) (xy 229.671255 130.72514) (xy 229.671255 130.71141) (xy 229.726185 130.71141)
			(xy 229.726185 130.69767) (xy 229.781115 130.69767) (xy 229.781115 130.68394) (xy 229.932155 130.68394)
			(xy 229.932155 130.67021) (xy 230.975775 130.67021) (xy 230.975775 130.68394) (xy 230.989505 130.68394)
			(xy 230.989505 130.67021) (xy 231.003235 130.67021)
		)
		(stroke
			(width 0)
			(type default)
		)
		(fill yes)
		(layer "F.Cu")
	)
	(gr_poly
		(pts
			(xy 234.161535 137.85191) (xy 234.243925 137.85191) (xy 234.243925 137.86565) (xy 234.298855 137.86565)
			(xy 234.298855 137.87938) (xy 234.340055 137.87938) (xy 234.340055 137.89311) (xy 234.381245 137.89311)
			(xy 234.381245 137.90684) (xy 234.408705 137.90684) (xy 234.408705 137.92057) (xy 234.449905 137.92057)
			(xy 234.449905 137.9343) (xy 234.477365 137.9343) (xy 234.477365 137.94804) (xy 234.491105 137.94804)
			(xy 234.491105 137.96177) (xy 234.518565 137.96177) (xy 234.518565 137.9755) (xy 234.546025 137.9755)
			(xy 234.546025 137.98923) (xy 234.559765 137.98923) (xy 234.559765 138.00296) (xy 234.587225 138.00296)
			(xy 234.587225 138.0167) (xy 234.600955 138.0167) (xy 234.600955 138.03043) (xy 234.614685 138.03043)
			(xy 234.614685 138.04416) (xy 234.628415 138.04416) (xy 234.628415 138.05789) (xy 234.655885 138.05789)
			(xy 234.655885 138.07162) (xy 234.669615 138.07162) (xy 234.669615 138.08536) (xy 234.683345 138.08536)
			(xy 234.683345 138.09909) (xy 234.697075 138.09909) (xy 234.697075 138.11282) (xy 234.710805 138.11282)
			(xy 234.710805 138.12655) (xy 234.724545 138.12655) (xy 234.724545 138.14028) (xy 234.738275 138.14028)
			(xy 234.738275 138.15401) (xy 234.752005 138.15401) (xy 234.752005 138.16775) (xy 234.752005 138.18148)
			(xy 234.765735 138.18148) (xy 234.765735 138.19521) (xy 234.779465 138.19521) (xy 234.779465 138.20894)
			(xy 234.793195 138.20894) (xy 234.793195 138.22267) (xy 234.793195 138.2364) (xy 234.806935 138.2364)
			(xy 234.806935 138.25014) (xy 234.820665 138.25014) (xy 234.820665 138.26387) (xy 234.820665 138.2776)
			(xy 234.834395 138.2776) (xy 234.834395 138.29133) (xy 234.834395 138.30506) (xy 234.848125 138.30506)
			(xy 234.848125 138.31879) (xy 234.861855 138.31879) (xy 234.861855 138.33253) (xy 234.861855 138.34626)
			(xy 234.875585 138.34626) (xy 234.875585 138.35999) (xy 234.875585 138.37372) (xy 234.875585 138.38745)
			(xy 234.889325 138.38745) (xy 234.889325 138.40118) (xy 234.889325 138.41492) (xy 234.903055 138.41492)
			(xy 234.903055 138.42865) (xy 234.903055 138.44238) (xy 234.903055 138.45611) (xy 234.916785 138.45611)
			(xy 234.916785 138.46984) (xy 234.916785 138.48358) (xy 234.916785 138.49731) (xy 234.930515 138.49731)
			(xy 234.930515 138.51104) (xy 234.930515 138.52477) (xy 234.930515 138.5385) (xy 234.930515 138.55224)
			(xy 234.944245 138.55224) (xy 234.944245 138.56597) (xy 234.944245 138.5797) (xy 234.944245 138.59343)
			(xy 234.944245 138.60716) (xy 234.944245 138.62089) (xy 234.944245 138.63463) (xy 234.957975 138.63463)
			(xy 234.957975 138.64836) (xy 234.957975 138.66209) (xy 234.957975 138.67582) (xy 234.957975 138.68955)
			(xy 234.957975 138.70328) (xy 234.957975 138.71702) (xy 234.957975 138.73075) (xy 234.957975 138.74448)
			(xy 234.957975 138.75821) (xy 234.957975 138.77194) (xy 234.957975 138.78567) (xy 234.957975 138.79941)
			(xy 234.957975 138.81314) (xy 234.957975 138.82687) (xy 234.957975 138.8406) (xy 234.944245 138.8406)
			(xy 234.944245 138.85433) (xy 234.944245 138.86806) (xy 234.944245 138.8818) (xy 234.944245 138.89553)
			(xy 234.944245 138.90926) (xy 234.944245 138.92299) (xy 234.930515 138.92299) (xy 234.930515 138.93672)
			(xy 234.930515 138.95045) (xy 234.930515 138.96419) (xy 234.930515 138.97792) (xy 234.916785 138.97792)
			(xy 234.916785 138.99165) (xy 234.916785 139.00538) (xy 234.916785 139.01911) (xy 234.903055 139.01911)
			(xy 234.903055 139.03285) (xy 234.903055 139.04658) (xy 234.903055 139.06031) (xy 234.889325 139.06031)
			(xy 234.889325 139.07404) (xy 234.889325 139.08777) (xy 234.875585 139.08777) (xy 234.875585 139.10151)
			(xy 234.875585 139.11524) (xy 234.861855 139.11524) (xy 234.861855 139.12897) (xy 234.861855 139.1427)
			(xy 234.848125 139.1427) (xy 234.848125 139.15643) (xy 234.848125 139.17016) (xy 234.834395 139.17016)
			(xy 234.834395 139.1839) (xy 234.834395 139.19763) (xy 234.820665 139.19763) (xy 234.820665 139.21136)
			(xy 234.806935 139.21136) (xy 234.806935 139.22509) (xy 234.806935 139.23882) (xy 234.793195 139.23882)
			(xy 234.793195 139.25255) (xy 234.779465 139.25255) (xy 234.779465 139.26629) (xy 234.779465 139.28002)
			(xy 234.765735 139.28002) (xy 234.765735 139.29375) (xy 234.752005 139.29375) (xy 234.752005 139.30748)
			(xy 234.738275 139.30748) (xy 234.738275 139.32121) (xy 234.724545 139.32121) (xy 234.724545 139.33494)
			(xy 234.710805 139.33494) (xy 234.710805 139.34868) (xy 234.697075 139.34868) (xy 234.697075 139.36241)
			(xy 234.683345 139.36241) (xy 234.683345 139.37614) (xy 234.669615 139.37614) (xy 234.669615 139.38987)
			(xy 234.655885 139.38987) (xy 234.655885 139.4036) (xy 234.642155 139.4036) (xy 234.642155 139.41733)
			(xy 234.628415 139.41733) (xy 234.628415 139.43107) (xy 234.614685 139.43107) (xy 234.614685 139.4448)
			(xy 234.587225 139.4448) (xy 234.587225 139.45853) (xy 234.573495 139.45853) (xy 234.573495 139.47226)
			(xy 234.559765 139.47226) (xy 234.559765 139.48599) (xy 234.532295 139.48599) (xy 234.532295 139.49972)
			(xy 234.504835 139.49972) (xy 234.504835 139.51346) (xy 234.491105 139.51346) (xy 234.491105 139.52719)
			(xy 234.463635 139.52719) (xy 234.463635 139.54092) (xy 234.436175 139.54092) (xy 234.436175 139.55465)
			(xy 234.394975 139.55465) (xy 234.394975 139.56838) (xy 234.367515 139.56838) (xy 234.367515 139.58212)
			(xy 234.326315 139.58212) (xy 234.326315 139.59585) (xy 234.271395 139.59585) (xy 234.271395 139.60958)
			(xy 234.202735 139.60958) (xy 234.202735 139.62331) (xy 234.120345 139.62331) (xy 234.120345 139.63704)
			(xy 234.106615 139.63704) (xy 234.106615 139.62331) (xy 234.092885 139.62331) (xy 234.092885 139.63704)
			(xy 234.079145 139.63704) (xy 234.079145 139.62331) (xy 234.065415 139.62331) (xy 234.065415 139.63704)
			(xy 233.969295 139.63704) (xy 233.969295 139.62331) (xy 233.873175 139.62331) (xy 233.873175 139.60958)
			(xy 233.804515 139.60958) (xy 233.804515 139.59585) (xy 233.763315 139.59585) (xy 233.763315 139.58212)
			(xy 233.722125 139.58212) (xy 233.722125 139.56838) (xy 233.680925 139.56838) (xy 233.680925 139.55465)
			(xy 233.653465 139.55465) (xy 233.653465 139.54092) (xy 233.626005 139.54092) (xy 233.626005 139.52719)
			(xy 233.598535 139.52719) (xy 233.598535 139.51346) (xy 233.571075 139.51346) (xy 233.571075 139.49972)
			(xy 233.557345 139.49972) (xy 233.557345 139.48599) (xy 233.529875 139.48599) (xy 233.529875 139.47226)
			(xy 233.516145 139.47226) (xy 233.516145 139.45853) (xy 233.488685 139.45853) (xy 233.488685 139.4448)
			(xy 233.474955 139.4448) (xy 233.474955 139.43107) (xy 233.461225 139.43107) (xy 233.461225 139.41733)
			(xy 233.447485 139.41733) (xy 233.447485 139.4036) (xy 233.420025 139.4036) (xy 233.420025 139.38987)
			(xy 233.406295 139.38987) (xy 233.406295 139.37614) (xy 233.392565 139.37614) (xy 233.392565 139.36241)
			(xy 233.378825 139.36241) (xy 233.378825 139.34868) (xy 233.365095 139.34868) (xy 233.365095 139.33494)
			(xy 233.351365 139.33494) (xy 233.351365 139.32121) (xy 233.351365 139.30748) (xy 233.337635 139.30748)
			(xy 233.337635 139.29375) (xy 233.323905 139.29375) (xy 233.323905 139.28002) (xy 233.310165 139.28002)
			(xy 233.310165 139.26629) (xy 233.296435 139.26629) (xy 233.296435 139.25255) (xy 233.296435 139.23882)
			(xy 233.282705 139.23882) (xy 233.282705 139.22509) (xy 233.268975 139.22509) (xy 233.268975 139.21136)
			(xy 233.268975 139.19763) (xy 233.255245 139.19763) (xy 233.255245 139.1839) (xy 233.255245 139.17016)
			(xy 233.241515 139.17016) (xy 233.241515 139.15643) (xy 233.227775 139.15643) (xy 233.227775 139.1427)
			(xy 233.227775 139.12897) (xy 233.214045 139.12897) (xy 233.214045 139.11524) (xy 233.214045 139.10151)
			(xy 233.200315 139.10151) (xy 233.200315 139.08777) (xy 233.200315 139.07404) (xy 233.200315 139.06031)
			(xy 233.186585 139.06031) (xy 233.186585 139.04658) (xy 233.186585 139.03285) (xy 233.172855 139.03285)
			(xy 233.172855 139.01911) (xy 233.172855 139.00538) (xy 233.172855 138.99165) (xy 233.159125 138.99165)
			(xy 233.159125 138.97792) (xy 233.159125 138.96419) (xy 233.159125 138.95045) (xy 233.159125 138.93672)
			(xy 233.145385 138.93672) (xy 233.145385 138.92299) (xy 233.145385 138.90926) (xy 233.145385 138.89553)
			(xy 233.145385 138.8818) (xy 233.145385 138.86806) (xy 233.131655 138.86806) (xy 233.131655 138.85433)
			(xy 233.131655 138.8406) (xy 233.131655 138.82687) (xy 233.131655 138.81314) (xy 233.131655 138.79941)
			(xy 233.131655 138.78567) (xy 233.131655 138.77194) (xy 233.131655 138.75821) (xy 233.131655 138.74448)
			(xy 233.131655 138.73075) (xy 233.131655 138.71702) (xy 233.131655 138.70328) (xy 233.131655 138.68955)
			(xy 233.131655 138.67582) (xy 233.131655 138.66209) (xy 233.131655 138.64836) (xy 233.131655 138.63463)
			(xy 233.131655 138.62089) (xy 233.131655 138.60716) (xy 233.145385 138.60716) (xy 233.145385 138.59343)
			(xy 233.145385 138.5797) (xy 233.145385 138.56597) (xy 233.145385 138.55224) (xy 233.145385 138.5385)
			(xy 233.159125 138.5385) (xy 233.159125 138.52477) (xy 233.159125 138.51104) (xy 233.159125 138.49731)
			(xy 233.159125 138.48358) (xy 233.172855 138.48358) (xy 233.172855 138.46984) (xy 233.172855 138.45611)
			(xy 233.172855 138.44238) (xy 233.186585 138.44238) (xy 233.186585 138.42865) (xy 233.186585 138.41492)
			(xy 233.186585 138.40118) (xy 233.200315 138.40118) (xy 233.200315 138.38745) (xy 233.200315 138.37372)
			(xy 233.214045 138.37372) (xy 233.214045 138.35999) (xy 233.214045 138.34626) (xy 233.227775 138.34626)
			(xy 233.227775 138.33253) (xy 233.227775 138.31879) (xy 233.241515 138.31879) (xy 233.241515 138.30506)
			(xy 233.241515 138.29133) (xy 233.255245 138.29133) (xy 233.255245 138.2776) (xy 233.255245 138.26387)
			(xy 233.268975 138.26387) (xy 233.268975 138.25014) (xy 233.282705 138.25014) (xy 233.282705 138.2364)
			(xy 233.282705 138.22267) (xy 233.296435 138.22267) (xy 233.296435 138.20894) (xy 233.310165 138.20894)
			(xy 233.310165 138.19521) (xy 233.323905 138.19521) (xy 233.323905 138.18148) (xy 233.323905 138.16775)
			(xy 233.337635 138.16775) (xy 233.337635 138.15401) (xy 233.351365 138.15401) (xy 233.351365 138.14028)
			(xy 233.365095 138.14028) (xy 233.365095 138.12655) (xy 233.378825 138.12655) (xy 233.378825 138.11282)
			(xy 233.392565 138.11282) (xy 233.392565 138.09909) (xy 233.406295 138.09909) (xy 233.406295 138.08536)
			(xy 233.420025 138.08536) (xy 233.420025 138.07162) (xy 233.433755 138.07162) (xy 233.433755 138.05789)
			(xy 233.447485 138.05789) (xy 233.447485 138.04416) (xy 233.461225 138.04416) (xy 233.461225 138.03043)
			(xy 233.488685 138.03043) (xy 233.488685 138.0167) (xy 233.502415 138.0167) (xy 233.502415 138.00296)
			(xy 233.529875 138.00296) (xy 233.529875 137.98923) (xy 233.543615 137.98923) (xy 233.543615 137.9755)
			(xy 233.571075 137.9755) (xy 233.571075 137.96177) (xy 233.584805 137.96177) (xy 233.584805 137.94804)
			(xy 233.612265 137.94804) (xy 233.612265 137.9343) (xy 233.639735 137.9343) (xy 233.639735 137.92057)
			(xy 233.667195 137.92057) (xy 233.667195 137.90684) (xy 233.708395 137.90684) (xy 233.708395 137.89311)
			(xy 233.749585 137.89311) (xy 233.749585 137.87938) (xy 233.790785 137.87938) (xy 233.790785 137.86565)
			(xy 233.845705 137.86565) (xy 233.845705 137.85191) (xy 233.914365 137.85191) (xy 233.914365 137.83818)
			(xy 234.161535 137.83818)
		)
		(stroke
			(width 0)
			(type default)
		)
		(fill yes)
		(layer "F.Cu")
	)
	(gr_poly
		(pts
			(xy 208.208535 130.68394) (xy 208.345845 130.68394) (xy 208.345845 130.69767) (xy 208.400775 130.69767)
			(xy 208.400775 130.71141) (xy 208.455705 130.71141) (xy 208.455705 130.72514) (xy 208.483165 130.72514)
			(xy 208.483165 130.73887) (xy 208.524355 130.73887) (xy 208.524355 130.7526) (xy 208.551825 130.7526)
			(xy 208.551825 130.76633) (xy 208.579285 130.76633) (xy 208.579285 130.78006) (xy 208.606745 130.78006)
			(xy 208.606745 130.7938) (xy 208.634215 130.7938) (xy 208.634215 130.80753) (xy 208.647945 130.80753)
			(xy 208.647945 130.82126) (xy 208.675405 130.82126) (xy 208.675405 130.83499) (xy 208.689145 130.83499)
			(xy 208.689145 130.84872) (xy 208.702875 130.84872) (xy 208.702875 130.86245) (xy 208.730335 130.86245)
			(xy 208.730335 130.87619) (xy 208.744065 130.87619) (xy 208.744065 130.88992) (xy 208.757805 130.88992)
			(xy 208.757805 130.90365) (xy 208.771535 130.90365) (xy 208.771535 130.91738) (xy 208.785265 130.91738)
			(xy 208.785265 130.93111) (xy 208.798995 130.93111) (xy 208.798995 130.94484) (xy 208.812725 130.94484)
			(xy 208.812725 130.95858) (xy 208.826455 130.95858) (xy 208.826455 130.97231) (xy 208.840195 130.97231)
			(xy 208.840195 130.98604) (xy 208.840195 130.99977) (xy 208.853925 130.99977) (xy 208.853925 131.0135)
			(xy 208.867655 131.0135) (xy 208.867655 131.02723) (xy 208.881385 131.02723) (xy 208.881385 131.04097)
			(xy 208.881385 131.0547) (xy 208.895115 131.0547) (xy 208.895115 131.06843) (xy 208.908845 131.06843)
			(xy 208.908845 131.08216) (xy 208.908845 131.09589) (xy 208.922585 131.09589) (xy 208.922585 131.10962)
			(xy 208.922585 131.12336) (xy 208.936315 131.12336) (xy 208.936315 131.13709) (xy 208.936315 131.15082)
			(xy 208.950045 131.15082) (xy 208.950045 131.16455) (xy 208.950045 131.17828) (xy 208.963775 131.17828)
			(xy 208.963775 131.19202) (xy 208.963775 131.20575) (xy 208.963775 131.21948) (xy 208.977505 131.21948)
			(xy 208.977505 131.23321) (xy 208.977505 131.24694) (xy 208.991235 131.24694) (xy 208.991235 131.26068)
			(xy 208.991235 131.27441) (xy 208.991235 131.28814) (xy 208.991235 131.30187) (xy 209.004975 131.30187)
			(xy 209.004975 131.3156) (xy 209.004975 131.32933) (xy 209.004975 131.34307) (xy 209.004975 131.3568)
			(xy 209.004975 131.37053) (xy 209.018705 131.37053) (xy 209.018705 131.38426) (xy 209.018705 131.39799)
			(xy 209.018705 131.41172) (xy 209.018705 131.42546) (xy 209.018705 131.43919) (xy 209.018705 131.45292)
			(xy 209.018705 131.46665) (xy 209.018705 131.48038) (xy 209.018705 131.49411) (xy 209.018705 131.50785)
			(xy 209.018705 131.52158) (xy 209.018705 131.53531) (xy 209.018705 131.54904) (xy 209.018705 131.56277)
			(xy 209.018705 131.5765) (xy 209.018705 131.59024) (xy 209.018705 131.60397) (xy 209.018705 131.6177)
			(xy 209.018705 131.63143) (xy 209.018705 131.64516) (xy 209.018705 131.6589) (xy 209.018705 131.67263)
			(xy 209.018705 131.68636) (xy 209.018705 131.70009) (xy 209.018705 131.71382) (xy 209.018705 131.72756)
			(xy 209.018705 131.74129) (xy 209.018705 131.75502) (xy 209.018705 131.76875) (xy 209.018705 131.78248)
			(xy 209.018705 131.79621) (xy 209.018705 131.80995) (xy 209.018705 131.82368) (xy 209.018705 131.83741)
			(xy 209.018705 131.85114) (xy 209.018705 131.86487) (xy 209.018705 131.8786) (xy 209.018705 131.89233)
			(xy 209.018705 131.90607) (xy 209.018705 131.9198) (xy 209.018705 131.93353) (xy 209.018705 131.94726)
			(xy 209.018705 131.96099) (xy 209.018705 131.97472) (xy 209.018705 131.98846) (xy 209.018705 132.00219)
			(xy 209.018705 132.01592) (xy 209.018705 132.02965) (xy 209.018705 132.04338) (xy 209.018705 132.05711)
			(xy 209.018705 132.07085) (xy 209.018705 132.08458) (xy 209.018705 132.09831) (xy 209.018705 132.11204)
			(xy 209.018705 132.12577) (xy 209.018705 132.13951) (xy 209.018705 132.15324) (xy 209.018705 132.16697)
			(xy 209.018705 132.1807) (xy 209.018705 132.19443) (xy 209.018705 132.20817) (xy 209.018705 132.2219)
			(xy 209.018705 132.23563) (xy 209.018705 132.24936) (xy 209.018705 132.26309) (xy 209.018705 132.27682)
			(xy 209.018705 132.29056) (xy 209.018705 132.30429) (xy 209.018705 132.31802) (xy 209.018705 132.33175)
			(xy 209.018705 132.34548) (xy 209.018705 132.35921) (xy 209.018705 132.37295) (xy 209.018705 132.38668)
			(xy 209.018705 132.40041) (xy 209.018705 132.41414) (xy 209.018705 132.42787) (xy 209.018705 132.4416)
			(xy 209.018705 132.45534) (xy 209.018705 132.46907) (xy 209.018705 132.4828) (xy 209.018705 132.49653)
			(xy 209.018705 132.51026) (xy 209.018705 132.52399) (xy 209.018705 132.53773) (xy 209.018705 132.55146)
			(xy 209.018705 132.56519) (xy 209.018705 132.57892) (xy 209.018705 132.59265) (xy 209.018705 132.60638)
			(xy 209.018705 132.62012) (xy 209.018705 132.63385) (xy 209.018705 132.64758) (xy 209.018705 132.66131)
			(xy 209.018705 132.67504) (xy 209.018705 132.68878) (xy 209.018705 132.70251) (xy 209.018705 132.71624)
			(xy 209.018705 132.72997) (xy 209.018705 132.7437) (xy 209.018705 132.75744) (xy 209.018705 132.77117)
			(xy 209.018705 132.7849) (xy 209.018705 132.79863) (xy 209.018705 132.81236) (xy 209.018705 132.82609)
			(xy 209.018705 132.83983) (xy 209.018705 132.85356) (xy 209.018705 132.86729) (xy 209.018705 132.88102)
			(xy 209.018705 132.89475) (xy 209.018705 132.90848) (xy 209.018705 132.92222) (xy 209.018705 132.93595)
			(xy 209.018705 132.94968) (xy 209.018705 132.96341) (xy 209.018705 132.97714) (xy 209.018705 132.99087)
			(xy 209.018705 133.00461) (xy 209.018705 133.01834) (xy 209.018705 133.03207) (xy 209.018705 133.0458)
			(xy 209.018705 133.05953) (xy 209.018705 133.07326) (xy 209.018705 133.087) (xy 209.018705 133.10073)
			(xy 209.018705 133.11446) (xy 209.018705 133.12819) (xy 209.018705 133.14192) (xy 209.018705 133.15565)
			(xy 209.018705 133.16939) (xy 209.018705 133.18312) (xy 209.018705 133.19685) (xy 209.018705 133.21058)
			(xy 209.018705 133.22431) (xy 209.018705 133.23805) (xy 209.018705 133.25178) (xy 209.018705 133.26551)
			(xy 209.018705 133.27924) (xy 209.018705 133.29297) (xy 209.018705 133.30671) (xy 209.018705 133.32044)
			(xy 209.018705 133.33417) (xy 209.018705 133.3479) (xy 209.018705 133.36163) (xy 209.018705 133.37536)
			(xy 209.018705 133.3891) (xy 209.018705 133.40283) (xy 209.018705 133.41656) (xy 209.018705 133.43029)
			(xy 209.018705 133.44402) (xy 209.018705 133.45775) (xy 209.018705 133.47149) (xy 209.018705 133.48522)
			(xy 209.018705 133.49895) (xy 209.018705 133.51268) (xy 209.018705 133.52641) (xy 209.018705 133.54014)
			(xy 209.018705 133.55388) (xy 209.018705 133.56761) (xy 209.018705 133.58134) (xy 209.018705 133.59507)
			(xy 209.018705 133.6088) (xy 209.018705 133.62253) (xy 209.018705 133.63627) (xy 209.018705 133.65)
			(xy 209.018705 133.66373) (xy 209.018705 133.67746) (xy 209.018705 133.69119) (xy 209.018705 133.70493)
			(xy 209.018705 133.71866) (xy 209.018705 133.73239) (xy 209.018705 133.74612) (xy 209.018705 133.75985)
			(xy 209.018705 133.77359) (xy 209.018705 133.78732) (xy 209.018705 133.80105) (xy 209.018705 133.81478)
			(xy 209.018705 133.82851) (xy 209.018705 133.84224) (xy 209.018705 133.85598) (xy 209.018705 133.86971)
			(xy 209.018705 133.88344) (xy 209.018705 133.89717) (xy 209.018705 133.9109) (xy 209.018705 133.92463)
			(xy 209.018705 133.93837) (xy 209.018705 133.9521) (xy 209.018705 133.96583) (xy 209.018705 133.97956)
			(xy 209.018705 133.99329) (xy 209.018705 134.00702) (xy 209.018705 134.02076) (xy 209.018705 134.03449)
			(xy 209.018705 134.04822) (xy 209.018705 134.06195) (xy 209.018705 134.07568) (xy 209.018705 134.08941)
			(xy 209.018705 134.10315) (xy 209.018705 134.11688) (xy 209.018705 134.13061) (xy 209.018705 134.14434)
			(xy 209.018705 134.15807) (xy 209.018705 134.1718) (xy 209.018705 134.18554) (xy 209.018705 134.19927)
			(xy 209.018705 134.213) (xy 209.018705 134.22673) (xy 209.018705 134.24046) (xy 209.018705 134.2542)
			(xy 209.018705 134.26793) (xy 209.018705 134.28166) (xy 209.018705 134.29539) (xy 209.018705 134.30912)
			(xy 209.018705 134.32286) (xy 209.018705 134.33659) (xy 209.018705 134.35032) (xy 209.018705 134.36405)
			(xy 209.018705 134.37778) (xy 209.018705 134.39151) (xy 209.018705 134.40525) (xy 209.018705 134.41898)
			(xy 209.018705 134.43271) (xy 209.018705 134.44644) (xy 209.018705 134.46017) (xy 209.018705 134.4739)
			(xy 209.018705 134.48764) (xy 209.018705 134.50137) (xy 209.018705 134.5151) (xy 209.018705 134.52883)
			(xy 209.018705 134.54256) (xy 209.018705 134.55629) (xy 209.018705 134.57003) (xy 209.018705 134.58376)
			(xy 209.018705 134.59749) (xy 209.018705 134.61122) (xy 209.018705 134.62495) (xy 209.018705 134.63868)
			(xy 209.018705 134.65242) (xy 209.018705 134.66615) (xy 209.018705 134.67988) (xy 209.018705 134.69361)
			(xy 209.018705 134.70734) (xy 209.018705 134.72107) (xy 209.018705 134.73481) (xy 209.018705 134.74854)
			(xy 209.018705 134.76227) (xy 209.018705 134.776) (xy 209.018705 134.78973) (xy 209.018705 134.80347)
			(xy 209.018705 134.8172) (xy 209.018705 134.83093) (xy 209.018705 134.84466) (xy 209.018705 134.85839)
			(xy 209.018705 134.87213) (xy 209.018705 134.88586) (xy 209.018705 134.89959) (xy 209.018705 134.91332)
			(xy 209.018705 134.92705) (xy 209.018705 134.94078) (xy 209.018705 134.95452) (xy 209.018705 134.96825)
			(xy 209.018705 134.98198) (xy 209.018705 134.99571) (xy 209.018705 135.00944) (xy 209.018705 135.02317)
			(xy 209.018705 135.03691) (xy 209.018705 135.05064) (xy 209.018705 135.06437) (xy 209.018705 135.0781)
			(xy 209.018705 135.09183) (xy 209.018705 135.10556) (xy 209.018705 135.1193) (xy 209.018705 135.13303)
			(xy 209.018705 135.14676) (xy 209.018705 135.16049) (xy 209.018705 135.17422) (xy 209.018705 135.18795)
			(xy 209.018705 135.20169) (xy 209.018705 135.21542) (xy 209.018705 135.22915) (xy 209.018705 135.24288)
			(xy 209.018705 135.25661) (xy 209.018705 135.27034) (xy 209.018705 135.28408) (xy 209.018705 135.29781)
			(xy 209.018705 135.31154) (xy 209.018705 135.32527) (xy 209.018705 135.339) (xy 209.018705 135.35274)
			(xy 209.018705 135.36647) (xy 209.018705 135.3802) (xy 209.018705 135.39393) (xy 209.018705 135.40766)
			(xy 209.018705 135.4214) (xy 209.018705 135.43513) (xy 209.018705 135.44886) (xy 209.018705 135.46259)
			(xy 209.018705 135.47632) (xy 209.018705 135.49005) (xy 209.018705 135.50379) (xy 209.018705 135.51752)
			(xy 209.018705 135.53125) (xy 209.018705 135.54498) (xy 209.018705 135.55871) (xy 209.018705 135.57244)
			(xy 209.018705 135.58618) (xy 209.018705 135.59991) (xy 209.018705 135.61364) (xy 209.018705 135.62737)
			(xy 209.018705 135.6411) (xy 209.018705 135.65483) (xy 209.018705 135.66857) (xy 209.018705 135.6823)
			(xy 209.018705 135.69603) (xy 209.018705 135.70976) (xy 209.018705 135.72349) (xy 209.018705 135.73722)
			(xy 209.018705 135.75096) (xy 209.018705 135.76469) (xy 209.018705 135.77842) (xy 209.018705 135.79215)
			(xy 209.018705 135.80588) (xy 209.018705 135.81961) (xy 209.018705 135.83335) (xy 209.018705 135.84708)
			(xy 209.018705 135.86081) (xy 209.018705 135.87454) (xy 209.018705 135.88827) (xy 209.018705 135.90201)
			(xy 209.018705 135.91574) (xy 209.018705 135.92947) (xy 209.018705 135.9432) (xy 209.018705 135.95693)
			(xy 209.018705 135.97067) (xy 209.018705 135.9844) (xy 209.018705 135.99813) (xy 209.018705 136.01186)
			(xy 209.018705 136.02559) (xy 209.018705 136.03932) (xy 209.018705 136.05306) (xy 209.018705 136.06679)
			(xy 209.018705 136.08052) (xy 209.018705 136.09425) (xy 209.018705 136.10798) (xy 209.018705 136.12171)
			(xy 209.018705 136.13545) (xy 209.018705 136.14918) (xy 209.018705 136.16291) (xy 209.018705 136.17664)
			(xy 209.018705 136.19037) (xy 209.018705 136.2041) (xy 209.018705 136.21784) (xy 209.018705 136.23157)
			(xy 209.018705 136.2453) (xy 209.018705 136.25903) (xy 209.018705 136.27276) (xy 209.018705 136.28649)
			(xy 209.018705 136.30023) (xy 209.018705 136.31396) (xy 209.018705 136.32769) (xy 209.018705 136.34142)
			(xy 209.018705 136.35515) (xy 209.018705 136.36889) (xy 209.018705 136.38262) (xy 209.018705 136.39635)
			(xy 209.018705 136.41008) (xy 209.018705 136.42381) (xy 209.018705 136.43755) (xy 209.018705 136.45128)
			(xy 209.018705 136.46501) (xy 209.018705 136.47874) (xy 209.018705 136.49247) (xy 209.018705 136.5062)
			(xy 209.018705 136.51994) (xy 209.018705 136.53367) (xy 209.018705 136.5474) (xy 209.018705 136.56113)
			(xy 209.018705 136.57486) (xy 209.018705 136.58859) (xy 209.018705 136.60233) (xy 209.018705 136.61606)
			(xy 209.018705 136.62979) (xy 209.018705 136.64352) (xy 209.018705 136.65725) (xy 209.018705 136.67098)
			(xy 209.018705 136.68472) (xy 209.018705 136.69845) (xy 209.018705 136.71218) (xy 209.018705 136.72591)
			(xy 209.018705 136.73964) (xy 209.018705 136.75337) (xy 209.018705 136.76711) (xy 209.018705 136.78084)
			(xy 209.018705 136.79457) (xy 209.018705 136.8083) (xy 209.018705 136.82203) (xy 209.018705 136.83576)
			(xy 209.018705 136.8495) (xy 209.018705 136.86323) (xy 209.018705 136.87696) (xy 209.018705 136.89069)
			(xy 209.018705 136.90442) (xy 209.018705 136.91816) (xy 209.018705 136.93189) (xy 209.018705 136.94562)
			(xy 209.018705 136.95935) (xy 209.018705 136.97308) (xy 209.018705 136.98682) (xy 209.018705 137.00055)
			(xy 209.018705 137.01428) (xy 209.018705 137.02801) (xy 209.018705 137.04174) (xy 209.018705 137.05547)
			(xy 209.018705 137.06921) (xy 209.018705 137.08294) (xy 209.018705 137.09667) (xy 209.018705 137.1104)
			(xy 209.018705 137.12413) (xy 209.018705 137.13786) (xy 209.018705 137.1516) (xy 209.018705 137.16533)
			(xy 209.018705 137.17906) (xy 209.018705 137.19279) (xy 209.018705 137.20652) (xy 209.018705 137.22025)
			(xy 209.018705 137.23399) (xy 209.018705 137.24772) (xy 209.018705 137.26145) (xy 209.018705 137.27518)
			(xy 209.018705 137.28891) (xy 209.018705 137.30264) (xy 209.018705 137.31638) (xy 209.018705 137.33011)
			(xy 209.018705 137.34384) (xy 209.018705 137.35757) (xy 209.018705 137.3713) (xy 209.018705 137.38503)
			(xy 209.018705 137.39877) (xy 209.018705 137.4125) (xy 209.018705 137.42623) (xy 209.018705 137.43996)
			(xy 209.018705 137.45369) (xy 209.018705 137.46743) (xy 209.018705 137.48116) (xy 209.018705 137.49489)
			(xy 209.018705 137.50862) (xy 209.018705 137.52235) (xy 209.018705 137.53609) (xy 209.018705 137.54982)
			(xy 209.018705 137.56355) (xy 209.018705 137.57728) (xy 209.018705 137.59101) (xy 209.018705 137.60474)
			(xy 209.018705 137.61848) (xy 209.018705 137.63221) (xy 209.018705 137.64594) (xy 209.018705 137.65967)
			(xy 209.018705 137.6734) (xy 209.018705 137.68713) (xy 209.018705 137.70087) (xy 209.018705 137.7146)
			(xy 209.018705 137.72833) (xy 209.018705 137.74206) (xy 209.018705 137.75579) (xy 209.018705 137.76952)
			(xy 209.018705 137.78326) (xy 209.018705 137.79699) (xy 209.018705 137.81072) (xy 209.018705 137.82445)
			(xy 209.018705 137.83818) (xy 209.018705 137.85191) (xy 209.018705 137.86565) (xy 209.018705 137.87938)
			(xy 209.018705 137.89311) (xy 209.018705 137.90684) (xy 209.018705 137.92057) (xy 209.018705 137.9343)
			(xy 209.018705 137.94804) (xy 209.018705 137.96177) (xy 209.018705 137.9755) (xy 209.018705 137.98923)
			(xy 209.018705 138.00296) (xy 209.018705 138.0167) (xy 209.018705 138.03043) (xy 209.018705 138.04416)
			(xy 209.018705 138.05789) (xy 209.018705 138.07162) (xy 209.018705 138.08536) (xy 209.018705 138.09909)
			(xy 209.018705 138.11282) (xy 209.018705 138.12655) (xy 209.018705 138.14028) (xy 209.018705 138.15401)
			(xy 209.018705 138.16775) (xy 209.018705 138.18148) (xy 209.018705 138.19521) (xy 209.018705 138.20894)
			(xy 209.018705 138.22267) (xy 209.018705 138.2364) (xy 209.018705 138.25014) (xy 209.018705 138.26387)
			(xy 209.018705 138.2776) (xy 209.018705 138.29133) (xy 209.018705 138.30506) (xy 209.018705 138.31879)
			(xy 209.018705 138.33253) (xy 209.018705 138.34626) (xy 209.018705 138.35999) (xy 209.018705 138.37372)
			(xy 209.018705 138.38745) (xy 209.018705 138.40118) (xy 209.018705 138.41492) (xy 209.018705 138.42865)
			(xy 209.018705 138.44238) (xy 209.018705 138.45611) (xy 209.018705 138.46984) (xy 209.018705 138.48358)
			(xy 209.018705 138.49731) (xy 209.018705 138.51104) (xy 209.018705 138.52477) (xy 209.018705 138.5385)
			(xy 209.018705 138.55224) (xy 209.018705 138.56597) (xy 209.018705 138.5797) (xy 209.018705 138.59343)
			(xy 209.018705 138.60716) (xy 209.018705 138.62089) (xy 209.018705 138.63463) (xy 209.018705 138.64836)
			(xy 209.018705 138.66209) (xy 209.018705 138.67582) (xy 209.018705 138.68955) (xy 209.018705 138.70328)
			(xy 209.018705 138.71702) (xy 209.018705 138.73075) (xy 209.018705 138.74448) (xy 209.018705 138.75821)
			(xy 209.018705 138.77194) (xy 209.018705 138.78567) (xy 209.018705 138.79941) (xy 209.018705 138.81314)
			(xy 209.018705 138.82687) (xy 209.018705 138.8406) (xy 209.018705 138.85433) (xy 209.018705 138.86806)
			(xy 209.018705 138.8818) (xy 209.018705 138.89553) (xy 209.018705 138.90926) (xy 209.018705 138.92299)
			(xy 209.018705 138.93672) (xy 209.018705 138.95045) (xy 209.018705 138.96419) (xy 209.018705 138.97792)
			(xy 209.018705 138.99165) (xy 209.018705 139.00538) (xy 209.018705 139.01911) (xy 209.018705 139.03285)
			(xy 209.018705 139.04658) (xy 209.018705 139.06031) (xy 209.018705 139.07404) (xy 209.018705 139.08777)
			(xy 209.018705 139.10151) (xy 209.018705 139.11524) (xy 209.018705 139.12897) (xy 209.018705 139.1427)
			(xy 209.018705 139.15643) (xy 209.018705 139.17016) (xy 209.018705 139.1839) (xy 209.018705 139.19763)
			(xy 209.018705 139.21136) (xy 209.018705 139.22509) (xy 209.018705 139.23882) (xy 209.018705 139.25255)
			(xy 209.018705 139.26629) (xy 209.018705 139.28002) (xy 209.018705 139.29375) (xy 209.018705 139.30748)
			(xy 209.018705 139.32121) (xy 209.018705 139.33494) (xy 209.018705 139.34868) (xy 209.018705 139.36241)
			(xy 209.018705 139.37614) (xy 209.018705 139.38987) (xy 209.018705 139.4036) (xy 209.018705 139.41733)
			(xy 209.018705 139.43107) (xy 209.018705 139.4448) (xy 209.018705 139.45853) (xy 209.018705 139.47226)
			(xy 209.018705 139.48599) (xy 209.018705 139.49972) (xy 209.018705 139.51346) (xy 209.018705 139.52719)
			(xy 209.018705 139.54092) (xy 209.018705 139.55465) (xy 209.018705 139.56838) (xy 209.018705 139.58212)
			(xy 209.018705 139.59585) (xy 209.018705 139.60958) (xy 209.018705 139.62331) (xy 209.018705 139.63704)
			(xy 209.018705 139.65078) (xy 209.018705 139.66451) (xy 209.018705 139.67824) (xy 209.018705 139.69197)
			(xy 209.018705 139.7057) (xy 209.018705 139.71943) (xy 209.018705 139.73317) (xy 209.018705 139.7469)
			(xy 209.018705 139.76063) (xy 209.018705 139.77436) (xy 209.018705 139.78809) (xy 209.018705 139.80182)
			(xy 209.018705 139.81556) (xy 209.018705 139.82929) (xy 209.018705 139.84302) (xy 209.018705 139.85675)
			(xy 209.018705 139.87048) (xy 209.018705 139.88421) (xy 209.018705 139.89795) (xy 209.018705 139.91168)
			(xy 209.018705 139.92541) (xy 209.018705 139.93914) (xy 209.018705 139.95287) (xy 209.018705 139.9666)
			(xy 209.018705 139.98034) (xy 209.018705 139.99407) (xy 209.018705 140.0078) (xy 209.018705 140.02153)
			(xy 209.018705 140.03526) (xy 209.018705 140.04899) (xy 209.018705 140.06273) (xy 209.018705 140.07646)
			(xy 209.018705 140.09019) (xy 209.018705 140.10392) (xy 209.018705 140.11765) (xy 209.018705 140.13139)
			(xy 209.018705 140.14512) (xy 209.018705 140.15885) (xy 209.018705 140.17258) (xy 209.018705 140.18631)
			(xy 209.018705 140.20005) (xy 209.018705 140.21378) (xy 209.018705 140.22751) (xy 209.018705 140.24124)
			(xy 209.018705 140.25497) (xy 209.018705 140.2687) (xy 209.018705 140.28244) (xy 209.018705 140.29617)
			(xy 209.018705 140.3099) (xy 209.018705 140.32363) (xy 209.018705 140.33736) (xy 209.018705 140.35109)
			(xy 209.018705 140.36483) (xy 209.018705 140.37856) (xy 209.018705 140.39229) (xy 209.018705 140.40602)
			(xy 209.018705 140.41975) (xy 209.018705 140.43348) (xy 209.018705 140.44722) (xy 209.018705 140.46095)
			(xy 209.018705 140.47468) (xy 209.018705 140.48841) (xy 209.018705 140.50214) (xy 209.018705 140.51587)
			(xy 209.018705 140.5296) (xy 209.018705 140.54334) (xy 209.018705 140.55707) (xy 209.018705 140.5708)
			(xy 209.018705 140.58453) (xy 209.018705 140.59827) (xy 209.018705 140.612) (xy 209.018705 140.62573)
			(xy 209.018705 140.63946) (xy 209.018705 140.65319) (xy 209.018705 140.66693) (xy 209.018705 140.68066)
			(xy 209.018705 140.69439) (xy 209.018705 140.70812) (xy 209.018705 140.72185) (xy 209.018705 140.73558)
			(xy 209.018705 140.74931) (xy 209.018705 140.76305) (xy 209.018705 140.77678) (xy 209.018705 140.79051)
			(xy 209.018705 140.80424) (xy 209.018705 140.81797) (xy 209.018705 140.8317) (xy 209.018705 140.84544)
			(xy 209.018705 140.85917) (xy 209.018705 140.8729) (xy 209.018705 140.88663) (xy 209.018705 140.90036)
			(xy 209.018705 140.91409) (xy 209.018705 140.92783) (xy 209.018705 140.94156) (xy 209.018705 140.95529)
			(xy 209.018705 140.96902) (xy 209.018705 140.98275) (xy 209.018705 140.99648) (xy 209.018705 141.01022)
			(xy 209.018705 141.02395) (xy 209.018705 141.03768) (xy 209.018705 141.05141) (xy 209.018705 141.06514)
			(xy 209.018705 141.07888) (xy 209.018705 141.09261) (xy 209.018705 141.10634) (xy 209.018705 141.12007)
			(xy 209.018705 141.1338) (xy 209.018705 141.14754) (xy 209.018705 141.16127) (xy 209.018705 141.175)
			(xy 209.018705 141.18873) (xy 209.018705 141.20246) (xy 209.018705 141.21619) (xy 209.018705 141.22993)
			(xy 209.018705 141.24366) (xy 209.018705 141.25739) (xy 209.018705 141.27112) (xy 209.018705 141.28485)
			(xy 209.018705 141.29858) (xy 209.018705 141.31232) (xy 209.018705 141.32605) (xy 209.018705 141.33978)
			(xy 209.018705 141.35351) (xy 209.018705 141.36724) (xy 209.018705 141.38097) (xy 209.018705 141.39471)
			(xy 209.018705 141.40844) (xy 209.018705 141.42217) (xy 209.018705 141.4359) (xy 209.018705 141.44963)
			(xy 209.018705 141.46336) (xy 209.018705 141.4771) (xy 209.018705 141.49083) (xy 209.018705 141.50456)
			(xy 209.018705 141.51829) (xy 209.018705 141.53202) (xy 209.018705 141.54575) (xy 209.018705 141.55949)
			(xy 209.018705 141.57322) (xy 209.018705 141.58695) (xy 209.018705 141.60068) (xy 209.018705 141.61441)
			(xy 209.018705 141.62815) (xy 209.018705 141.64188) (xy 209.018705 141.65561) (xy 209.018705 141.66934)
			(xy 209.018705 141.68307) (xy 209.018705 141.69681) (xy 209.018705 141.71054) (xy 209.018705 141.72427)
			(xy 209.018705 141.738) (xy 209.018705 141.75173) (xy 209.018705 141.76546) (xy 209.018705 141.7792)
			(xy 209.018705 141.79293) (xy 209.018705 141.80666) (xy 209.018705 141.82039) (xy 209.018705 141.83412)
			(xy 209.018705 141.84785) (xy 209.018705 141.86159) (xy 209.018705 141.87532) (xy 209.018705 141.88905)
			(xy 209.018705 141.90278) (xy 209.018705 141.91651) (xy 209.018705 141.93024) (xy 209.018705 141.94398)
			(xy 209.018705 141.95771) (xy 209.018705 141.97144) (xy 209.018705 141.98517) (xy 209.018705 141.9989)
			(xy 209.018705 142.01263) (xy 209.018705 142.02637) (xy 209.018705 142.0401) (xy 209.018705 142.05383)
			(xy 209.018705 142.06756) (xy 209.018705 142.08129) (xy 209.018705 142.09502) (xy 209.018705 142.10876)
			(xy 209.018705 142.12249) (xy 209.018705 142.13622) (xy 209.018705 142.14995) (xy 209.018705 142.16368)
			(xy 209.018705 142.17742) (xy 209.018705 142.19115) (xy 209.018705 142.20488) (xy 209.018705 142.21861)
			(xy 209.018705 142.23234) (xy 209.018705 142.24608) (xy 209.018705 142.25981) (xy 209.018705 142.27354)
			(xy 209.018705 142.28727) (xy 209.018705 142.301) (xy 209.018705 142.31473) (xy 209.018705 142.32847)
			(xy 209.018705 142.3422) (xy 209.018705 142.35593) (xy 209.018705 142.36966) (xy 209.018705 142.38339)
			(xy 209.018705 142.39712) (xy 209.018705 142.41086) (xy 209.018705 142.42459) (xy 209.018705 142.43832)
			(xy 209.018705 142.45205) (xy 209.018705 142.46578) (xy 209.018705 142.47951) (xy 209.018705 142.49325)
			(xy 209.018705 142.50698) (xy 209.018705 142.52071) (xy 209.018705 142.53444) (xy 209.018705 142.54817)
			(xy 209.018705 142.5619) (xy 209.018705 142.57564) (xy 209.018705 142.58937) (xy 209.018705 142.6031)
			(xy 209.018705 142.61683) (xy 209.018705 142.63056) (xy 209.018705 142.64429) (xy 209.018705 142.65803)
			(xy 209.018705 142.67176) (xy 209.018705 142.68549) (xy 209.018705 142.69922) (xy 209.018705 142.71295)
			(xy 209.018705 142.72669) (xy 209.018705 142.74042) (xy 209.018705 142.75415) (xy 209.018705 142.76788)
			(xy 209.018705 142.78161) (xy 209.018705 142.79535) (xy 209.018705 142.80908) (xy 209.018705 142.82281)
			(xy 209.018705 142.83654) (xy 209.018705 142.85027) (xy 209.018705 142.864) (xy 209.018705 142.87774)
			(xy 209.018705 142.89147) (xy 209.018705 142.9052) (xy 209.018705 142.91893) (xy 209.018705 142.93266)
			(xy 209.018705 142.94639) (xy 209.018705 142.96013) (xy 209.018705 142.97386) (xy 209.018705 142.98759)
			(xy 209.018705 143.00132) (xy 209.018705 143.01505) (xy 209.018705 143.02878) (xy 209.018705 143.04252)
			(xy 209.018705 143.05625) (xy 209.018705 143.06998) (xy 209.018705 143.08371) (xy 209.018705 143.09744)
			(xy 209.018705 143.11117) (xy 209.018705 143.12491) (xy 209.018705 143.13864) (xy 209.018705 143.15237)
			(xy 209.018705 143.1661) (xy 209.018705 143.17983) (xy 209.018705 143.19357) (xy 209.018705 143.2073)
			(xy 209.018705 143.22103) (xy 209.018705 143.23476) (xy 209.018705 143.24849) (xy 209.018705 143.26223)
			(xy 209.018705 143.27596) (xy 209.018705 143.28969) (xy 209.018705 143.30342) (xy 209.018705 143.31715)
			(xy 209.018705 143.33088) (xy 209.018705 143.34462) (xy 209.018705 143.35835) (xy 209.018705 143.37208)
			(xy 209.018705 143.38581) (xy 209.018705 143.39954) (xy 209.018705 143.41327) (xy 209.018705 143.42701)
			(xy 209.018705 143.44074) (xy 209.018705 143.45447) (xy 209.018705 143.4682) (xy 209.018705 143.48193)
			(xy 209.018705 143.49566) (xy 209.018705 143.5094) (xy 209.018705 143.52313) (xy 209.018705 143.53686)
			(xy 209.018705 143.55059) (xy 209.018705 143.56432) (xy 209.018705 143.57805) (xy 209.018705 143.59179)
			(xy 209.018705 143.60552) (xy 209.018705 143.61925) (xy 209.018705 143.63298) (xy 209.018705 143.64671)
			(xy 209.018705 143.66044) (xy 209.018705 143.67418) (xy 209.018705 143.68791) (xy 209.018705 143.70164)
			(xy 209.018705 143.71537) (xy 209.018705 143.7291) (xy 209.018705 143.74284) (xy 209.018705 143.75657)
			(xy 209.018705 143.7703) (xy 209.018705 143.78403) (xy 209.018705 143.79776) (xy 209.018705 143.8115)
			(xy 209.018705 143.82523) (xy 209.018705 143.83896) (xy 209.018705 143.85269) (xy 209.018705 143.86642)
			(xy 209.018705 143.88015) (xy 209.018705 143.89389) (xy 209.018705 143.90762) (xy 209.018705 143.92135)
			(xy 209.018705 143.93508) (xy 209.018705 143.94881) (xy 209.018705 143.96254) (xy 209.018705 143.97628)
			(xy 209.018705 143.99001) (xy 209.018705 144.00374) (xy 209.018705 144.01747) (xy 209.018705 144.0312)
			(xy 209.018705 144.04493) (xy 209.018705 144.05867) (xy 209.018705 144.0724) (xy 209.018705 144.08613)
			(xy 209.018705 144.09986) (xy 209.018705 144.11359) (xy 209.018705 144.12732) (xy 209.018705 144.14106)
			(xy 209.018705 144.15479) (xy 209.018705 144.16852) (xy 209.018705 144.18225) (xy 209.018705 144.19598)
			(xy 209.018705 144.20971) (xy 209.018705 144.22345) (xy 209.018705 144.23718) (xy 209.018705 144.25091)
			(xy 209.018705 144.26464) (xy 209.018705 144.27837) (xy 209.018705 144.29211) (xy 209.018705 144.30584)
			(xy 209.018705 144.31957) (xy 209.018705 144.3333) (xy 209.018705 144.34703) (xy 209.018705 144.36077)
			(xy 209.018705 144.3745) (xy 209.018705 144.38823) (xy 209.018705 144.40196) (xy 209.018705 144.41569)
			(xy 209.018705 144.42942) (xy 209.018705 144.44316) (xy 209.018705 144.45689) (xy 209.018705 144.47062)
			(xy 209.018705 144.48435) (xy 209.018705 144.49808) (xy 209.018705 144.51181) (xy 209.018705 144.52555)
			(xy 209.018705 144.53928) (xy 209.018705 144.55301) (xy 209.018705 144.56674) (xy 209.018705 144.58047)
			(xy 209.018705 144.5942) (xy 209.018705 144.60794) (xy 209.018705 144.62167) (xy 209.018705 144.6354)
			(xy 209.018705 144.64913) (xy 209.018705 144.66286) (xy 209.018705 144.67659) (xy 209.018705 144.69033)
			(xy 209.018705 144.70406) (xy 209.018705 144.71779) (xy 209.018705 144.73152) (xy 209.018705 144.74525)
			(xy 209.018705 144.75898) (xy 209.018705 144.77272) (xy 209.018705 144.78645) (xy 209.018705 144.80018)
			(xy 209.018705 144.81391) (xy 209.018705 144.82764) (xy 209.018705 144.84138) (xy 209.018705 144.85511)
			(xy 209.018705 144.86884) (xy 209.018705 144.88257) (xy 209.018705 144.8963) (xy 209.018705 144.91004)
			(xy 209.018705 144.92377) (xy 209.018705 144.9375) (xy 209.018705 144.95123) (xy 209.018705 144.96496)
			(xy 209.018705 144.97869) (xy 209.018705 144.99243) (xy 209.018705 145.00616) (xy 209.018705 145.01989)
			(xy 209.018705 145.03362) (xy 209.018705 145.04735) (xy 209.018705 145.06108) (xy 209.018705 145.07482)
			(xy 209.018705 145.08855) (xy 209.018705 145.10228) (xy 209.018705 145.11601) (xy 209.018705 145.12974)
			(xy 209.018705 145.14347) (xy 209.018705 145.15721) (xy 209.018705 145.17094) (xy 209.018705 145.18467)
			(xy 209.018705 145.1984) (xy 209.018705 145.21213) (xy 209.018705 145.22586) (xy 209.018705 145.2396)
			(xy 209.018705 145.25333) (xy 209.018705 145.26706) (xy 209.018705 145.28079) (xy 209.018705 145.29452)
			(xy 209.018705 145.30826) (xy 209.018705 145.32199) (xy 209.018705 145.33572) (xy 209.018705 145.34945)
			(xy 209.018705 145.36318) (xy 209.018705 145.37692) (xy 209.018705 145.39065) (xy 209.018705 145.40438)
			(xy 209.018705 145.41811) (xy 209.018705 145.43184) (xy 209.018705 145.44557) (xy 209.018705 145.45931)
			(xy 209.018705 145.47304) (xy 209.018705 145.48677) (xy 209.018705 145.5005) (xy 209.018705 145.51423)
			(xy 209.018705 145.52796) (xy 209.018705 145.5417) (xy 209.018705 145.55543) (xy 209.018705 145.56916)
			(xy 209.018705 145.58289) (xy 209.018705 145.59662) (xy 209.018705 145.61035) (xy 209.018705 145.62409)
			(xy 209.018705 145.63782) (xy 209.018705 145.65155) (xy 209.018705 145.66528) (xy 209.018705 145.67901)
			(xy 209.018705 145.69274) (xy 209.018705 145.70648) (xy 209.018705 145.72021) (xy 209.018705 145.73394)
			(xy 209.018705 145.74767) (xy 209.018705 145.7614) (xy 209.018705 145.77513) (xy 209.018705 145.78887)
			(xy 209.018705 145.8026) (xy 209.018705 145.81633) (xy 209.018705 145.83006) (xy 209.018705 145.84379)
			(xy 209.018705 145.85753) (xy 209.018705 145.87126) (xy 209.018705 145.88499) (xy 209.018705 145.89872)
			(xy 209.018705 145.91245) (xy 209.018705 145.92619) (xy 209.018705 145.93992) (xy 209.018705 145.95365)
			(xy 209.018705 145.96738) (xy 209.018705 145.98111) (xy 209.018705 145.99484) (xy 209.018705 146.00858)
			(xy 209.018705 146.02231) (xy 209.018705 146.03604) (xy 209.018705 146.04977) (xy 209.018705 146.0635)
			(xy 209.018705 146.07723) (xy 209.018705 146.09097) (xy 209.018705 146.1047) (xy 209.018705 146.11843)
			(xy 209.018705 146.13216) (xy 209.018705 146.14589) (xy 209.018705 146.15962) (xy 209.018705 146.17336)
			(xy 209.018705 146.18709) (xy 209.018705 146.20082) (xy 209.018705 146.21455) (xy 209.018705 146.22828)
			(xy 209.018705 146.24201) (xy 209.018705 146.25575) (xy 209.018705 146.26948) (xy 209.018705 146.28321)
			(xy 209.018705 146.29694) (xy 209.018705 146.31067) (xy 209.018705 146.3244) (xy 209.018705 146.33814)
			(xy 209.018705 146.35187) (xy 209.018705 146.3656) (xy 208.510625 146.3656) (xy 208.510625 146.35187)
			(xy 208.510625 146.33814) (xy 208.510625 146.3244) (xy 208.510625 146.31067) (xy 208.510625 146.29694)
			(xy 208.510625 146.28321) (xy 208.510625 146.26948) (xy 208.510625 146.25575) (xy 208.510625 146.24201)
			(xy 208.510625 146.22828) (xy 208.510625 146.21455) (xy 208.510625 146.20082) (xy 208.510625 146.18709)
			(xy 208.510625 146.17336) (xy 208.510625 146.15962) (xy 208.510625 146.14589) (xy 208.510625 146.13216)
			(xy 208.510625 146.11843) (xy 208.510625 146.1047) (xy 208.510625 146.09097) (xy 208.510625 146.07723)
			(xy 208.510625 146.0635) (xy 208.510625 146.04977) (xy 208.510625 146.03604) (xy 208.510625 146.02231)
			(xy 208.510625 146.00858) (xy 208.510625 145.99484) (xy 208.510625 145.98111) (xy 208.510625 145.96738)
			(xy 208.510625 145.95365) (xy 208.510625 145.93992) (xy 208.510625 145.92619) (xy 208.510625 145.91245)
			(xy 208.510625 145.89872) (xy 208.510625 145.88499) (xy 208.510625 145.87126) (xy 208.510625 145.85753)
			(xy 208.510625 145.84379) (xy 208.510625 145.83006) (xy 208.510625 145.81633) (xy 208.510625 145.8026)
			(xy 208.510625 145.78887) (xy 208.510625 145.77513) (xy 208.510625 145.7614) (xy 208.510625 145.74767)
			(xy 208.510625 145.73394) (xy 208.510625 145.72021) (xy 208.510625 145.70648) (xy 208.510625 145.69274)
			(xy 208.510625 145.67901) (xy 208.510625 145.66528) (xy 208.510625 145.65155) (xy 208.510625 145.63782)
			(xy 208.510625 145.62409) (xy 208.510625 145.61035) (xy 208.510625 145.59662) (xy 208.510625 145.58289)
			(xy 208.510625 145.56916) (xy 208.510625 145.55543) (xy 208.510625 145.5417) (xy 208.510625 145.52796)
			(xy 208.510625 145.51423) (xy 208.510625 145.5005) (xy 208.510625 145.48677) (xy 208.510625 145.47304)
			(xy 208.510625 145.45931) (xy 208.510625 145.44557) (xy 208.510625 145.43184) (xy 208.510625 145.41811)
			(xy 208.510625 145.40438) (xy 208.510625 145.39065) (xy 208.510625 145.37692) (xy 208.510625 145.36318)
			(xy 208.510625 145.34945) (xy 208.510625 145.33572) (xy 208.510625 145.32199) (xy 208.510625 145.30826)
			(xy 208.510625 145.29452) (xy 208.510625 145.28079) (xy 208.510625 145.26706) (xy 208.510625 145.25333)
			(xy 208.510625 145.2396) (xy 208.510625 145.22586) (xy 208.510625 145.21213) (xy 208.510625 145.1984)
			(xy 208.510625 145.18467) (xy 208.510625 145.17094) (xy 208.510625 145.15721) (xy 208.510625 145.14347)
			(xy 208.510625 145.12974) (xy 208.510625 145.11601) (xy 208.510625 145.10228) (xy 208.510625 145.08855)
			(xy 208.510625 145.07482) (xy 208.510625 145.06108) (xy 208.510625 145.04735) (xy 208.510625 145.03362)
			(xy 208.510625 145.01989) (xy 208.510625 145.00616) (xy 208.510625 144.99243) (xy 208.510625 144.97869)
			(xy 208.510625 144.96496) (xy 208.510625 144.95123) (xy 208.510625 144.9375) (xy 208.510625 144.92377)
			(xy 208.510625 144.91004) (xy 208.510625 144.8963) (xy 208.510625 144.88257) (xy 208.510625 144.86884)
			(xy 208.510625 144.85511) (xy 208.510625 144.84138) (xy 208.510625 144.82764) (xy 208.510625 144.81391)
			(xy 208.510625 144.80018) (xy 208.510625 144.78645) (xy 208.510625 144.77272) (xy 208.510625 144.75898)
			(xy 208.510625 144.74525) (xy 208.510625 144.73152) (xy 208.510625 144.71779) (xy 208.510625 144.70406)
			(xy 208.510625 144.69033) (xy 208.510625 144.67659) (xy 208.510625 144.66286) (xy 208.510625 144.64913)
			(xy 208.510625 144.6354) (xy 208.510625 144.62167) (xy 208.510625 144.60794) (xy 208.510625 144.5942)
			(xy 208.510625 144.58047) (xy 208.510625 144.56674) (xy 208.510625 144.55301) (xy 208.510625 144.53928)
			(xy 208.510625 144.52555) (xy 208.510625 144.51181) (xy 208.510625 144.49808) (xy 208.510625 144.48435)
			(xy 208.510625 144.47062) (xy 208.510625 144.45689) (xy 208.510625 144.44316) (xy 208.510625 144.42942)
			(xy 208.510625 144.41569) (xy 208.510625 144.40196) (xy 208.510625 144.38823) (xy 208.510625 144.3745)
			(xy 208.510625 144.36077) (xy 208.510625 144.34703) (xy 208.510625 144.3333) (xy 208.510625 144.31957)
			(xy 208.510625 144.30584) (xy 208.510625 144.29211) (xy 208.510625 144.27837) (xy 208.510625 144.26464)
			(xy 208.510625 144.25091) (xy 208.510625 144.23718) (xy 208.510625 144.22345) (xy 208.510625 144.20971)
			(xy 208.510625 144.19598) (xy 208.510625 144.18225) (xy 208.510625 144.16852) (xy 208.510625 144.15479)
			(xy 208.510625 144.14106) (xy 208.510625 144.12732) (xy 208.510625 144.11359) (xy 208.510625 144.09986)
			(xy 208.510625 144.08613) (xy 208.510625 144.0724) (xy 208.510625 144.05867) (xy 208.510625 144.04493)
			(xy 208.510625 144.0312) (xy 208.510625 144.01747) (xy 208.510625 144.00374) (xy 208.510625 143.99001)
			(xy 208.510625 143.97628) (xy 208.510625 143.96254) (xy 208.510625 143.94881) (xy 208.510625 143.93508)
			(xy 208.510625 143.92135) (xy 208.510625 143.90762) (xy 208.510625 143.89389) (xy 208.510625 143.88015)
			(xy 208.510625 143.86642) (xy 208.510625 143.85269) (xy 208.510625 143.83896) (xy 208.510625 143.82523)
			(xy 208.510625 143.8115) (xy 208.510625 143.79776) (xy 208.510625 143.78403) (xy 208.510625 143.7703)
			(xy 208.510625 143.75657) (xy 208.510625 143.74284) (xy 208.510625 143.7291) (xy 208.510625 143.71537)
			(xy 208.510625 143.70164) (xy 208.510625 143.68791) (xy 208.510625 143.67418) (xy 208.510625 143.66044)
			(xy 208.510625 143.64671) (xy 208.510625 143.63298) (xy 208.510625 143.61925) (xy 208.510625 143.60552)
			(xy 208.510625 143.59179) (xy 208.510625 143.57805) (xy 208.510625 143.56432) (xy 208.510625 143.55059)
			(xy 208.510625 143.53686) (xy 208.510625 143.52313) (xy 208.510625 143.5094) (xy 208.510625 143.49566)
			(xy 208.510625 143.48193) (xy 208.510625 143.4682) (xy 208.510625 143.45447) (xy 208.510625 143.44074)
			(xy 208.510625 143.42701) (xy 208.510625 143.41327) (xy 208.510625 143.39954) (xy 208.510625 143.38581)
			(xy 208.510625 143.37208) (xy 208.510625 143.35835) (xy 208.510625 143.34462) (xy 208.510625 143.33088)
			(xy 208.510625 143.31715) (xy 208.510625 143.30342) (xy 208.510625 143.28969) (xy 208.510625 143.27596)
			(xy 208.510625 143.26223) (xy 208.510625 143.24849) (xy 208.510625 143.23476) (xy 208.510625 143.22103)
			(xy 208.510625 143.2073) (xy 208.510625 143.19357) (xy 208.510625 143.17983) (xy 208.510625 143.1661)
			(xy 208.510625 143.15237) (xy 208.510625 143.13864) (xy 208.510625 143.12491) (xy 208.510625 143.11117)
			(xy 208.510625 143.09744) (xy 208.510625 143.08371) (xy 208.510625 143.06998) (xy 208.510625 143.05625)
			(xy 208.510625 143.04252) (xy 208.510625 143.02878) (xy 208.510625 143.01505) (xy 208.510625 143.00132)
			(xy 208.510625 142.98759) (xy 208.510625 142.97386) (xy 208.510625 142.96013) (xy 208.510625 142.94639)
			(xy 208.510625 142.93266) (xy 208.510625 142.91893) (xy 208.510625 142.9052) (xy 208.510625 142.89147)
			(xy 208.510625 142.87774) (xy 208.510625 142.864) (xy 208.510625 142.85027) (xy 208.510625 142.83654)
			(xy 208.510625 142.82281) (xy 208.510625 142.80908) (xy 208.510625 142.79535) (xy 208.510625 142.78161)
			(xy 208.510625 142.76788) (xy 208.510625 142.75415) (xy 208.510625 142.74042) (xy 208.510625 142.72669)
			(xy 208.510625 142.71295) (xy 208.510625 142.69922) (xy 208.510625 142.68549) (xy 208.510625 142.67176)
			(xy 208.510625 142.65803) (xy 208.510625 142.64429) (xy 208.510625 142.63056) (xy 208.510625 142.61683)
			(xy 208.510625 142.6031) (xy 208.510625 142.58937) (xy 208.510625 142.57564) (xy 208.510625 142.5619)
			(xy 208.510625 142.54817) (xy 208.510625 142.53444) (xy 208.510625 142.52071) (xy 208.510625 142.50698)
			(xy 208.510625 142.49325) (xy 208.510625 142.47951) (xy 208.510625 142.46578) (xy 208.510625 142.45205)
			(xy 208.510625 142.43832) (xy 208.510625 142.42459) (xy 208.510625 142.41086) (xy 208.510625 142.39712)
			(xy 208.510625 142.38339) (xy 208.510625 142.36966) (xy 208.510625 142.35593) (xy 208.510625 142.3422)
			(xy 208.510625 142.32847) (xy 208.510625 142.31473) (xy 208.510625 142.301) (xy 208.510625 142.28727)
			(xy 208.510625 142.27354) (xy 208.510625 142.25981) (xy 208.510625 142.24608) (xy 208.510625 142.23234)
			(xy 208.510625 142.21861) (xy 208.510625 142.20488) (xy 208.510625 142.19115) (xy 208.510625 142.17742)
			(xy 208.510625 142.16368) (xy 208.510625 142.14995) (xy 208.510625 142.13622) (xy 208.510625 142.12249)
			(xy 208.510625 142.10876) (xy 208.510625 142.09502) (xy 208.510625 142.08129) (xy 208.510625 142.06756)
			(xy 208.510625 142.05383) (xy 208.510625 142.0401) (xy 208.510625 142.02637) (xy 208.510625 142.01263)
			(xy 208.510625 141.9989) (xy 208.510625 141.98517) (xy 208.510625 141.97144) (xy 208.510625 141.95771)
			(xy 208.510625 141.94398) (xy 208.510625 141.93024) (xy 208.510625 141.91651) (xy 208.510625 141.90278)
			(xy 208.510625 141.88905) (xy 208.510625 141.87532) (xy 208.510625 141.86159) (xy 208.510625 141.84785)
			(xy 208.510625 141.83412) (xy 208.510625 141.82039) (xy 208.510625 141.80666) (xy 208.510625 141.79293)
			(xy 208.510625 141.7792) (xy 208.510625 141.76546) (xy 208.510625 141.75173) (xy 208.510625 141.738)
			(xy 208.510625 141.72427) (xy 208.510625 141.71054) (xy 208.510625 141.69681) (xy 208.510625 141.68307)
			(xy 208.510625 141.66934) (xy 208.510625 141.65561) (xy 208.510625 141.64188) (xy 208.510625 141.62815)
			(xy 208.510625 141.61441) (xy 208.510625 141.60068) (xy 208.510625 141.58695) (xy 208.510625 141.57322)
			(xy 208.510625 141.55949) (xy 208.510625 141.54575) (xy 208.510625 141.53202) (xy 208.510625 141.51829)
			(xy 208.510625 141.50456) (xy 208.510625 141.49083) (xy 208.510625 141.4771) (xy 208.510625 141.46336)
			(xy 208.510625 141.44963) (xy 208.510625 141.4359) (xy 208.510625 141.42217) (xy 208.510625 141.40844)
			(xy 208.510625 141.39471) (xy 208.510625 141.38097) (xy 208.510625 141.36724) (xy 208.510625 141.35351)
			(xy 208.510625 141.33978) (xy 208.510625 141.32605) (xy 208.510625 141.31232) (xy 208.510625 141.29858)
			(xy 208.510625 141.28485) (xy 208.510625 141.27112) (xy 208.510625 141.25739) (xy 208.510625 141.24366)
			(xy 208.510625 141.22993) (xy 208.510625 141.21619) (xy 208.510625 141.20246) (xy 208.510625 141.18873)
			(xy 208.510625 141.175) (xy 208.510625 141.16127) (xy 208.510625 141.14754) (xy 208.510625 141.1338)
			(xy 208.510625 141.12007) (xy 208.510625 141.10634) (xy 208.510625 141.09261) (xy 208.510625 141.07888)
			(xy 208.510625 141.06514) (xy 208.510625 141.05141) (xy 208.510625 141.03768) (xy 208.510625 141.02395)
			(xy 208.510625 141.01022) (xy 208.510625 140.99648) (xy 208.510625 140.98275) (xy 208.510625 140.96902)
			(xy 208.510625 140.95529) (xy 208.510625 140.94156) (xy 208.510625 140.92783) (xy 208.510625 140.91409)
			(xy 208.510625 140.90036) (xy 208.510625 140.88663) (xy 208.510625 140.8729) (xy 208.510625 140.85917)
			(xy 208.510625 140.84544) (xy 208.510625 140.8317) (xy 208.510625 140.81797) (xy 208.510625 140.80424)
			(xy 208.510625 140.79051) (xy 208.510625 140.77678) (xy 208.510625 140.76305) (xy 208.510625 140.74931)
			(xy 208.510625 140.73558) (xy 208.510625 140.72185) (xy 208.510625 140.70812) (xy 208.510625 140.69439)
			(xy 208.510625 140.68066) (xy 208.510625 140.66693) (xy 208.510625 140.65319) (xy 208.510625 140.63946)
			(xy 208.510625 140.62573) (xy 208.510625 140.612) (xy 208.510625 140.59827) (xy 208.510625 140.58453)
			(xy 208.510625 140.5708) (xy 208.510625 140.55707) (xy 208.510625 140.54334) (xy 208.510625 140.5296)
			(xy 208.510625 140.51587) (xy 208.510625 140.50214) (xy 208.510625 140.48841) (xy 208.510625 140.47468)
			(xy 208.510625 140.46095) (xy 208.510625 140.44722) (xy 208.510625 140.43348) (xy 208.510625 140.41975)
			(xy 208.510625 140.40602) (xy 208.510625 140.39229) (xy 208.510625 140.37856) (xy 208.510625 140.36483)
			(xy 208.510625 140.35109) (xy 208.510625 140.33736) (xy 208.510625 140.32363) (xy 208.510625 140.3099)
			(xy 208.510625 140.29617) (xy 208.510625 140.28244) (xy 208.510625 140.2687) (xy 208.510625 140.25497)
			(xy 208.510625 140.24124) (xy 208.510625 140.22751) (xy 208.510625 140.21378) (xy 208.510625 140.20005)
			(xy 208.510625 140.18631) (xy 208.510625 140.17258) (xy 208.510625 140.15885) (xy 208.510625 140.14512)
			(xy 208.510625 140.13139) (xy 208.510625 140.11765) (xy 208.510625 140.10392) (xy 208.510625 140.09019)
			(xy 208.510625 140.07646) (xy 208.510625 140.06273) (xy 208.510625 140.04899) (xy 208.510625 140.03526)
			(xy 208.510625 140.02153) (xy 208.510625 140.0078) (xy 208.510625 139.99407) (xy 208.510625 139.98034)
			(xy 208.510625 139.9666) (xy 208.510625 139.95287) (xy 208.510625 139.93914) (xy 208.510625 139.92541)
			(xy 208.510625 139.91168) (xy 208.510625 139.89795) (xy 208.510625 139.88421) (xy 208.510625 139.87048)
			(xy 208.510625 139.85675) (xy 208.510625 139.84302) (xy 208.510625 139.82929) (xy 208.510625 139.81556)
			(xy 208.510625 139.80182) (xy 208.510625 139.78809) (xy 208.510625 139.77436) (xy 208.510625 139.76063)
			(xy 208.510625 139.7469) (xy 208.510625 139.73317) (xy 208.510625 139.71943) (xy 208.510625 139.7057)
			(xy 208.510625 139.69197) (xy 208.510625 139.67824) (xy 208.510625 139.66451) (xy 208.510625 139.65078)
			(xy 208.510625 139.63704) (xy 208.510625 139.62331) (xy 208.510625 139.60958) (xy 208.510625 139.59585)
			(xy 208.510625 139.58212) (xy 208.510625 139.56838) (xy 208.510625 139.55465) (xy 208.510625 139.54092)
			(xy 208.510625 139.52719) (xy 208.510625 139.51346) (xy 208.510625 139.49972) (xy 208.510625 139.48599)
			(xy 208.510625 139.47226) (xy 208.510625 139.45853) (xy 208.510625 139.4448) (xy 208.510625 139.43107)
			(xy 208.510625 139.41733) (xy 208.510625 139.4036) (xy 208.510625 139.38987) (xy 208.510625 139.37614)
			(xy 208.510625 139.36241) (xy 208.510625 139.34868) (xy 208.510625 139.33494) (xy 208.510625 139.32121)
			(xy 208.510625 139.30748) (xy 208.510625 139.29375) (xy 208.510625 139.28002) (xy 208.510625 139.26629)
			(xy 208.510625 139.25255) (xy 208.510625 139.23882) (xy 208.510625 139.22509) (xy 208.510625 139.21136)
			(xy 208.510625 139.19763) (xy 208.510625 139.1839) (xy 208.510625 139.17016) (xy 208.510625 139.15643)
			(xy 208.510625 139.1427) (xy 208.510625 139.12897) (xy 208.510625 139.11524) (xy 208.510625 139.10151)
			(xy 208.510625 139.08777) (xy 208.510625 139.07404) (xy 208.510625 139.06031) (xy 208.510625 139.04658)
			(xy 208.510625 139.03285) (xy 208.510625 139.01911) (xy 208.510625 139.00538) (xy 208.510625 138.99165)
			(xy 208.510625 138.97792) (xy 208.510625 138.96419) (xy 208.510625 138.95045) (xy 208.510625 138.93672)
			(xy 208.510625 138.92299) (xy 208.510625 138.90926) (xy 208.510625 138.89553) (xy 208.510625 138.8818)
			(xy 208.510625 138.86806) (xy 208.510625 138.85433) (xy 208.510625 138.8406) (xy 208.510625 138.82687)
			(xy 208.510625 138.81314) (xy 208.510625 138.79941) (xy 208.510625 138.78567) (xy 208.510625 138.77194)
			(xy 208.510625 138.75821) (xy 208.510625 138.74448) (xy 208.510625 138.73075) (xy 208.510625 138.71702)
			(xy 208.510625 138.70328) (xy 208.510625 138.68955) (xy 208.510625 138.67582) (xy 208.510625 138.66209)
			(xy 208.510625 138.64836) (xy 208.510625 138.63463) (xy 208.510625 138.62089) (xy 208.510625 138.60716)
			(xy 208.510625 138.59343) (xy 208.510625 138.5797) (xy 208.510625 138.56597) (xy 208.510625 138.55224)
			(xy 208.510625 138.5385) (xy 208.510625 138.52477) (xy 208.510625 138.51104) (xy 208.510625 138.49731)
			(xy 208.510625 138.48358) (xy 208.510625 138.46984) (xy 208.510625 138.45611) (xy 208.510625 138.44238)
			(xy 208.510625 138.42865) (xy 208.510625 138.41492) (xy 208.510625 138.40118) (xy 208.510625 138.38745)
			(xy 208.510625 138.37372) (xy 208.510625 138.35999) (xy 208.510625 138.34626) (xy 208.510625 138.33253)
			(xy 208.510625 138.31879) (xy 208.510625 138.30506) (xy 208.510625 138.29133) (xy 208.510625 138.2776)
			(xy 208.510625 138.26387) (xy 208.510625 138.25014) (xy 208.510625 138.2364) (xy 208.510625 138.22267)
			(xy 208.510625 138.20894) (xy 208.510625 138.19521) (xy 208.510625 138.18148) (xy 208.510625 138.16775)
			(xy 208.510625 138.15401) (xy 208.510625 138.14028) (xy 208.510625 138.12655) (xy 208.510625 138.11282)
			(xy 208.510625 138.09909) (xy 208.510625 138.08536) (xy 208.510625 138.07162) (xy 208.510625 138.05789)
			(xy 208.510625 138.04416) (xy 208.510625 138.03043) (xy 208.510625 138.0167) (xy 208.510625 138.00296)
			(xy 208.510625 137.98923) (xy 208.510625 137.9755) (xy 208.510625 137.96177) (xy 208.510625 137.94804)
			(xy 208.510625 137.9343) (xy 208.510625 137.92057) (xy 208.510625 137.90684) (xy 208.510625 137.89311)
			(xy 208.510625 137.87938) (xy 208.510625 137.86565) (xy 208.510625 137.85191) (xy 208.510625 137.83818)
			(xy 208.510625 137.82445) (xy 208.510625 137.81072) (xy 208.510625 137.79699) (xy 208.510625 137.78326)
			(xy 208.510625 137.76952) (xy 208.510625 137.75579) (xy 208.510625 137.74206) (xy 208.510625 137.72833)
			(xy 208.510625 137.7146) (xy 208.510625 137.70087) (xy 208.510625 137.68713) (xy 208.510625 137.6734)
			(xy 208.510625 137.65967) (xy 208.510625 137.64594) (xy 208.510625 137.63221) (xy 208.510625 137.61848)
			(xy 208.510625 137.60474) (xy 208.510625 137.59101) (xy 208.510625 137.57728) (xy 208.510625 137.56355)
			(xy 208.510625 137.54982) (xy 208.510625 137.53609) (xy 208.510625 137.52235) (xy 208.510625 137.50862)
			(xy 208.510625 137.49489) (xy 208.510625 137.48116) (xy 208.510625 137.46743) (xy 208.510625 137.45369)
			(xy 208.510625 137.43996) (xy 208.510625 137.42623) (xy 208.510625 137.4125) (xy 208.510625 137.39877)
			(xy 208.510625 137.38503) (xy 208.510625 137.3713) (xy 208.510625 137.35757) (xy 208.510625 137.34384)
			(xy 208.510625 137.33011) (xy 208.510625 137.31638) (xy 208.510625 137.30264) (xy 208.510625 137.28891)
			(xy 208.510625 137.27518) (xy 208.510625 137.26145) (xy 208.510625 137.24772) (xy 208.510625 137.23399)
			(xy 208.510625 137.22025) (xy 208.510625 137.20652) (xy 208.510625 137.19279) (xy 208.510625 137.17906)
			(xy 208.510625 137.16533) (xy 208.510625 137.1516) (xy 208.510625 137.13786) (xy 208.510625 137.12413)
			(xy 208.510625 137.1104) (xy 208.510625 137.09667) (xy 208.510625 137.08294) (xy 208.510625 137.06921)
			(xy 208.510625 137.05547) (xy 208.510625 137.04174) (xy 208.510625 137.02801) (xy 208.510625 137.01428)
			(xy 208.510625 137.00055) (xy 208.510625 136.98682) (xy 208.510625 136.97308) (xy 208.510625 136.95935)
			(xy 208.510625 136.94562) (xy 208.510625 136.93189) (xy 208.510625 136.91816) (xy 208.510625 136.90442)
			(xy 208.510625 136.89069) (xy 208.510625 136.87696) (xy 208.510625 136.86323) (xy 208.510625 136.8495)
			(xy 208.510625 136.83576) (xy 208.510625 136.82203) (xy 208.510625 136.8083) (xy 208.510625 136.79457)
			(xy 208.510625 136.78084) (xy 208.510625 136.76711) (xy 208.510625 136.75337) (xy 208.510625 136.73964)
			(xy 208.510625 136.72591) (xy 208.510625 136.71218) (xy 208.510625 136.69845) (xy 208.510625 136.68472)
			(xy 208.510625 136.67098) (xy 208.510625 136.65725) (xy 208.510625 136.64352) (xy 208.510625 136.62979)
			(xy 208.510625 136.61606) (xy 208.510625 136.60233) (xy 208.510625 136.58859) (xy 208.510625 136.57486)
			(xy 208.510625 136.56113) (xy 208.510625 136.5474) (xy 208.510625 136.53367) (xy 208.510625 136.51994)
			(xy 208.510625 136.5062) (xy 208.510625 136.49247) (xy 208.510625 136.47874) (xy 208.510625 136.46501)
			(xy 208.510625 136.45128) (xy 208.510625 136.43755) (xy 208.510625 136.42381) (xy 208.510625 136.41008)
			(xy 208.510625 136.39635) (xy 208.510625 136.38262) (xy 208.510625 136.36889) (xy 208.510625 136.35515)
			(xy 208.510625 136.34142) (xy 208.510625 136.32769) (xy 208.510625 136.31396) (xy 208.510625 136.30023)
			(xy 208.510625 136.28649) (xy 208.510625 136.27276) (xy 208.510625 136.25903) (xy 208.510625 136.2453)
			(xy 208.510625 136.23157) (xy 208.510625 136.21784) (xy 208.510625 136.2041) (xy 208.510625 136.19037)
			(xy 208.510625 136.17664) (xy 208.510625 136.16291) (xy 208.510625 136.14918) (xy 208.510625 136.13545)
			(xy 208.510625 136.12171) (xy 208.510625 136.10798) (xy 208.510625 136.09425) (xy 208.510625 136.08052)
			(xy 208.510625 136.06679) (xy 208.510625 136.05306) (xy 208.510625 136.03932) (xy 208.510625 136.02559)
			(xy 208.510625 136.01186) (xy 208.510625 135.99813) (xy 208.510625 135.9844) (xy 208.510625 135.97067)
			(xy 208.510625 135.95693) (xy 208.510625 135.9432) (xy 208.510625 135.92947) (xy 208.510625 135.91574)
			(xy 208.510625 135.90201) (xy 208.510625 135.88827) (xy 208.510625 135.87454) (xy 208.510625 135.86081)
			(xy 208.510625 135.84708) (xy 208.510625 135.83335) (xy 208.510625 135.81961) (xy 208.510625 135.80588)
			(xy 208.510625 135.79215) (xy 208.510625 135.77842) (xy 208.510625 135.76469) (xy 208.510625 135.75096)
			(xy 208.510625 135.73722) (xy 208.510625 135.72349) (xy 208.510625 135.70976) (xy 208.510625 135.69603)
			(xy 208.510625 135.6823) (xy 208.510625 135.66857) (xy 208.510625 135.65483) (xy 208.510625 135.6411)
			(xy 208.510625 135.62737) (xy 208.510625 135.61364) (xy 208.510625 135.59991) (xy 208.510625 135.58618)
			(xy 208.510625 135.57244) (xy 208.510625 135.55871) (xy 208.510625 135.54498) (xy 208.510625 135.53125)
			(xy 208.510625 135.51752) (xy 208.510625 135.50379) (xy 208.510625 135.49005) (xy 208.510625 135.47632)
			(xy 208.510625 135.46259) (xy 208.510625 135.44886) (xy 208.510625 135.43513) (xy 208.510625 135.4214)
			(xy 208.510625 135.40766) (xy 208.510625 135.39393) (xy 208.510625 135.3802) (xy 208.510625 135.36647)
			(xy 208.510625 135.35274) (xy 208.510625 135.339) (xy 208.510625 135.32527) (xy 208.510625 135.31154)
			(xy 208.510625 135.29781) (xy 208.510625 135.28408) (xy 208.510625 135.27034) (xy 208.510625 135.25661)
			(xy 208.510625 135.24288) (xy 208.510625 135.22915) (xy 208.510625 135.21542) (xy 208.510625 135.20169)
			(xy 208.510625 135.18795) (xy 208.510625 135.17422) (xy 208.510625 135.16049) (xy 208.510625 135.14676)
			(xy 208.510625 135.13303) (xy 208.510625 135.1193) (xy 208.510625 135.10556) (xy 208.510625 135.09183)
			(xy 208.510625 135.0781) (xy 208.510625 135.06437) (xy 208.510625 135.05064) (xy 208.510625 135.03691)
			(xy 208.510625 135.02317) (xy 208.510625 135.00944) (xy 208.510625 134.99571) (xy 208.510625 134.98198)
			(xy 208.510625 134.96825) (xy 208.510625 134.95452) (xy 208.510625 134.94078) (xy 208.510625 134.92705)
			(xy 208.510625 134.91332) (xy 208.510625 134.89959) (xy 208.510625 134.88586) (xy 208.510625 134.87213)
			(xy 208.510625 134.85839) (xy 208.510625 134.84466) (xy 208.510625 134.83093) (xy 208.510625 134.8172)
			(xy 208.510625 134.80347) (xy 208.510625 134.78973) (xy 208.510625 134.776) (xy 208.510625 134.76227)
			(xy 208.510625 134.74854) (xy 208.510625 134.73481) (xy 208.510625 134.72107) (xy 208.510625 134.70734)
			(xy 208.510625 134.69361) (xy 208.510625 134.67988) (xy 208.510625 134.66615) (xy 208.510625 134.65242)
			(xy 208.510625 134.63868) (xy 208.510625 134.62495) (xy 208.510625 134.61122) (xy 208.510625 134.59749)
			(xy 208.510625 134.58376) (xy 208.510625 134.57003) (xy 208.510625 134.55629) (xy 208.510625 134.54256)
			(xy 208.510625 134.52883) (xy 208.510625 134.5151) (xy 208.510625 134.50137) (xy 208.510625 134.48764)
			(xy 208.510625 134.4739) (xy 208.510625 134.46017) (xy 208.510625 134.44644) (xy 208.510625 134.43271)
			(xy 208.510625 134.41898) (xy 208.510625 134.40525) (xy 208.510625 134.39151) (xy 208.510625 134.37778)
			(xy 208.510625 134.36405) (xy 208.510625 134.35032) (xy 208.510625 134.33659) (xy 208.510625 134.32286)
			(xy 208.510625 134.30912) (xy 208.510625 134.29539) (xy 208.510625 134.28166) (xy 208.510625 134.26793)
			(xy 208.510625 134.2542) (xy 208.510625 134.24046) (xy 208.510625 134.22673) (xy 208.510625 134.213)
			(xy 208.510625 134.19927) (xy 208.510625 134.18554) (xy 208.510625 134.1718) (xy 208.510625 134.15807)
			(xy 208.510625 134.14434) (xy 208.510625 134.13061) (xy 208.510625 134.11688) (xy 208.510625 134.10315)
			(xy 208.510625 134.08941) (xy 208.510625 134.07568) (xy 208.510625 134.06195) (xy 208.510625 134.04822)
			(xy 208.510625 134.03449) (xy 208.510625 134.02076) (xy 208.510625 134.00702) (xy 208.510625 133.99329)
			(xy 208.510625 133.97956) (xy 208.510625 133.96583) (xy 208.510625 133.9521) (xy 208.510625 133.93837)
			(xy 208.510625 133.92463) (xy 208.510625 133.9109) (xy 208.510625 133.89717) (xy 208.510625 133.88344)
			(xy 208.510625 133.86971) (xy 208.510625 133.85598) (xy 208.510625 133.84224) (xy 208.510625 133.82851)
			(xy 208.510625 133.81478) (xy 208.510625 133.80105) (xy 208.510625 133.78732) (xy 208.510625 133.77359)
			(xy 208.510625 133.75985) (xy 208.510625 133.74612) (xy 208.510625 133.73239) (xy 208.510625 133.71866)
			(xy 208.510625 133.70493) (xy 208.510625 133.69119) (xy 208.510625 133.67746) (xy 208.510625 133.66373)
			(xy 208.510625 133.65) (xy 208.510625 133.63627) (xy 208.510625 133.62253) (xy 208.510625 133.6088)
			(xy 208.510625 133.59507) (xy 208.510625 133.58134) (xy 208.510625 133.56761) (xy 208.510625 133.55388)
			(xy 208.510625 133.54014) (xy 208.510625 133.52641) (xy 208.510625 133.51268) (xy 208.510625 133.49895)
			(xy 208.510625 133.48522) (xy 208.510625 133.47149) (xy 208.510625 133.45775) (xy 208.510625 133.44402)
			(xy 208.510625 133.43029) (xy 208.510625 133.41656) (xy 208.510625 133.40283) (xy 208.510625 133.3891)
			(xy 208.510625 133.37536) (xy 208.510625 133.36163) (xy 208.510625 133.3479) (xy 208.510625 133.33417)
			(xy 208.510625 133.32044) (xy 208.510625 133.30671) (xy 208.510625 133.29297) (xy 208.510625 133.27924)
			(xy 208.510625 133.26551) (xy 208.510625 133.25178) (xy 208.510625 133.23805) (xy 208.510625 133.22431)
			(xy 208.510625 133.21058) (xy 208.510625 133.19685) (xy 208.510625 133.18312) (xy 208.510625 133.16939)
			(xy 208.510625 133.15565) (xy 208.510625 133.14192) (xy 208.510625 133.12819) (xy 208.510625 133.11446)
			(xy 208.510625 133.10073) (xy 208.510625 133.087) (xy 208.510625 133.07326) (xy 208.510625 133.05953)
			(xy 208.510625 133.0458) (xy 208.510625 133.03207) (xy 208.510625 133.01834) (xy 208.510625 133.00461)
			(xy 208.510625 132.99087) (xy 208.510625 132.97714) (xy 208.510625 132.96341) (xy 208.510625 132.94968)
			(xy 208.510625 132.93595) (xy 208.510625 132.92222) (xy 208.510625 132.90848) (xy 208.510625 132.89475)
			(xy 208.510625 132.88102) (xy 208.510625 132.86729) (xy 208.510625 132.85356) (xy 208.510625 132.83983)
			(xy 208.510625 132.82609) (xy 208.510625 132.81236) (xy 208.510625 132.79863) (xy 208.510625 132.7849)
			(xy 208.510625 132.77117) (xy 208.510625 132.75744) (xy 208.510625 132.7437) (xy 208.510625 132.72997)
			(xy 208.510625 132.71624) (xy 208.510625 132.70251) (xy 208.510625 132.68878) (xy 208.510625 132.67504)
			(xy 208.510625 132.66131) (xy 208.510625 132.64758) (xy 208.510625 132.63385) (xy 208.510625 132.62012)
			(xy 208.510625 132.60638) (xy 208.510625 132.59265) (xy 208.510625 132.57892) (xy 208.510625 132.56519)
			(xy 208.510625 132.55146) (xy 208.510625 132.53773) (xy 208.510625 132.52399) (xy 208.510625 132.51026)
			(xy 208.510625 132.49653) (xy 208.510625 132.4828) (xy 208.510625 132.46907) (xy 208.510625 132.45534)
			(xy 208.510625 132.4416) (xy 208.510625 132.42787) (xy 208.510625 132.41414) (xy 208.510625 132.40041)
			(xy 208.510625 132.38668) (xy 208.510625 132.37295) (xy 208.510625 132.35921) (xy 208.510625 132.34548)
			(xy 208.510625 132.33175) (xy 208.510625 132.31802) (xy 208.510625 132.30429) (xy 208.510625 132.29056)
			(xy 208.510625 132.27682) (xy 208.510625 132.26309) (xy 208.510625 132.24936) (xy 208.510625 132.23563)
			(xy 208.510625 132.2219) (xy 208.510625 132.20817) (xy 208.510625 132.19443) (xy 208.510625 132.1807)
			(xy 208.510625 132.16697) (xy 208.510625 132.15324) (xy 208.510625 132.13951) (xy 208.510625 132.12577)
			(xy 208.510625 132.11204) (xy 208.510625 132.09831) (xy 208.510625 132.08458) (xy 208.510625 132.07085)
			(xy 208.510625 132.05711) (xy 208.510625 132.04338) (xy 208.510625 132.02965) (xy 208.510625 132.01592)
			(xy 208.510625 132.00219) (xy 208.510625 131.98846) (xy 208.510625 131.97472) (xy 208.510625 131.96099)
			(xy 208.510625 131.94726) (xy 208.510625 131.93353) (xy 208.510625 131.9198) (xy 208.510625 131.90607)
			(xy 208.510625 131.89233) (xy 208.510625 131.8786) (xy 208.510625 131.86487) (xy 208.510625 131.85114)
			(xy 208.510625 131.83741) (xy 208.510625 131.82368) (xy 208.510625 131.80995) (xy 208.510625 131.79621)
			(xy 208.510625 131.78248) (xy 208.510625 131.76875) (xy 208.510625 131.75502) (xy 208.510625 131.74129)
			(xy 208.510625 131.72756) (xy 208.510625 131.71382) (xy 208.510625 131.70009) (xy 208.510625 131.68636)
			(xy 208.510625 131.67263) (xy 208.510625 131.6589) (xy 208.510625 131.64516) (xy 208.510625 131.63143)
			(xy 208.510625 131.6177) (xy 208.510625 131.60397) (xy 208.510625 131.59024) (xy 208.510625 131.5765)
			(xy 208.510625 131.56277) (xy 208.510625 131.54904) (xy 208.510625 131.53531) (xy 208.510625 131.52158)
			(xy 208.510625 131.50785) (xy 208.496895 131.50785) (xy 208.496895 131.49411) (xy 208.496895 131.48038)
			(xy 208.496895 131.46665) (xy 208.496895 131.45292) (xy 208.496895 131.43919) (xy 208.483165 131.43919)
			(xy 208.483165 131.42546) (xy 208.483165 131.41172) (xy 208.469435 131.41172) (xy 208.469435 131.39799)
			(xy 208.469435 131.38426) (xy 208.455705 131.38426) (xy 208.455705 131.37053) (xy 208.455705 131.3568)
			(xy 208.441965 131.3568) (xy 208.441965 131.34307) (xy 208.428235 131.34307) (xy 208.428235 131.32933)
			(xy 208.428235 131.3156) (xy 208.414505 131.3156) (xy 208.414505 131.30187) (xy 208.400775 131.30187)
			(xy 208.400775 131.28814) (xy 208.387045 131.28814) (xy 208.387045 131.27441) (xy 208.359575 131.27441)
			(xy 208.359575 131.26068) (xy 208.345845 131.26068) (xy 208.345845 131.24694) (xy 208.318385 131.24694)
			(xy 208.318385 131.23321) (xy 208.290925 131.23321) (xy 208.290925 131.21948) (xy 208.263455 131.21948)
			(xy 208.263455 131.20575) (xy 208.208535 131.20575) (xy 208.208535 131.19202) (xy 206.464595 131.19202)
			(xy 206.464595 131.17828) (xy 206.464595 131.16455) (xy 206.464595 131.15082) (xy 206.464595 131.13709)
			(xy 206.464595 131.12336) (xy 206.464595 131.10962) (xy 206.464595 131.09589) (xy 206.464595 131.08216)
			(xy 206.464595 131.06843) (xy 206.464595 131.0547) (xy 206.464595 131.04097) (xy 206.464595 131.02723)
			(xy 206.464595 131.0135) (xy 206.464595 130.99977) (xy 206.464595 130.98604) (xy 206.464595 130.97231)
			(xy 206.464595 130.95858) (xy 206.464595 130.94484) (xy 206.464595 130.93111) (xy 206.464595 130.91738)
			(xy 206.464595 130.90365) (xy 206.464595 130.88992) (xy 206.464595 130.87619) (xy 206.464595 130.86245)
			(xy 206.464595 130.84872) (xy 206.464595 130.83499) (xy 206.464595 130.82126) (xy 206.464595 130.80753)
			(xy 206.464595 130.7938) (xy 206.464595 130.78006) (xy 206.464595 130.76633) (xy 206.464595 130.7526)
			(xy 206.464595 130.73887) (xy 206.464595 130.72514) (xy 206.464595 130.71141) (xy 206.464595 130.69767)
			(xy 206.464595 130.68394) (xy 206.464595 130.67021) (xy 208.208535 130.67021)
		)
		(stroke
			(width 0)
			(type default)
		)
		(fill yes)
		(layer "F.Cu")
	)
	(gr_poly
		(pts
			(xy 226.869975 130.68394) (xy 227.021025 130.68394) (xy 227.021025 130.69767) (xy 227.075955 130.69767)
			(xy 227.075955 130.71141) (xy 227.130885 130.71141) (xy 227.130885 130.72514) (xy 227.172075 130.72514)
			(xy 227.172075 130.73887) (xy 227.213275 130.73887) (xy 227.213275 130.7526) (xy 227.240735 130.7526)
			(xy 227.240735 130.76633) (xy 227.268205 130.76633) (xy 227.268205 130.78006) (xy 227.295665 130.78006)
			(xy 227.295665 130.7938) (xy 227.323125 130.7938) (xy 227.323125 130.80753) (xy 227.350595 130.80753)
			(xy 227.350595 130.82126) (xy 227.364325 130.82126) (xy 227.364325 130.83499) (xy 227.391785 130.83499)
			(xy 227.391785 130.84872) (xy 227.405515 130.84872) (xy 227.405515 130.86245) (xy 227.419245 130.86245)
			(xy 227.419245 130.87619) (xy 227.446715 130.87619) (xy 227.446715 130.88992) (xy 227.460445 130.88992)
			(xy 227.460445 130.90365) (xy 227.474175 130.90365) (xy 227.474175 130.91738) (xy 227.487905 130.91738)
			(xy 227.487905 130.93111) (xy 227.501635 130.93111) (xy 227.501635 130.94484) (xy 227.515365 130.94484)
			(xy 227.515365 130.95858) (xy 227.529105 130.95858) (xy 227.529105 130.97231) (xy 227.542835 130.97231)
			(xy 227.542835 130.98604) (xy 227.556565 130.98604) (xy 227.556565 130.99977) (xy 227.570295 130.99977)
			(xy 227.570295 131.0135) (xy 227.584025 131.0135) (xy 227.584025 131.02723) (xy 227.584025 131.04097)
			(xy 227.597765 131.04097) (xy 227.597765 131.0547) (xy 227.611495 131.0547) (xy 227.611495 131.06843)
			(xy 227.625225 131.06843) (xy 227.625225 131.08216) (xy 227.625225 131.09589) (xy 227.638955 131.09589)
			(xy 227.638955 131.10962) (xy 227.638955 131.12336) (xy 227.652685 131.12336) (xy 227.652685 131.13709)
			(xy 227.666425 131.13709) (xy 227.666425 131.15082) (xy 227.666425 131.16455) (xy 227.680155 131.16455)
			(xy 227.680155 131.17828) (xy 227.680155 131.19202) (xy 227.693885 131.19202) (xy 227.693885 131.20575)
			(xy 227.693885 131.21948) (xy 227.707615 131.21948) (xy 227.707615 131.23321) (xy 227.707615 131.24694)
			(xy 227.707615 131.26068) (xy 227.721345 131.26068) (xy 227.721345 131.27441) (xy 227.721345 131.28814)
			(xy 227.721345 131.30187) (xy 227.735075 131.30187) (xy 227.735075 131.3156) (xy 227.735075 131.32933)
			(xy 227.735075 131.34307) (xy 227.748815 131.34307) (xy 227.748815 131.3568) (xy 227.748815 131.37053)
			(xy 227.748815 131.38426) (xy 227.748815 131.39799) (xy 227.762545 131.39799) (xy 227.762545 131.41172)
			(xy 227.762545 131.42546) (xy 227.762545 131.43919) (xy 227.762545 131.45292) (xy 227.762545 131.46665)
			(xy 227.762545 131.48038) (xy 227.776275 131.48038) (xy 227.776275 131.49411) (xy 227.776275 131.50785)
			(xy 227.776275 131.52158) (xy 227.776275 131.53531) (xy 227.776275 131.54904) (xy 227.776275 131.56277)
			(xy 227.776275 131.5765) (xy 227.776275 131.59024) (xy 227.776275 131.60397) (xy 227.776275 131.6177)
			(xy 227.776275 131.63143) (xy 227.762545 131.63143) (xy 227.762545 131.64516) (xy 227.776275 131.64516)
			(xy 227.776275 131.6589) (xy 227.762545 131.6589) (xy 227.762545 131.67263) (xy 227.762545 131.68636)
			(xy 227.762545 131.70009) (xy 227.762545 131.71382) (xy 227.762545 131.72756) (xy 227.762545 131.74129)
			(xy 227.762545 131.75502) (xy 227.748815 131.75502) (xy 227.748815 131.76875) (xy 227.748815 131.78248)
			(xy 227.748815 131.79621) (xy 227.748815 131.80995) (xy 227.735075 131.80995) (xy 227.735075 131.82368)
			(xy 227.735075 131.83741) (xy 227.735075 131.85114) (xy 227.721345 131.85114) (xy 227.721345 131.86487)
			(xy 227.721345 131.8786) (xy 227.721345 131.89233) (xy 227.707615 131.89233) (xy 227.707615 131.90607)
			(xy 227.707615 131.9198) (xy 227.707615 131.93353) (xy 227.693885 131.93353) (xy 227.693885 131.94726)
			(xy 227.693885 131.96099) (xy 227.680155 131.96099) (xy 227.680155 131.97472) (xy 227.680155 131.98846)
			(xy 227.666425 131.98846) (xy 227.666425 132.00219) (xy 227.666425 132.01592) (xy 227.652685 132.01592)
			(xy 227.652685 132.02965) (xy 227.638955 132.02965) (xy 227.638955 132.04338) (xy 227.638955 132.05711)
			(xy 227.625225 132.05711) (xy 227.625225 132.07085) (xy 227.611495 132.07085) (xy 227.611495 132.08458)
			(xy 227.611495 132.09831) (xy 227.597765 132.09831) (xy 227.597765 132.11204) (xy 227.584025 132.11204)
			(xy 227.584025 132.12577) (xy 227.570295 132.12577) (xy 227.570295 132.13951) (xy 227.570295 132.15324)
			(xy 227.556565 132.15324) (xy 227.556565 132.16697) (xy 227.542835 132.16697) (xy 227.542835 132.1807)
			(xy 227.529105 132.1807) (xy 227.529105 132.19443) (xy 227.515365 132.19443) (xy 227.515365 132.20817)
			(xy 227.501635 132.20817) (xy 227.501635 132.2219) (xy 227.487905 132.2219) (xy 227.487905 132.23563)
			(xy 227.474175 132.23563) (xy 227.474175 132.24936) (xy 227.460445 132.24936) (xy 227.460445 132.26309)
			(xy 227.432975 132.26309) (xy 227.432975 132.27682) (xy 227.419245 132.27682) (xy 227.419245 132.29056)
			(xy 227.405515 132.29056) (xy 227.405515 132.30429) (xy 227.378055 132.30429) (xy 227.378055 132.31802)
			(xy 227.364325 132.31802) (xy 227.364325 132.33175) (xy 227.336855 132.33175) (xy 227.336855 132.34548)
			(xy 227.323125 132.34548) (xy 227.323125 132.35921) (xy 227.295665 132.35921) (xy 227.295665 132.37295)
			(xy 227.268205 132.37295) (xy 227.268205 132.38668) (xy 227.240735 132.38668) (xy 227.240735 132.40041)
			(xy 227.199545 132.40041) (xy 227.199545 132.41414) (xy 227.172075 132.41414) (xy 227.172075 132.42787)
			(xy 227.117155 132.42787) (xy 227.117155 132.4416) (xy 227.075955 132.4416) (xy 227.075955 132.45534)
			(xy 226.993565 132.45534) (xy 226.993565 132.46907) (xy 224.920065 132.46907) (xy 224.920065 132.4828)
			(xy 224.810215 132.4828) (xy 224.810215 132.49653) (xy 224.755285 132.49653) (xy 224.755285 132.51026)
			(xy 224.700365 132.51026) (xy 224.700365 132.52399) (xy 224.672895 132.52399) (xy 224.672895 132.53773)
			(xy 224.631705 132.53773) (xy 224.631705 132.55146) (xy 224.604245 132.55146) (xy 224.604245 132.56519)
			(xy 224.576775 132.56519) (xy 224.576775 132.57892) (xy 224.549315 132.57892) (xy 224.549315 132.59265)
			(xy 224.521855 132.59265) (xy 224.521855 132.60638) (xy 224.508115 132.60638) (xy 224.508115 132.62012)
			(xy 224.480655 132.62012) (xy 224.480655 132.63385) (xy 224.453195 132.63385) (xy 224.453195 132.64758)
			(xy 224.439455 132.64758) (xy 224.439455 132.66131) (xy 224.425725 132.66131) (xy 224.425725 132.67504)
			(xy 224.411995 132.67504) (xy 224.411995 132.68878) (xy 224.384535 132.68878) (xy 224.384535 132.70251)
			(xy 224.370795 132.70251) (xy 224.370795 132.71624) (xy 224.357065 132.71624) (xy 224.357065 132.72997)
			(xy 224.343335 132.72997) (xy 224.343335 132.7437) (xy 224.329605 132.7437) (xy 224.329605 132.75744)
			(xy 224.315875 132.75744) (xy 224.315875 132.77117) (xy 224.302145 132.77117) (xy 224.302145 132.7849)
			(xy 224.288405 132.7849) (xy 224.288405 132.79863) (xy 224.288405 132.81236) (xy 224.274675 132.81236)
			(xy 224.274675 132.82609) (xy 224.260945 132.82609) (xy 224.260945 132.83983) (xy 224.247215 132.83983)
			(xy 224.247215 132.85356) (xy 224.247215 132.86729) (xy 224.233485 132.86729) (xy 224.233485 132.88102)
			(xy 224.219755 132.88102) (xy 224.219755 132.89475) (xy 224.219755 132.90848) (xy 224.206015 132.90848)
			(xy 224.206015 132.92222) (xy 224.192285 132.92222) (xy 224.192285 132.93595) (xy 224.192285 132.94968)
			(xy 224.178555 132.94968) (xy 224.178555 132.96341) (xy 224.178555 132.97714) (xy 224.164825 132.97714)
			(xy 224.164825 132.99087) (xy 224.164825 133.00461) (xy 224.151095 133.00461) (xy 224.151095 133.01834)
			(xy 224.151095 133.03207) (xy 224.151095 133.0458) (xy 224.137365 133.0458) (xy 224.137365 133.05953)
			(xy 224.137365 133.07326) (xy 224.123625 133.07326) (xy 224.123625 133.087) (xy 224.123625 133.10073)
			(xy 224.123625 133.11446) (xy 224.109895 133.11446) (xy 224.109895 133.12819) (xy 224.109895 133.14192)
			(xy 224.109895 133.15565) (xy 224.109895 133.16939) (xy 224.096165 133.16939) (xy 224.096165 133.18312)
			(xy 224.096165 133.19685) (xy 224.096165 133.21058) (xy 224.096165 133.22431) (xy 224.096165 133.23805)
			(xy 224.096165 133.25178) (xy 224.082435 133.25178) (xy 224.082435 133.26551) (xy 224.082435 133.27924)
			(xy 224.082435 133.29297) (xy 224.082435 133.30671) (xy 224.082435 133.32044) (xy 224.082435 133.33417)
			(xy 224.082435 133.3479) (xy 224.082435 133.36163) (xy 224.082435 133.37536) (xy 224.082435 133.3891)
			(xy 224.082435 133.40283) (xy 224.082435 133.41656) (xy 224.082435 133.43029) (xy 224.082435 133.44402)
			(xy 224.082435 133.45775) (xy 224.082435 133.47149) (xy 224.096165 133.47149) (xy 224.096165 133.48522)
			(xy 224.096165 133.49895) (xy 224.096165 133.51268) (xy 224.096165 133.52641) (xy 224.096165 133.54014)
			(xy 224.096165 133.55388) (xy 224.109895 133.55388) (xy 224.109895 133.56761) (xy 224.109895 133.58134)
			(xy 224.109895 133.59507) (xy 224.109895 133.6088) (xy 224.123625 133.6088) (xy 224.123625 133.62253)
			(xy 224.123625 133.63627) (xy 224.123625 133.65) (xy 224.137365 133.65) (xy 224.137365 133.66373)
			(xy 224.137365 133.67746) (xy 224.137365 133.69119) (xy 224.151095 133.69119) (xy 224.151095 133.70493)
			(xy 224.151095 133.71866) (xy 224.164825 133.71866) (xy 224.164825 133.73239) (xy 224.164825 133.74612)
			(xy 224.178555 133.74612) (xy 224.178555 133.75985) (xy 224.178555 133.77359) (xy 224.192285 133.77359)
			(xy 224.192285 133.78732) (xy 224.192285 133.80105) (xy 224.206015 133.80105) (xy 224.206015 133.81478)
			(xy 224.206015 133.82851) (xy 224.219755 133.82851) (xy 224.219755 133.84224) (xy 224.233485 133.84224)
			(xy 224.233485 133.85598) (xy 224.233485 133.86971) (xy 224.247215 133.86971) (xy 224.247215 133.88344)
			(xy 224.260945 133.88344) (xy 224.260945 133.89717) (xy 224.260945 133.9109) (xy 224.274675 133.9109)
			(xy 224.274675 133.92463) (xy 224.288405 133.92463) (xy 224.288405 133.93837) (xy 224.302145 133.93837)
			(xy 224.302145 133.9521) (xy 224.315875 133.9521) (xy 224.315875 133.96583) (xy 224.329605 133.96583)
			(xy 224.329605 133.97956) (xy 224.343335 133.97956) (xy 224.343335 133.99329) (xy 224.357065 133.99329)
			(xy 224.357065 134.00702) (xy 224.370795 134.00702) (xy 224.370795 134.02076) (xy 224.384535 134.02076)
			(xy 224.384535 134.03449) (xy 224.398265 134.03449) (xy 224.398265 134.04822) (xy 224.411995 134.04822)
			(xy 224.411995 134.06195) (xy 224.425725 134.06195) (xy 224.425725 134.07568) (xy 224.453195 134.07568)
			(xy 224.453195 134.08941) (xy 224.466925 134.08941) (xy 224.466925 134.10315) (xy 224.494385 134.10315)
			(xy 224.494385 134.11688) (xy 224.508115 134.11688) (xy 224.508115 134.13061) (xy 224.535585 134.13061)
			(xy 224.535585 134.14434) (xy 224.563045 134.14434) (xy 224.563045 134.15807) (xy 224.590505 134.15807)
			(xy 224.590505 134.1718) (xy 224.617975 134.1718) (xy 224.617975 134.18554) (xy 224.645435 134.18554)
			(xy 224.645435 134.19927) (xy 224.686635 134.19927) (xy 224.686635 134.213) (xy 224.727825 134.213)
			(xy 224.727825 134.22673) (xy 224.782755 134.22673) (xy 224.782755 134.24046) (xy 224.851415 134.24046)
			(xy 224.851415 134.2542) (xy 235.713225 134.2542) (xy 235.713225 134.26793) (xy 235.726955 134.26793)
			(xy 235.726955 134.2542) (xy 235.740695 134.2542) (xy 235.740695 134.26793) (xy 235.836815 134.26793)
			(xy 235.836815 134.28166) (xy 235.891735 134.28166) (xy 235.891735 134.29539) (xy 235.932935 134.29539)
			(xy 235.932935 134.30912) (xy 235.974125 134.30912) (xy 235.974125 134.32286) (xy 236.015325 134.32286)
			(xy 236.015325 134.33659) (xy 236.042785 134.33659) (xy 236.042785 134.35032) (xy 236.070255 134.35032)
			(xy 236.070255 134.36405) (xy 236.097715 134.36405) (xy 236.097715 134.37778) (xy 236.125185 134.37778)
			(xy 236.125185 134.39151) (xy 236.138915 134.39151) (xy 236.138915 134.40525) (xy 236.166375 134.40525)
			(xy 236.166375 134.41898) (xy 236.180105 134.41898) (xy 236.180105 134.43271) (xy 236.207575 134.43271)
			(xy 236.207575 134.44644) (xy 236.221305 134.44644) (xy 236.221305 134.46017) (xy 236.235035 134.46017)
			(xy 236.235035 134.4739) (xy 236.248765 134.4739) (xy 236.248765 134.48764) (xy 236.276225 134.48764)
			(xy 236.276225 134.50137) (xy 236.289955 134.50137) (xy 236.289955 134.5151) (xy 236.303695 134.5151)
			(xy 236.303695 134.52883) (xy 236.317425 134.52883) (xy 236.317425 134.54256) (xy 236.331155 134.54256)
			(xy 236.331155 134.55629) (xy 236.344885 134.55629) (xy 236.344885 134.57003) (xy 236.344885 134.58376)
			(xy 236.358615 134.58376) (xy 236.358615 134.59749) (xy 236.372345 134.59749) (xy 236.372345 134.61122)
			(xy 236.386085 134.61122) (xy 236.386085 134.62495) (xy 236.399815 134.62495) (xy 236.399815 134.63868)
			(xy 236.399815 134.65242) (xy 236.413545 134.65242) (xy 236.413545 134.66615) (xy 236.427275 134.66615)
			(xy 236.427275 134.67988) (xy 236.427275 134.69361) (xy 236.441005 134.69361) (xy 236.441005 134.70734)
			(xy 236.454735 134.70734) (xy 236.454735 134.72107) (xy 236.454735 134.73481) (xy 236.468475 134.73481)
			(xy 236.468475 134.74854) (xy 236.468475 134.76227) (xy 236.482205 134.76227) (xy 236.482205 134.776)
			(xy 236.482205 134.78973) (xy 236.495935 134.78973) (xy 236.495935 134.80347) (xy 236.495935 134.8172)
			(xy 236.495935 134.83093) (xy 236.509665 134.83093) (xy 236.509665 134.84466) (xy 236.509665 134.85839)
			(xy 236.523395 134.85839) (xy 236.523395 134.87213) (xy 236.523395 134.88586) (xy 236.523395 134.89959)
			(xy 236.537135 134.89959) (xy 236.537135 134.91332) (xy 236.537135 134.92705) (xy 236.537135 134.94078)
			(xy 236.537135 134.95452) (xy 236.550865 134.95452) (xy 236.550865 134.96825) (xy 236.550865 134.98198)
			(xy 236.550865 134.99571) (xy 236.550865 135.00944) (xy 236.550865 135.02317) (xy 236.564595 135.02317)
			(xy 236.564595 135.03691) (xy 236.564595 135.05064) (xy 236.564595 135.06437) (xy 236.564595 135.0781)
			(xy 236.564595 135.09183) (xy 236.564595 135.10556) (xy 236.564595 135.1193) (xy 236.564595 135.13303)
			(xy 236.564595 135.14676) (xy 236.564595 135.16049) (xy 236.564595 135.17422) (xy 236.564595 135.18795)
			(xy 236.564595 135.20169) (xy 236.564595 135.21542) (xy 236.564595 135.22915) (xy 236.564595 135.24288)
			(xy 236.564595 135.25661) (xy 236.564595 135.27034) (xy 236.564595 135.28408) (xy 236.550865 135.28408)
			(xy 236.550865 135.29781) (xy 236.550865 135.31154) (xy 236.550865 135.32527) (xy 236.550865 135.339)
			(xy 236.550865 135.35274) (xy 236.537135 135.35274) (xy 236.537135 135.36647) (xy 236.537135 135.3802)
			(xy 236.537135 135.39393) (xy 236.537135 135.40766) (xy 236.523395 135.40766) (xy 236.523395 135.4214)
			(xy 236.523395 135.43513) (xy 236.523395 135.44886) (xy 236.509665 135.44886) (xy 236.509665 135.46259)
			(xy 236.509665 135.47632) (xy 236.509665 135.49005) (xy 236.495935 135.49005) (xy 236.495935 135.50379)
			(xy 236.495935 135.51752) (xy 236.482205 135.51752) (xy 236.482205 135.53125) (xy 236.482205 135.54498)
			(xy 236.468475 135.54498) (xy 236.468475 135.55871) (xy 236.468475 135.57244) (xy 236.454735 135.57244)
			(xy 236.454735 135.58618) (xy 236.454735 135.59991) (xy 236.441005 135.59991) (xy 236.441005 135.61364)
			(xy 236.441005 135.62737) (xy 236.427275 135.62737) (xy 236.427275 135.6411) (xy 236.413545 135.6411)
			(xy 236.413545 135.65483) (xy 236.413545 135.66857) (xy 236.399815 135.66857) (xy 236.399815 135.6823)
			(xy 236.386085 135.6823) (xy 236.386085 135.69603) (xy 236.372345 135.69603) (xy 236.372345 135.70976)
			(xy 236.358615 135.70976) (xy 236.358615 135.72349) (xy 236.358615 135.73722) (xy 236.344885 135.73722)
			(xy 236.344885 135.75096) (xy 236.331155 135.75096) (xy 236.331155 135.76469) (xy 236.317425 135.76469)
			(xy 236.317425 135.77842) (xy 236.303695 135.77842) (xy 236.303695 135.79215) (xy 236.289955 135.79215)
			(xy 236.289955 135.80588) (xy 236.276225 135.80588) (xy 236.276225 135.81961) (xy 236.262495 135.81961)
			(xy 236.262495 135.83335) (xy 236.248765 135.83335) (xy 236.248765 135.84708) (xy 236.221305 135.84708)
			(xy 236.221305 135.86081) (xy 236.207575 135.86081) (xy 236.207575 135.87454) (xy 236.193835 135.87454)
			(xy 236.193835 135.88827) (xy 236.166375 135.88827) (xy 236.166375 135.90201) (xy 236.152645 135.90201)
			(xy 236.152645 135.91574) (xy 236.125185 135.91574) (xy 236.125185 135.92947) (xy 236.097715 135.92947)
			(xy 236.097715 135.9432) (xy 236.083985 135.9432) (xy 236.083985 135.95693) (xy 236.042785 135.95693)
			(xy 236.042785 135.97067) (xy 236.015325 135.97067) (xy 236.015325 135.9844) (xy 235.987865 135.9844)
			(xy 235.987865 135.99813) (xy 235.946665 135.99813) (xy 235.946665 136.01186) (xy 235.905475 136.01186)
			(xy 235.905475 136.02559) (xy 235.850545 136.02559) (xy 235.850545 136.03932) (xy 235.768155 136.03932)
			(xy 235.768155 136.05306) (xy 228.641375 136.05306) (xy 228.641375 136.06679) (xy 228.558985 136.06679)
			(xy 228.558985 136.08052) (xy 228.504055 136.08052) (xy 228.504055 136.09425) (xy 228.449125 136.09425)
			(xy 228.449125 136.10798) (xy 228.421665 136.10798) (xy 228.421665 136.12171) (xy 228.380475 136.12171)
			(xy 228.380475 136.13545) (xy 228.353005 136.13545) (xy 228.353005 136.14918) (xy 228.325545 136.14918)
			(xy 228.325545 136.16291) (xy 228.298085 136.16291) (xy 228.298085 136.17664) (xy 228.270615 136.17664)
			(xy 228.270615 136.19037) (xy 228.256885 136.19037) (xy 228.256885 136.2041) (xy 228.229425 136.2041)
			(xy 228.229425 136.21784) (xy 228.215695 136.21784) (xy 228.215695 136.23157) (xy 228.201955 136.23157)
			(xy 228.201955 136.2453) (xy 228.174495 136.2453) (xy 228.174495 136.25903) (xy 228.160765 136.25903)
			(xy 228.160765 136.27276) (xy 228.147035 136.27276) (xy 228.147035 136.28649) (xy 228.133295 136.28649)
			(xy 228.133295 136.30023) (xy 228.119565 136.30023) (xy 228.119565 136.31396) (xy 228.105835 136.31396)
			(xy 228.105835 136.32769) (xy 228.092105 136.32769) (xy 228.092105 136.34142) (xy 228.078375 136.34142)
			(xy 228.078375 136.35515) (xy 228.064635 136.35515) (xy 228.064635 136.36889) (xy 228.050905 136.36889)
			(xy 228.050905 136.38262) (xy 228.037175 136.38262) (xy 228.037175 136.39635) (xy 228.023445 136.39635)
			(xy 228.023445 136.41008) (xy 228.023445 136.42381) (xy 228.009715 136.42381) (xy 228.009715 136.43755)
			(xy 227.995985 136.43755) (xy 227.995985 136.45128) (xy 227.995985 136.46501) (xy 227.982245 136.46501)
			(xy 227.982245 136.47874) (xy 227.968515 136.47874) (xy 227.968515 136.49247) (xy 227.968515 136.5062)
			(xy 227.954785 136.5062) (xy 227.954785 136.51994) (xy 227.954785 136.53367) (xy 227.941055 136.53367)
			(xy 227.941055 136.5474) (xy 227.941055 136.56113) (xy 227.927325 136.56113) (xy 227.927325 136.57486)
			(xy 227.927325 136.58859) (xy 227.913595 136.58859) (xy 227.913595 136.60233) (xy 227.913595 136.61606)
			(xy 227.899855 136.61606) (xy 227.899855 136.62979) (xy 227.899855 136.64352) (xy 227.899855 136.65725)
			(xy 227.886125 136.65725) (xy 227.886125 136.67098) (xy 227.886125 136.68472) (xy 227.886125 136.69845)
			(xy 227.872395 136.69845) (xy 227.872395 136.71218) (xy 227.872395 136.72591) (xy 227.872395 136.73964)
			(xy 227.872395 136.75337) (xy 227.858665 136.75337) (xy 227.858665 136.76711) (xy 227.858665 136.78084)
			(xy 227.858665 136.79457) (xy 227.858665 136.8083) (xy 227.858665 136.82203) (xy 227.858665 136.83576)
			(xy 227.844935 136.83576) (xy 227.844935 136.8495) (xy 227.844935 136.86323) (xy 227.844935 136.87696)
			(xy 227.844935 136.89069) (xy 227.844935 136.90442) (xy 227.844935 136.91816) (xy 227.844935 136.93189)
			(xy 227.844935 136.94562) (xy 227.844935 136.95935) (xy 227.844935 136.97308) (xy 227.844935 136.98682)
			(xy 227.844935 137.00055) (xy 227.844935 137.01428) (xy 227.844935 137.02801) (xy 227.844935 137.04174)
			(xy 227.844935 137.05547) (xy 227.858665 137.05547) (xy 227.858665 137.06921) (xy 227.858665 137.08294)
			(xy 227.858665 137.09667) (xy 227.858665 137.1104) (xy 227.858665 137.12413) (xy 227.858665 137.13786)
			(xy 227.872395 137.13786) (xy 227.872395 137.1516) (xy 227.872395 137.16533) (xy 227.872395 137.17906)
			(xy 227.872395 137.19279) (xy 227.886125 137.19279) (xy 227.886125 137.20652) (xy 227.886125 137.22025)
			(xy 227.886125 137.23399) (xy 227.899855 137.23399) (xy 227.899855 137.24772) (xy 227.899855 137.26145)
			(xy 227.899855 137.27518) (xy 227.913595 137.27518) (xy 227.913595 137.28891) (xy 227.913595 137.30264)
			(xy 227.927325 137.30264) (xy 227.927325 137.31638) (xy 227.927325 137.33011) (xy 227.941055 137.33011)
			(xy 227.941055 137.34384) (xy 227.941055 137.35757) (xy 227.954785 137.35757) (xy 227.954785 137.3713)
			(xy 227.954785 137.38503) (xy 227.968515 137.38503) (xy 227.968515 137.39877) (xy 227.968515 137.4125)
			(xy 227.982245 137.4125) (xy 227.982245 137.42623) (xy 227.995985 137.42623) (xy 227.995985 137.43996)
			(xy 227.995985 137.45369) (xy 228.009715 137.45369) (xy 228.009715 137.46743) (xy 228.023445 137.46743)
			(xy 228.023445 137.48116) (xy 228.037175 137.48116) (xy 228.037175 137.49489) (xy 228.037175 137.50862)
			(xy 228.050905 137.50862) (xy 228.050905 137.52235) (xy 228.064635 137.52235) (xy 228.064635 137.53609)
			(xy 228.078375 137.53609) (xy 228.078375 137.54982) (xy 228.092105 137.54982) (xy 228.092105 137.56355)
			(xy 228.105835 137.56355) (xy 228.105835 137.57728) (xy 228.119565 137.57728) (xy 228.119565 137.59101)
			(xy 228.133295 137.59101) (xy 228.133295 137.60474) (xy 228.147035 137.60474) (xy 228.147035 137.61848)
			(xy 228.160765 137.61848) (xy 228.160765 137.63221) (xy 228.188225 137.63221) (xy 228.188225 137.64594)
			(xy 228.201955 137.64594) (xy 228.201955 137.65967) (xy 228.215695 137.65967) (xy 228.215695 137.6734)
			(xy 228.243155 137.6734) (xy 228.243155 137.68713) (xy 228.256885 137.68713) (xy 228.256885 137.70087)
			(xy 228.284345 137.70087) (xy 228.284345 137.7146) (xy 228.311815 137.7146) (xy 228.311815 137.72833)
			(xy 228.325545 137.72833) (xy 228.325545 137.74206) (xy 228.353005 137.74206) (xy 228.353005 137.75579)
			(xy 228.394205 137.75579) (xy 228.394205 137.76952) (xy 228.421665 137.76952) (xy 228.421665 137.78326)
			(xy 228.462865 137.78326) (xy 228.462865 137.79699) (xy 228.504055 137.79699) (xy 228.504055 137.81072)
			(xy 228.558985 137.81072) (xy 228.558985 137.82445) (xy 228.655105 137.82445) (xy 228.655105 137.83818)
			(xy 231.291605 137.83818) (xy 231.291605 137.85191) (xy 231.360265 137.85191) (xy 231.360265 137.86565)
			(xy 231.415185 137.86565) (xy 231.415185 137.87938) (xy 231.456385 137.87938) (xy 231.456385 137.89311)
			(xy 231.497575 137.89311) (xy 231.497575 137.90684) (xy 231.538775 137.90684) (xy 231.538775 137.92057)
			(xy 231.566235 137.92057) (xy 231.566235 137.9343) (xy 231.593705 137.9343) (xy 231.593705 137.94804)
			(xy 231.621165 137.94804) (xy 231.621165 137.96177) (xy 231.648625 137.96177) (xy 231.648625 137.9755)
			(xy 231.662355 137.9755) (xy 231.662355 137.98923) (xy 231.689825 137.98923) (xy 231.689825 138.00296)
			(xy 231.703555 138.00296) (xy 231.703555 138.0167) (xy 231.717285 138.0167) (xy 231.717285 138.03043)
			(xy 231.744745 138.03043) (xy 231.744745 138.04416) (xy 231.758485 138.04416) (xy 231.758485 138.05789)
			(xy 231.772215 138.05789) (xy 231.772215 138.07162) (xy 231.785945 138.07162) (xy 231.785945 138.08536)
			(xy 231.799675 138.08536) (xy 231.799675 138.09909) (xy 231.813405 138.09909) (xy 231.813405 138.11282)
			(xy 231.827145 138.11282) (xy 231.827145 138.12655) (xy 231.840875 138.12655) (xy 231.840875 138.14028)
			(xy 231.854605 138.14028) (xy 231.854605 138.15401) (xy 231.868335 138.15401) (xy 231.868335 138.16775)
			(xy 231.882065 138.16775) (xy 231.882065 138.18148) (xy 231.895805 138.18148) (xy 231.895805 138.19521)
			(xy 231.895805 138.20894) (xy 231.909535 138.20894) (xy 231.909535 138.22267) (xy 231.923265 138.22267)
			(xy 231.923265 138.2364) (xy 231.936995 138.2364) (xy 231.936995 138.25014) (xy 231.936995 138.26387)
			(xy 231.950725 138.26387) (xy 231.950725 138.2776) (xy 231.950725 138.29133) (xy 231.964455 138.29133)
			(xy 231.964455 138.30506) (xy 231.978195 138.30506) (xy 231.978195 138.31879) (xy 231.978195 138.33253)
			(xy 231.991925 138.33253) (xy 231.991925 138.34626) (xy 231.991925 138.35999) (xy 232.005655 138.35999)
			(xy 232.005655 138.37372) (xy 232.005655 138.38745) (xy 232.005655 138.40118) (xy 232.019385 138.40118)
			(xy 232.019385 138.41492) (xy 232.019385 138.42865) (xy 232.033115 138.42865) (xy 232.033115 138.44238)
			(xy 232.033115 138.45611) (xy 232.033115 138.46984) (xy 232.046845 138.46984) (xy 232.046845 138.48358)
			(xy 232.046845 138.49731) (xy 232.046845 138.51104) (xy 232.046845 138.52477) (xy 232.060585 138.52477)
			(xy 232.060585 138.5385) (xy 232.060585 138.55224) (xy 232.060585 138.56597) (xy 232.060585 138.5797)
			(xy 232.060585 138.59343) (xy 232.074315 138.59343) (xy 232.074315 138.60716) (xy 232.074315 138.62089)
			(xy 232.074315 138.63463) (xy 232.074315 138.64836) (xy 232.074315 138.66209) (xy 232.074315 138.67582)
			(xy 232.074315 138.68955) (xy 232.074315 138.70328) (xy 232.074315 138.71702) (xy 232.074315 138.73075)
			(xy 232.074315 138.74448) (xy 232.074315 138.75821) (xy 232.074315 138.77194) (xy 232.074315 138.78567)
			(xy 232.074315 138.79941) (xy 232.074315 138.81314) (xy 232.074315 138.82687) (xy 232.074315 138.8406)
			(xy 232.074315 138.85433) (xy 232.074315 138.86806) (xy 232.074315 138.8818) (xy 232.060585 138.8818)
			(xy 232.060585 138.89553) (xy 232.060585 138.90926) (xy 232.060585 138.92299) (xy 232.060585 138.93672)
			(xy 232.060585 138.95045) (xy 232.046845 138.95045) (xy 232.046845 138.96419) (xy 232.046845 138.97792)
			(xy 232.046845 138.99165) (xy 232.033115 138.99165) (xy 232.033115 139.00538) (xy 232.033115 139.01911)
			(xy 232.033115 139.03285) (xy 232.019385 139.03285) (xy 232.019385 139.04658) (xy 232.019385 139.06031)
			(xy 232.019385 139.07404) (xy 232.005655 139.07404) (xy 232.005655 139.08777) (xy 232.005655 139.10151)
			(xy 231.991925 139.10151) (xy 231.991925 139.11524) (xy 231.991925 139.12897) (xy 231.978195 139.12897)
			(xy 231.978195 139.1427) (xy 231.978195 139.15643) (xy 231.964455 139.15643) (xy 231.964455 139.17016)
			(xy 231.964455 139.1839) (xy 231.950725 139.1839) (xy 231.950725 139.19763) (xy 231.950725 139.21136)
			(xy 231.936995 139.21136) (xy 231.936995 139.22509) (xy 231.923265 139.22509) (xy 231.923265 139.23882)
			(xy 231.923265 139.25255) (xy 231.909535 139.25255) (xy 231.909535 139.26629) (xy 231.895805 139.26629)
			(xy 231.895805 139.28002) (xy 231.882065 139.28002) (xy 231.882065 139.29375) (xy 231.868335 139.29375)
			(xy 231.868335 139.30748) (xy 231.868335 139.32121) (xy 231.854605 139.32121) (xy 231.854605 139.33494)
			(xy 231.840875 139.33494) (xy 231.840875 139.34868) (xy 231.827145 139.34868) (xy 231.827145 139.36241)
			(xy 231.813405 139.36241) (xy 231.813405 139.37614) (xy 231.799675 139.37614) (xy 231.799675 139.38987)
			(xy 231.785945 139.38987) (xy 231.785945 139.4036) (xy 231.772215 139.4036) (xy 231.772215 139.41733)
			(xy 231.744745 139.41733) (xy 231.744745 139.43107) (xy 231.731015 139.43107) (xy 231.731015 139.4448)
			(xy 231.717285 139.4448) (xy 231.717285 139.45853) (xy 231.689825 139.45853) (xy 231.689825 139.47226)
			(xy 231.676095 139.47226) (xy 231.676095 139.48599) (xy 231.648625 139.48599) (xy 231.648625 139.49972)
			(xy 231.634895 139.49972) (xy 231.634895 139.51346) (xy 231.607435 139.51346) (xy 231.607435 139.52719)
			(xy 231.579965 139.52719) (xy 231.579965 139.54092) (xy 231.552505 139.54092) (xy 231.552505 139.55465)
			(xy 231.525045 139.55465) (xy 231.525045 139.56838) (xy 231.483845 139.56838) (xy 231.483845 139.58212)
			(xy 231.442655 139.58212) (xy 231.442655 139.59585) (xy 231.401455 139.59585) (xy 231.401455 139.60958)
			(xy 231.332795 139.60958) (xy 231.332795 139.62331) (xy 231.236675 139.62331) (xy 231.236675 139.63704)
			(xy 231.209215 139.63704) (xy 231.209215 139.62331) (xy 231.195475 139.62331) (xy 231.195475 139.63704)
			(xy 227.075955 139.63704) (xy 227.075955 139.62331) (xy 227.062225 139.62331) (xy 227.062225 139.63704)
			(xy 226.924905 139.63704) (xy 226.924905 139.65078) (xy 226.856245 139.65078) (xy 226.856245 139.66451)
			(xy 226.801325 139.66451) (xy 226.801325 139.67824) (xy 226.760125 139.67824) (xy 226.760125 139.69197)
			(xy 226.732665 139.69197) (xy 226.732665 139.7057) (xy 226.691465 139.7057) (xy 226.691465 139.71943)
			(xy 226.664005 139.71943) (xy 226.664005 139.73317) (xy 226.636545 139.73317) (xy 226.636545 139.7469)
			(xy 226.622805 139.7469) (xy 226.622805 139.76063) (xy 226.595345 139.76063) (xy 226.595345 139.77436)
			(xy 226.567885 139.77436) (xy 226.567885 139.78809) (xy 226.554145 139.78809) (xy 226.554145 139.80182)
			(xy 226.526685 139.80182) (xy 226.526685 139.81556) (xy 226.512955 139.81556) (xy 226.512955 139.82929)
			(xy 226.499225 139.82929) (xy 226.499225 139.84302) (xy 226.485485 139.84302) (xy 226.485485 139.85675)
			(xy 226.458025 139.85675) (xy 226.458025 139.87048) (xy 226.444295 139.87048) (xy 226.444295 139.88421)
			(xy 226.430565 139.88421) (xy 226.430565 139.89795) (xy 226.416835 139.89795) (xy 226.416835 139.91168)
			(xy 226.403095 139.91168) (xy 226.403095 139.92541) (xy 226.389365 139.92541) (xy 226.389365 139.93914)
			(xy 226.389365 139.95287) (xy 226.375635 139.95287) (xy 226.375635 139.9666) (xy 226.361905 139.9666)
			(xy 226.361905 139.98034) (xy 226.348175 139.98034) (xy 226.348175 139.99407) (xy 226.334445 139.99407)
			(xy 226.334445 140.0078) (xy 226.334445 140.02153) (xy 226.320705 140.02153) (xy 226.320705 140.03526)
			(xy 226.306975 140.03526) (xy 226.306975 140.04899) (xy 226.306975 140.06273) (xy 226.293245 140.06273)
			(xy 226.293245 140.07646) (xy 226.279515 140.07646) (xy 226.279515 140.09019) (xy 226.279515 140.10392)
			(xy 226.265785 140.10392) (xy 226.265785 140.11765) (xy 226.265785 140.13139) (xy 226.252055 140.13139)
			(xy 226.252055 140.14512) (xy 226.252055 140.15885) (xy 226.238315 140.15885) (xy 226.238315 140.17258)
			(xy 226.238315 140.18631) (xy 226.224585 140.18631) (xy 226.224585 140.20005) (xy 226.224585 140.21378)
			(xy 226.224585 140.22751) (xy 226.210855 140.22751) (xy 226.210855 140.24124) (xy 226.210855 140.25497)
			(xy 226.210855 140.2687) (xy 226.197125 140.2687) (xy 226.197125 140.28244) (xy 226.197125 140.29617)
			(xy 226.197125 140.3099) (xy 226.183395 140.3099) (xy 226.183395 140.32363) (xy 226.183395 140.33736)
			(xy 226.183395 140.35109) (xy 226.183395 140.36483) (xy 226.183395 140.37856) (xy 226.169665 140.37856)
			(xy 226.169665 140.39229) (xy 226.169665 140.40602) (xy 226.169665 140.41975) (xy 226.169665 140.43348)
			(xy 226.169665 140.44722) (xy 226.169665 140.46095) (xy 226.169665 140.47468) (xy 226.169665 140.48841)
			(xy 226.169665 140.50214) (xy 226.169665 140.51587) (xy 226.169665 140.5296) (xy 226.169665 140.54334)
			(xy 226.169665 140.55707) (xy 226.169665 140.5708) (xy 226.169665 140.58453) (xy 226.169665 140.59827)
			(xy 226.169665 140.612) (xy 226.169665 140.62573) (xy 226.169665 140.63946) (xy 226.169665 140.65319)
			(xy 226.169665 140.66693) (xy 226.183395 140.66693) (xy 226.183395 140.68066) (xy 226.183395 140.69439)
			(xy 226.183395 140.70812) (xy 226.183395 140.72185) (xy 226.183395 140.73558) (xy 226.197125 140.73558)
			(xy 226.197125 140.74931) (xy 226.197125 140.76305) (xy 226.197125 140.77678) (xy 226.210855 140.77678)
			(xy 226.210855 140.79051) (xy 226.210855 140.80424) (xy 226.210855 140.81797) (xy 226.224585 140.81797)
			(xy 226.224585 140.8317) (xy 226.224585 140.84544) (xy 226.224585 140.85917) (xy 226.238315 140.85917)
			(xy 226.238315 140.8729) (xy 226.238315 140.88663) (xy 226.252055 140.88663) (xy 226.252055 140.90036)
			(xy 226.252055 140.91409) (xy 226.265785 140.91409) (xy 226.265785 140.92783) (xy 226.265785 140.94156)
			(xy 226.279515 140.94156) (xy 226.279515 140.95529) (xy 226.279515 140.96902) (xy 226.293245 140.96902)
			(xy 226.293245 140.98275) (xy 226.293245 140.99648) (xy 226.306975 140.99648) (xy 226.306975 141.01022)
			(xy 226.320705 141.01022) (xy 226.320705 141.02395) (xy 226.320705 141.03768) (xy 226.334445 141.03768)
			(xy 226.334445 141.05141) (xy 226.348175 141.05141) (xy 226.348175 141.06514) (xy 226.361905 141.06514)
			(xy 226.361905 141.07888) (xy 226.361905 141.09261) (xy 226.375635 141.09261) (xy 226.375635 141.10634)
			(xy 226.389365 141.10634) (xy 226.389365 141.12007) (xy 226.403095 141.12007) (xy 226.403095 141.1338)
			(xy 226.416835 141.1338) (xy 226.416835 141.14754) (xy 226.430565 141.14754) (xy 226.430565 141.16127)
			(xy 226.444295 141.16127) (xy 226.444295 141.175) (xy 226.458025 141.175) (xy 226.458025 141.18873)
			(xy 226.471755 141.18873) (xy 226.471755 141.20246) (xy 226.485485 141.20246) (xy 226.485485 141.21619)
			(xy 226.512955 141.21619) (xy 226.512955 141.22993) (xy 226.526685 141.22993) (xy 226.526685 141.24366)
			(xy 226.540415 141.24366) (xy 226.540415 141.25739) (xy 226.567885 141.25739) (xy 226.567885 141.27112)
			(xy 226.581615 141.27112) (xy 226.581615 141.28485) (xy 226.609075 141.28485) (xy 226.609075 141.29858)
			(xy 226.636545 141.29858) (xy 226.636545 141.31232) (xy 226.664005 141.31232) (xy 226.664005 141.32605)
			(xy 226.691465 141.32605) (xy 226.691465 141.33978) (xy 226.718935 141.33978) (xy 226.718935 141.35351)
			(xy 226.760125 141.35351) (xy 226.760125 141.36724) (xy 226.787585 141.36724) (xy 226.787585 141.38097)
			(xy 226.842515 141.38097) (xy 226.842515 141.39471) (xy 226.911175 141.39471) (xy 226.911175 141.40844)
			(xy 227.034755 141.40844) (xy 227.034755 141.42217) (xy 229.877235 141.42217) (xy 229.877235 141.4359)
			(xy 229.945895 141.4359) (xy 229.945895 141.44963) (xy 229.987085 141.44963) (xy 229.987085 141.46336)
			(xy 230.028285 141.46336) (xy 230.028285 141.4771) (xy 230.069475 141.4771) (xy 230.069475 141.49083)
			(xy 230.110675 141.49083) (xy 230.110675 141.50456) (xy 230.138135 141.50456) (xy 230.138135 141.51829)
			(xy 230.165595 141.51829) (xy 230.165595 141.53202) (xy 230.179325 141.53202) (xy 230.179325 141.54575)
			(xy 230.206795 141.54575) (xy 230.206795 141.55949) (xy 230.234255 141.55949) (xy 230.234255 141.57322)
			(xy 230.247985 141.57322) (xy 230.247985 141.58695) (xy 230.275455 141.58695) (xy 230.275455 141.60068)
			(xy 230.289185 141.60068) (xy 230.289185 141.61441) (xy 230.302915 141.61441) (xy 230.302915 141.62815)
			(xy 230.316645 141.62815) (xy 230.316645 141.64188) (xy 230.344115 141.64188) (xy 230.344115 141.65561)
			(xy 230.357845 141.65561) (xy 230.357845 141.66934) (xy 230.371575 141.66934) (xy 230.371575 141.68307)
			(xy 230.385305 141.68307) (xy 230.385305 141.69681) (xy 230.399035 141.69681) (xy 230.399035 141.71054)
			(xy 230.412775 141.71054) (xy 230.412775 141.72427) (xy 230.412775 141.738) (xy 230.426505 141.738)
			(xy 230.426505 141.75173) (xy 230.440235 141.75173) (xy 230.440235 141.76546) (xy 230.453965 141.76546)
			(xy 230.453965 141.7792) (xy 230.467695 141.7792) (xy 230.467695 141.79293) (xy 230.467695 141.80666)
			(xy 230.481425 141.80666) (xy 230.481425 141.82039) (xy 230.495165 141.82039) (xy 230.495165 141.83412)
			(xy 230.495165 141.84785) (xy 230.508895 141.84785) (xy 230.508895 141.86159) (xy 230.522625 141.86159)
			(xy 230.522625 141.87532) (xy 230.522625 141.88905) (xy 230.536355 141.88905) (xy 230.536355 141.90278)
			(xy 230.536355 141.91651) (xy 230.550085 141.91651) (xy 230.550085 141.93024) (xy 230.550085 141.94398)
			(xy 230.563815 141.94398) (xy 230.563815 141.95771) (xy 230.563815 141.97144) (xy 230.577555 141.97144)
			(xy 230.577555 141.98517) (xy 230.577555 141.9989) (xy 230.577555 142.01263) (xy 230.591285 142.01263)
			(xy 230.591285 142.02637) (xy 230.591285 142.0401) (xy 230.591285 142.05383) (xy 230.605015 142.05383)
			(xy 230.605015 142.06756) (xy 230.605015 142.08129) (xy 230.605015 142.09502) (xy 230.618745 142.09502)
			(xy 230.618745 142.10876) (xy 230.618745 142.12249) (xy 230.618745 142.13622) (xy 230.618745 142.14995)
			(xy 230.618745 142.16368) (xy 230.618745 142.17742) (xy 230.632475 142.17742) (xy 230.632475 142.19115)
			(xy 230.632475 142.20488) (xy 230.632475 142.21861) (xy 230.632475 142.23234) (xy 230.632475 142.24608)
			(xy 230.632475 142.25981) (xy 230.632475 142.27354) (xy 230.632475 142.28727) (xy 230.632475 142.301)
			(xy 230.646205 142.301) (xy 230.646205 142.31473) (xy 230.646205 142.32847) (xy 230.632475 142.32847)
			(xy 230.632475 142.3422) (xy 230.632475 142.35593) (xy 230.632475 142.36966) (xy 230.632475 142.38339)
			(xy 230.632475 142.39712) (xy 230.632475 142.41086) (xy 230.632475 142.42459) (xy 230.632475 142.43832)
			(xy 230.632475 142.45205) (xy 230.632475 142.46578) (xy 230.618745 142.46578) (xy 230.618745 142.47951)
			(xy 230.618745 142.49325) (xy 230.618745 142.50698) (xy 230.618745 142.52071) (xy 230.618745 142.53444)
			(xy 230.605015 142.53444) (xy 230.605015 142.54817) (xy 230.605015 142.5619) (xy 230.605015 142.57564)
			(xy 230.591285 142.57564) (xy 230.591285 142.58937) (xy 230.591285 142.6031) (xy 230.591285 142.61683)
			(xy 230.577555 142.61683) (xy 230.577555 142.63056) (xy 230.577555 142.64429) (xy 230.577555 142.65803)
			(xy 230.563815 142.65803) (xy 230.563815 142.67176) (xy 230.563815 142.68549) (xy 230.563815 142.69922)
			(xy 230.550085 142.69922) (xy 230.550085 142.71295) (xy 230.550085 142.72669) (xy 230.536355 142.72669)
			(xy 230.536355 142.74042) (xy 230.536355 142.75415) (xy 230.522625 142.75415) (xy 230.522625 142.76788)
			(xy 230.522625 142.78161) (xy 230.508895 142.78161) (xy 230.508895 142.79535) (xy 230.495165 142.79535)
			(xy 230.495165 142.80908) (xy 230.495165 142.82281) (xy 230.481425 142.82281) (xy 230.481425 142.83654)
			(xy 230.467695 142.83654) (xy 230.467695 142.85027) (xy 230.467695 142.864) (xy 230.453965 142.864)
			(xy 230.453965 142.87774) (xy 230.440235 142.87774) (xy 230.440235 142.89147) (xy 230.426505 142.89147)
			(xy 230.426505 142.9052) (xy 230.426505 142.91893) (xy 230.412775 142.91893) (xy 230.412775 142.93266)
			(xy 230.399035 142.93266) (xy 230.399035 142.94639) (xy 230.385305 142.94639) (xy 230.385305 142.96013)
			(xy 230.371575 142.96013) (xy 230.371575 142.97386) (xy 230.357845 142.97386) (xy 230.357845 142.98759)
			(xy 230.344115 142.98759) (xy 230.344115 143.00132) (xy 230.330385 143.00132) (xy 230.330385 143.01505)
			(xy 230.316645 143.01505) (xy 230.316645 143.02878) (xy 230.302915 143.02878) (xy 230.302915 143.04252)
			(xy 230.289185 143.04252) (xy 230.289185 143.05625) (xy 230.261725 143.05625) (xy 230.261725 143.06998)
			(xy 230.247985 143.06998) (xy 230.247985 143.08371) (xy 230.234255 143.08371) (xy 230.234255 143.09744)
			(xy 230.206795 143.09744) (xy 230.206795 143.11117) (xy 230.193065 143.11117) (xy 230.193065 143.12491)
			(xy 230.165595 143.12491) (xy 230.165595 143.13864) (xy 230.138135 143.13864) (xy 230.138135 143.15237)
			(xy 230.110675 143.15237) (xy 230.110675 143.1661) (xy 230.083205 143.1661) (xy 230.083205 143.17983)
			(xy 230.042015 143.17983) (xy 230.042015 143.19357) (xy 229.987085 143.19357) (xy 229.987085 143.2073)
			(xy 220.100225 143.2073) (xy 220.100225 143.22103) (xy 220.072765 143.22103) (xy 220.072765 143.23476)
			(xy 220.059025 143.23476) (xy 220.059025 143.24849) (xy 220.045295 143.24849) (xy 220.045295 143.26223)
			(xy 220.031565 143.26223) (xy 220.031565 143.27596) (xy 220.031565 143.28969) (xy 220.017835 143.28969)
			(xy 220.017835 143.30342) (xy 220.017835 143.31715) (xy 220.017835 143.33088) (xy 220.017835 143.34462)
			(xy 220.017835 143.35835) (xy 220.017835 143.37208) (xy 220.017835 143.38581) (xy 220.017835 143.39954)
			(xy 220.017835 143.41327) (xy 220.017835 143.42701) (xy 220.017835 143.44074) (xy 220.017835 143.45447)
			(xy 220.017835 143.4682) (xy 220.017835 143.48193) (xy 220.017835 143.49566) (xy 220.017835 143.5094)
			(xy 220.017835 143.52313) (xy 220.017835 143.53686) (xy 220.017835 143.55059) (xy 220.017835 143.56432)
			(xy 220.017835 143.57805) (xy 220.017835 143.59179) (xy 220.017835 143.60552) (xy 220.017835 143.61925)
			(xy 220.017835 143.63298) (xy 220.017835 143.64671) (xy 220.017835 143.66044) (xy 220.017835 143.67418)
			(xy 220.017835 143.68791) (xy 220.017835 143.70164) (xy 220.017835 143.71537) (xy 220.017835 143.7291)
			(xy 220.017835 143.74284) (xy 220.017835 143.75657) (xy 220.017835 143.7703) (xy 220.017835 143.78403)
			(xy 220.017835 143.79776) (xy 220.017835 143.8115) (xy 220.017835 143.82523) (xy 220.017835 143.83896)
			(xy 220.017835 143.85269) (xy 220.017835 143.86642) (xy 220.017835 143.88015) (xy 220.017835 143.89389)
			(xy 220.017835 143.90762) (xy 220.017835 143.92135) (xy 220.017835 143.93508) (xy 220.017835 143.94881)
			(xy 220.017835 143.96254) (xy 220.017835 143.97628) (xy 220.017835 143.99001) (xy 220.017835 144.00374)
			(xy 220.017835 144.01747) (xy 220.017835 144.0312) (xy 220.017835 144.04493) (xy 220.017835 144.05867)
			(xy 220.017835 144.0724) (xy 220.017835 144.08613) (xy 220.017835 144.09986) (xy 220.017835 144.11359)
			(xy 220.017835 144.12732) (xy 220.017835 144.14106) (xy 220.017835 144.15479) (xy 220.017835 144.16852)
			(xy 220.017835 144.18225) (xy 220.017835 144.19598) (xy 220.017835 144.20971) (xy 220.017835 144.22345)
			(xy 220.017835 144.23718) (xy 220.017835 144.25091) (xy 220.017835 144.26464) (xy 220.017835 144.27837)
			(xy 220.017835 144.29211) (xy 220.017835 144.30584) (xy 220.017835 144.31957) (xy 220.017835 144.3333)
			(xy 220.017835 144.34703) (xy 220.017835 144.36077) (xy 220.017835 144.3745) (xy 220.017835 144.38823)
			(xy 220.017835 144.40196) (xy 220.017835 144.41569) (xy 220.017835 144.42942) (xy 220.017835 144.44316)
			(xy 220.017835 144.45689) (xy 220.017835 144.47062) (xy 220.017835 144.48435) (xy 220.017835 144.49808)
			(xy 220.017835 144.51181) (xy 220.017835 144.52555) (xy 220.017835 144.53928) (xy 220.017835 144.55301)
			(xy 220.017835 144.56674) (xy 220.017835 144.58047) (xy 220.017835 144.5942) (xy 220.017835 144.60794)
			(xy 220.017835 144.62167) (xy 220.017835 144.6354) (xy 220.017835 144.64913) (xy 220.004105 144.64913)
			(xy 220.004105 144.66286) (xy 220.004105 144.67659) (xy 219.990375 144.67659) (xy 219.990375 144.69033)
			(xy 219.990375 144.70406) (xy 219.976635 144.70406) (xy 219.976635 144.71779) (xy 219.949175 144.71779)
			(xy 219.949175 144.73152) (xy 219.921715 144.73152) (xy 219.921715 144.74525) (xy 217.298945 144.74525)
			(xy 217.298945 144.73152) (xy 217.257755 144.73152) (xy 217.257755 144.71779) (xy 217.244025 144.71779)
			(xy 217.244025 144.70406) (xy 217.230295 144.70406) (xy 217.230295 144.69033) (xy 217.216555 144.69033)
			(xy 217.216555 144.67659) (xy 217.216555 144.66286) (xy 217.202825 144.66286) (xy 217.202825 144.64913)
			(xy 217.202825 144.6354) (xy 217.202825 144.62167) (xy 217.202825 144.60794) (xy 217.202825 144.5942)
			(xy 217.202825 144.58047) (xy 217.202825 144.56674) (xy 217.202825 144.55301) (xy 217.202825 144.53928)
			(xy 217.202825 144.52555) (xy 217.202825 144.51181) (xy 217.202825 144.49808) (xy 217.202825 144.48435)
			(xy 217.202825 144.47062) (xy 217.202825 144.45689) (xy 217.202825 144.44316) (xy 217.202825 144.42942)
			(xy 217.202825 144.41569) (xy 217.202825 144.40196) (xy 217.202825 144.38823) (xy 217.202825 144.3745)
			(xy 217.202825 144.36077) (xy 217.202825 144.34703) (xy 217.202825 144.3333) (xy 217.202825 144.31957)
			(xy 217.202825 144.30584) (xy 217.202825 144.29211) (xy 217.202825 144.27837) (xy 217.202825 144.26464)
			(xy 217.202825 144.25091) (xy 217.202825 144.23718) (xy 217.202825 144.22345) (xy 217.202825 144.20971)
			(xy 217.202825 144.19598) (xy 217.202825 144.18225) (xy 217.202825 144.16852) (xy 217.202825 144.15479)
			(xy 217.202825 144.14106) (xy 217.202825 144.12732) (xy 217.202825 144.11359) (xy 217.202825 144.09986)
			(xy 217.202825 144.08613) (xy 217.202825 144.0724) (xy 217.202825 144.05867) (xy 217.202825 144.04493)
			(xy 217.202825 144.0312) (xy 217.202825 144.01747) (xy 217.202825 144.00374) (xy 217.202825 143.99001)
			(xy 217.202825 143.97628) (xy 217.202825 143.96254) (xy 217.202825 143.94881) (xy 217.202825 143.93508)
			(xy 217.202825 143.92135) (xy 217.202825 143.90762) (xy 217.202825 143.89389) (xy 217.202825 143.88015)
			(xy 217.202825 143.86642) (xy 217.202825 143.85269) (xy 217.202825 143.83896) (xy 217.202825 143.82523)
			(xy 217.189095 143.82523) (xy 217.189095 143.8115) (xy 217.189095 143.79776) (xy 217.189095 143.78403)
			(xy 217.175365 143.78403) (xy 217.175365 143.7703) (xy 217.175365 143.75657) (xy 217.161635 143.75657)
			(xy 217.161635 143.74284) (xy 217.134165 143.74284) (xy 217.134165 143.7291) (xy 217.092975 143.7291)
			(xy 217.092975 143.71537) (xy 217.051775 143.71537) (xy 217.051775 143.7291) (xy 217.010585 143.7291)
			(xy 217.010585 143.74284) (xy 216.996845 143.74284) (xy 216.996845 143.75657) (xy 216.983115 143.75657)
			(xy 216.983115 143.7703) (xy 216.969385 143.7703) (xy 216.969385 143.78403) (xy 216.955655 143.78403)
			(xy 216.955655 143.79776) (xy 216.955655 143.8115) (xy 216.955655 143.82523) (xy 216.955655 143.83896)
			(xy 216.941925 143.83896) (xy 216.941925 143.85269) (xy 216.941925 143.86642) (xy 216.941925 143.88015)
			(xy 216.941925 143.89389) (xy 216.941925 143.90762) (xy 216.941925 143.92135) (xy 216.941925 143.93508)
			(xy 216.941925 143.94881) (xy 216.941925 143.96254) (xy 216.941925 143.97628) (xy 216.941925 143.99001)
			(xy 216.941925 144.00374) (xy 216.941925 144.01747) (xy 216.941925 144.0312) (xy 216.941925 144.04493)
			(xy 216.941925 144.05867) (xy 216.941925 144.0724) (xy 216.941925 144.08613) (xy 216.941925 144.09986)
			(xy 216.941925 144.11359) (xy 216.941925 144.12732) (xy 216.941925 144.14106) (xy 216.941925 144.15479)
			(xy 216.941925 144.16852) (xy 216.941925 144.18225) (xy 216.941925 144.19598) (xy 216.941925 144.20971)
			(xy 216.941925 144.22345) (xy 216.941925 144.23718) (xy 216.941925 144.25091) (xy 216.941925 144.26464)
			(xy 216.941925 144.27837) (xy 216.941925 144.29211) (xy 216.941925 144.30584) (xy 216.941925 144.31957)
			(xy 216.941925 144.3333) (xy 216.941925 144.34703) (xy 216.941925 144.36077) (xy 216.941925 144.3745)
			(xy 216.941925 144.38823) (xy 216.941925 144.40196) (xy 216.941925 144.41569) (xy 216.941925 144.42942)
			(xy 216.941925 144.44316) (xy 216.941925 144.45689) (xy 216.941925 144.47062) (xy 216.941925 144.48435)
			(xy 216.941925 144.49808) (xy 216.941925 144.51181) (xy 216.941925 144.52555) (xy 216.941925 144.53928)
			(xy 216.941925 144.55301) (xy 216.941925 144.56674) (xy 216.941925 144.58047) (xy 216.941925 144.5942)
			(xy 216.941925 144.60794) (xy 216.941925 144.62167) (xy 216.941925 144.6354) (xy 216.941925 144.64913)
			(xy 216.941925 144.66286) (xy 216.941925 144.67659) (xy 216.928195 144.67659) (xy 216.928195 144.69033)
			(xy 216.914455 144.69033) (xy 216.914455 144.70406) (xy 216.900725 144.70406) (xy 216.900725 144.71779)
			(xy 216.886995 144.71779) (xy 216.886995 144.73152) (xy 216.845805 144.73152) (xy 216.845805 144.74525)
			(xy 215.500085 144.74525) (xy 215.500085 144.73152) (xy 215.472625 144.73152) (xy 215.472625 144.71779)
			(xy 215.445165 144.71779) (xy 215.445165 144.70406) (xy 215.431425 144.70406) (xy 215.431425 144.69033)
			(xy 215.431425 144.67659) (xy 215.417695 144.67659) (xy 215.417695 144.66286) (xy 215.417695 144.64913)
			(xy 215.417695 144.6354) (xy 215.403965 144.6354) (xy 215.403965 144.62167) (xy 215.403965 144.60794)
			(xy 215.403965 144.5942) (xy 215.403965 144.58047) (xy 215.403965 144.56674) (xy 215.403965 144.55301)
			(xy 215.403965 144.53928) (xy 215.403965 144.52555) (xy 215.403965 144.51181) (xy 215.403965 144.49808)
			(xy 215.403965 144.48435) (xy 215.403965 144.47062) (xy 215.403965 144.45689) (xy 215.403965 144.44316)
			(xy 215.403965 144.42942) (xy 215.403965 144.41569) (xy 215.403965 144.40196) (xy 215.403965 144.38823)
			(xy 215.403965 144.3745) (xy 215.403965 144.36077) (xy 215.403965 144.34703) (xy 215.403965 144.3333)
			(xy 215.403965 144.31957) (xy 215.403965 144.30584) (xy 215.403965 144.29211) (xy 215.403965 144.27837)
			(xy 215.403965 144.26464) (xy 215.403965 144.25091) (xy 215.403965 144.23718) (xy 215.403965 144.22345)
			(xy 215.403965 144.20971) (xy 215.403965 144.19598) (xy 215.403965 144.18225) (xy 215.403965 144.16852)
			(xy 215.403965 144.15479) (xy 215.403965 144.14106) (xy 215.403965 144.12732) (xy 215.403965 144.11359)
			(xy 215.403965 144.09986) (xy 215.403965 144.08613) (xy 215.403965 144.0724) (xy 215.403965 144.05867)
			(xy 215.403965 144.04493) (xy 215.403965 144.0312) (xy 215.403965 144.01747) (xy 215.403965 144.00374)
			(xy 215.403965 143.99001) (xy 215.403965 143.97628) (xy 215.403965 143.96254) (xy 215.403965 143.94881)
			(xy 215.403965 143.93508) (xy 215.403965 143.92135) (xy 215.403965 143.90762) (xy 215.403965 143.89389)
			(xy 215.403965 143.88015) (xy 215.403965 143.86642) (xy 215.403965 143.85269) (xy 215.403965 143.83896)
			(xy 215.403965 143.82523) (xy 215.403965 143.8115) (xy 215.403965 143.79776) (xy 215.403965 143.78403)
			(xy 215.403965 143.7703) (xy 215.403965 143.75657) (xy 215.403965 143.74284) (xy 215.403965 143.7291)
			(xy 215.403965 143.71537) (xy 215.403965 143.70164) (xy 215.403965 143.68791) (xy 215.403965 143.67418)
			(xy 215.403965 143.66044) (xy 215.403965 143.64671) (xy 215.403965 143.63298) (xy 215.403965 143.61925)
			(xy 215.403965 143.60552) (xy 215.403965 143.59179) (xy 215.403965 143.57805) (xy 215.403965 143.56432)
			(xy 215.403965 143.55059) (xy 215.403965 143.53686) (xy 215.403965 143.52313) (xy 215.417695 143.52313)
			(xy 215.417695 143.5094) (xy 215.403965 143.5094) (xy 215.403965 143.49566) (xy 215.403965 143.48193)
			(xy 215.403965 143.4682) (xy 215.403965 143.45447) (xy 215.403965 143.44074) (xy 215.403965 143.42701)
			(xy 215.403965 143.41327) (xy 215.403965 143.39954) (xy 215.403965 143.38581) (xy 215.390235 143.38581)
			(xy 215.390235 143.37208) (xy 215.390235 143.35835) (xy 215.376505 143.35835) (xy 215.376505 143.34462)
			(xy 215.376505 143.33088) (xy 215.362775 143.33088) (xy 215.362775 143.31715) (xy 215.362775 143.30342)
			(xy 215.349035 143.30342) (xy 215.349035 143.28969) (xy 215.335305 143.28969) (xy 215.335305 143.27596)
			(xy 215.321575 143.27596) (xy 215.321575 143.26223) (xy 215.307845 143.26223) (xy 215.307845 143.24849)
			(xy 215.280385 143.24849) (xy 215.280385 143.23476) (xy 215.252915 143.23476) (xy 215.252915 143.22103)
			(xy 215.211725 143.22103) (xy 215.211725 143.2073) (xy 215.101865 143.2073) (xy 215.101865 143.22103)
			(xy 215.060675 143.22103) (xy 215.060675 143.23476) (xy 215.033215 143.23476) (xy 215.033215 143.24849)
			(xy 215.005745 143.24849) (xy 215.005745 143.26223) (xy 214.992015 143.26223) (xy 214.992015 143.27596)
			(xy 214.978285 143.27596) (xy 214.978285 143.28969) (xy 214.964555 143.28969) (xy 214.964555 143.30342)
			(xy 214.950815 143.30342) (xy 214.950815 143.31715) (xy 214.937085 143.31715) (xy 214.937085 143.33088)
			(xy 214.937085 143.34462) (xy 214.923355 143.34462) (xy 214.923355 143.35835) (xy 214.923355 143.37208)
			(xy 214.909625 143.37208) (xy 214.909625 143.38581) (xy 214.909625 143.39954) (xy 214.909625 143.41327)
			(xy 214.909625 143.42701) (xy 214.909625 143.44074) (xy 214.909625 143.45447) (xy 214.895895 143.45447)
			(xy 214.895895 143.4682) (xy 214.909625 143.4682) (xy 214.909625 143.48193) (xy 214.909625 143.49566)
			(xy 214.895895 143.49566) (xy 214.895895 143.5094) (xy 214.909625 143.5094) (xy 214.909625 143.52313)
			(xy 214.909625 143.53686) (xy 214.909625 143.55059) (xy 214.909625 143.56432) (xy 214.909625 143.57805)
			(xy 214.909625 143.59179) (xy 214.909625 143.60552) (xy 214.909625 143.61925) (xy 214.909625 143.63298)
			(xy 214.909625 143.64671) (xy 214.909625 143.66044) (xy 214.909625 143.67418) (xy 214.909625 143.68791)
			(xy 214.909625 143.70164) (xy 214.909625 143.71537) (xy 214.909625 143.7291) (xy 214.909625 143.74284)
			(xy 214.909625 143.75657) (xy 214.909625 143.7703) (xy 214.909625 143.78403) (xy 214.909625 143.79776)
			(xy 214.909625 143.8115) (xy 214.909625 143.82523) (xy 214.909625 143.83896) (xy 214.909625 143.85269)
			(xy 214.909625 143.86642) (xy 214.909625 143.88015) (xy 214.909625 143.89389) (xy 214.909625 143.90762)
			(xy 214.909625 143.92135) (xy 214.909625 143.93508) (xy 214.909625 143.94881) (xy 214.909625 143.96254)
			(xy 214.909625 143.97628) (xy 214.909625 143.99001) (xy 214.909625 144.00374) (xy 214.909625 144.01747)
			(xy 214.909625 144.0312) (xy 214.909625 144.04493) (xy 214.909625 144.05867) (xy 214.909625 144.0724)
			(xy 214.909625 144.08613) (xy 214.909625 144.09986) (xy 214.895895 144.09986) (xy 214.895895 144.11359)
			(xy 214.895895 144.12732) (xy 214.895895 144.14106) (xy 214.895895 144.15479) (xy 214.882155 144.15479)
			(xy 214.882155 144.16852) (xy 214.868425 144.16852) (xy 214.868425 144.18225) (xy 214.854695 144.18225)
			(xy 214.854695 144.19598) (xy 214.840965 144.19598) (xy 214.840965 144.20971) (xy 214.799765 144.20971)
			(xy 214.799765 144.22345) (xy 213.975865 144.22345) (xy 213.975865 144.20971) (xy 213.934665 144.20971)
			(xy 213.934665 144.19598) (xy 213.920935 144.19598) (xy 213.920935 144.18225) (xy 213.907205 144.18225)
			(xy 213.907205 144.16852) (xy 213.893475 144.16852) (xy 213.893475 144.15479) (xy 213.879745 144.15479)
			(xy 213.879745 144.14106) (xy 213.879745 144.12732) (xy 213.879745 144.11359) (xy 213.866005 144.11359)
			(xy 213.866005 144.09986) (xy 213.866005 144.08613) (xy 213.866005 144.0724) (xy 213.866005 144.05867)
			(xy 213.866005 144.04493) (xy 213.866005 144.0312) (xy 213.866005 144.01747) (xy 213.866005 144.00374)
			(xy 213.866005 143.99001) (xy 213.866005 143.97628) (xy 213.866005 143.96254) (xy 213.866005 143.94881)
			(xy 213.866005 143.93508) (xy 213.866005 143.92135) (xy 213.866005 143.90762) (xy 213.866005 143.89389)
			(xy 213.866005 143.88015) (xy 213.866005 143.86642) (xy 213.866005 143.85269) (xy 213.866005 143.83896)
			(xy 213.866005 143.82523) (xy 213.866005 143.8115) (xy 213.866005 143.79776) (xy 213.866005 143.78403)
			(xy 213.866005 143.7703) (xy 213.866005 143.75657) (xy 213.866005 143.74284) (xy 213.866005 143.7291)
			(xy 213.866005 143.71537) (xy 213.866005 143.70164) (xy 213.866005 143.68791) (xy 213.866005 143.67418)
			(xy 213.866005 143.66044) (xy 213.866005 143.64671) (xy 213.866005 143.63298) (xy 213.866005 143.61925)
			(xy 213.866005 143.60552) (xy 213.866005 143.59179) (xy 213.866005 143.57805) (xy 213.866005 143.56432)
			(xy 213.866005 143.55059) (xy 213.866005 143.53686) (xy 213.866005 143.52313) (xy 213.866005 143.5094)
			(xy 213.866005 143.49566) (xy 213.866005 143.48193) (xy 213.866005 143.4682) (xy 213.866005 143.45447)
			(xy 213.866005 143.44074) (xy 213.866005 143.42701) (xy 213.866005 143.41327) (xy 213.879745 143.41327)
			(xy 213.879745 143.39954) (xy 213.879745 143.38581) (xy 213.866005 143.38581) (xy 213.866005 143.37208)
			(xy 213.879745 143.37208) (xy 213.879745 143.35835) (xy 213.866005 143.35835) (xy 213.866005 143.34462)
			(xy 213.866005 143.33088) (xy 213.866005 143.31715) (xy 213.866005 143.30342) (xy 213.866005 143.28969)
			(xy 213.866005 143.27596) (xy 213.852275 143.27596) (xy 213.852275 143.26223) (xy 213.852275 143.24849)
			(xy 213.838545 143.24849) (xy 213.838545 143.23476) (xy 213.811085 143.23476) (xy 213.811085 143.22103)
			(xy 213.783615 143.22103) (xy 213.783615 143.2073) (xy 211.655195 143.2073) (xy 211.655195 143.22103)
			(xy 211.627735 143.22103) (xy 211.627735 143.23476) (xy 211.614005 143.23476) (xy 211.614005 143.24849)
			(xy 211.600275 143.24849) (xy 211.600275 143.26223) (xy 211.586535 143.26223) (xy 211.586535 143.27596)
			(xy 211.586535 143.28969) (xy 211.572805 143.28969) (xy 211.572805 143.30342) (xy 211.572805 143.31715)
			(xy 211.572805 143.33088) (xy 211.572805 143.34462) (xy 211.572805 143.35835) (xy 211.572805 143.37208)
			(xy 211.572805 143.38581) (xy 211.572805 143.39954) (xy 211.572805 143.41327) (xy 211.572805 143.42701)
			(xy 211.572805 143.44074) (xy 211.572805 143.45447) (xy 211.572805 143.4682) (xy 211.572805 143.48193)
			(xy 211.572805 143.49566) (xy 211.572805 143.5094) (xy 211.572805 143.52313) (xy 211.572805 143.53686)
			(xy 211.572805 143.55059) (xy 211.572805 143.56432) (xy 211.572805 143.57805) (xy 211.572805 143.59179)
			(xy 211.572805 143.60552) (xy 211.572805 143.61925) (xy 211.572805 143.63298) (xy 211.572805 143.64671)
			(xy 211.572805 143.66044) (xy 211.572805 143.67418) (xy 211.572805 143.68791) (xy 211.572805 143.70164)
			(xy 211.572805 143.71537) (xy 211.572805 143.7291) (xy 211.572805 143.74284) (xy 211.572805 143.75657)
			(xy 211.572805 143.7703) (xy 211.572805 143.78403) (xy 211.572805 143.79776) (xy 211.572805 143.8115)
			(xy 211.572805 143.82523) (xy 211.572805 143.83896) (xy 211.572805 143.85269) (xy 211.572805 143.86642)
			(xy 211.572805 143.88015) (xy 211.572805 143.89389) (xy 211.572805 143.90762) (xy 211.572805 143.92135)
			(xy 211.572805 143.93508) (xy 211.572805 143.94881) (xy 211.572805 143.96254) (xy 211.572805 143.97628)
			(xy 211.572805 143.99001) (xy 211.572805 144.00374) (xy 211.572805 144.01747) (xy 211.572805 144.0312)
			(xy 211.572805 144.04493) (xy 211.572805 144.05867) (xy 211.572805 144.0724) (xy 211.572805 144.08613)
			(xy 211.572805 144.09986) (xy 211.572805 144.11359) (xy 211.572805 144.12732) (xy 211.572805 144.14106)
			(xy 211.572805 144.15479) (xy 211.572805 144.16852) (xy 211.572805 144.18225) (xy 211.572805 144.19598)
			(xy 211.572805 144.20971) (xy 211.572805 144.22345) (xy 211.572805 144.23718) (xy 211.572805 144.25091)
			(xy 211.572805 144.26464) (xy 211.572805 144.27837) (xy 211.572805 144.29211) (xy 211.572805 144.30584)
			(xy 211.572805 144.31957) (xy 211.572805 144.3333) (xy 211.572805 144.34703) (xy 211.572805 144.36077)
			(xy 211.572805 144.3745) (xy 211.572805 144.38823) (xy 211.572805 144.40196) (xy 211.572805 144.41569)
			(xy 211.572805 144.42942) (xy 211.572805 144.44316) (xy 211.572805 144.45689) (xy 211.572805 144.47062)
			(xy 211.572805 144.48435) (xy 209.526775 144.48435) (xy 209.526775 144.47062) (xy 209.526775 144.45689)
			(xy 209.526775 144.44316) (xy 209.526775 144.42942) (xy 209.526775 144.41569) (xy 209.526775 144.40196)
			(xy 209.526775 144.38823) (xy 209.526775 144.3745) (xy 209.526775 144.36077) (xy 209.526775 144.34703)
			(xy 209.526775 144.3333) (xy 209.526775 144.31957) (xy 209.526775 144.30584) (xy 209.526775 144.29211)
			(xy 209.526775 144.27837) (xy 209.526775 144.26464) (xy 209.526775 144.25091) (xy 209.526775 144.23718)
			(xy 209.526775 144.22345) (xy 209.526775 144.20971) (xy 209.526775 144.19598) (xy 209.526775 144.18225)
			(xy 209.526775 144.16852) (xy 209.526775 144.15479) (xy 209.526775 144.14106) (xy 209.526775 144.12732)
			(xy 209.526775 144.11359) (xy 209.526775 144.09986) (xy 209.526775 144.08613) (xy 209.526775 144.0724)
			(xy 209.526775 144.05867) (xy 209.526775 144.04493) (xy 209.526775 144.0312) (xy 209.526775 144.01747)
			(xy 209.526775 144.00374) (xy 209.526775 143.99001) (xy 209.526775 143.97628) (xy 209.526775 143.96254)
			(xy 209.526775 143.94881) (xy 209.526775 143.93508) (xy 209.526775 143.92135) (xy 209.526775 143.90762)
			(xy 209.526775 143.89389) (xy 209.526775 143.88015) (xy 209.526775 143.86642) (xy 209.526775 143.85269)
			(xy 209.526775 143.83896) (xy 209.526775 143.82523) (xy 209.526775 143.8115) (xy 209.526775 143.79776)
			(xy 209.526775 143.78403) (xy 209.526775 143.7703) (xy 209.526775 143.75657) (xy 209.526775 143.74284)
			(xy 209.526775 143.7291) (xy 209.526775 143.71537) (xy 209.526775 143.70164) (xy 209.526775 143.68791)
			(xy 209.526775 143.67418) (xy 209.526775 143.66044) (xy 209.526775 143.64671) (xy 209.526775 143.63298)
			(xy 209.526775 143.61925) (xy 209.526775 143.60552) (xy 209.526775 143.59179) (xy 209.526775 143.57805)
			(xy 209.526775 143.56432) (xy 209.526775 143.55059) (xy 209.526775 143.53686) (xy 209.526775 143.52313)
			(xy 209.526775 143.5094) (xy 209.526775 143.49566) (xy 209.526775 143.48193) (xy 209.526775 143.4682)
			(xy 209.526775 143.45447) (xy 209.526775 143.44074) (xy 209.526775 143.42701) (xy 209.526775 143.41327)
			(xy 209.526775 143.39954) (xy 209.526775 143.38581) (xy 209.526775 143.37208) (xy 209.526775 143.35835)
			(xy 209.526775 143.34462) (xy 209.526775 143.33088) (xy 209.526775 143.31715) (xy 209.526775 143.30342)
			(xy 209.526775 143.28969) (xy 209.526775 143.27596) (xy 209.526775 143.26223) (xy 209.526775 143.24849)
			(xy 210.858755 143.24849) (xy 210.858755 143.23476) (xy 210.858755 143.22103) (xy 210.858755 143.2073)
			(xy 210.858755 143.19357) (xy 210.858755 143.17983) (xy 210.858755 143.1661) (xy 210.858755 143.15237)
			(xy 210.858755 143.13864) (xy 210.858755 143.12491) (xy 210.858755 143.11117) (xy 210.858755 143.09744)
			(xy 210.858755 143.08371) (xy 210.858755 143.06998) (xy 210.858755 143.05625) (xy 210.858755 143.04252)
			(xy 210.858755 143.02878) (xy 210.858755 143.01505) (xy 210.858755 143.00132) (xy 210.858755 142.98759)
			(xy 210.858755 142.97386) (xy 210.858755 142.96013) (xy 210.858755 142.94639) (xy 210.858755 142.93266)
			(xy 210.858755 142.91893) (xy 210.858755 142.9052) (xy 210.858755 142.89147) (xy 210.858755 142.87774)
			(xy 210.858755 142.864) (xy 210.858755 142.85027) (xy 210.858755 142.83654) (xy 210.858755 142.82281)
			(xy 210.858755 142.80908) (xy 210.858755 142.79535) (xy 210.858755 142.78161) (xy 210.858755 142.76788)
			(xy 210.858755 142.75415) (xy 210.858755 142.74042) (xy 210.858755 142.72669) (xy 210.858755 142.71295)
			(xy 210.858755 142.69922) (xy 210.858755 142.68549) (xy 210.858755 142.67176) (xy 210.858755 142.65803)
			(xy 210.858755 142.64429) (xy 210.858755 142.63056) (xy 210.858755 142.61683) (xy 210.858755 142.6031)
			(xy 210.858755 142.58937) (xy 210.858755 142.57564) (xy 210.858755 142.5619) (xy 210.858755 142.54817)
			(xy 210.858755 142.53444) (xy 210.858755 142.52071) (xy 210.858755 142.50698) (xy 210.858755 142.49325)
			(xy 210.858755 142.47951) (xy 210.858755 142.46578) (xy 210.858755 142.45205) (xy 210.858755 142.43832)
			(xy 210.858755 142.42459) (xy 210.858755 142.41086) (xy 210.858755 142.39712) (xy 210.858755 142.38339)
			(xy 210.858755 142.36966) (xy 210.858755 142.35593) (xy 210.858755 142.3422) (xy 210.858755 142.32847)
			(xy 210.858755 142.31473) (xy 210.858755 142.301) (xy 210.858755 142.28727) (xy 210.858755 142.27354)
			(xy 210.858755 142.25981) (xy 210.858755 142.24608) (xy 210.858755 142.23234) (xy 210.858755 142.21861)
			(xy 210.858755 142.20488) (xy 210.858755 142.19115) (xy 210.858755 142.17742) (xy 210.858755 142.16368)
			(xy 210.858755 142.14995) (xy 210.858755 142.13622) (xy 210.858755 142.12249) (xy 210.858755 142.10876)
			(xy 210.858755 142.09502) (xy 210.858755 142.08129) (xy 210.858755 142.06756) (xy 210.858755 142.05383)
			(xy 210.858755 142.0401) (xy 210.858755 142.02637) (xy 210.858755 142.01263) (xy 210.858755 141.9989)
			(xy 210.858755 141.98517) (xy 210.858755 141.97144) (xy 210.858755 141.95771) (xy 210.858755 141.94398)
			(xy 210.858755 141.93024) (xy 210.858755 141.91651) (xy 210.858755 141.90278) (xy 210.858755 141.88905)
			(xy 210.858755 141.87532) (xy 210.858755 141.86159) (xy 210.858755 141.84785) (xy 210.858755 141.83412)
			(xy 210.858755 141.82039) (xy 210.858755 141.80666) (xy 210.858755 141.79293) (xy 210.858755 141.7792)
			(xy 210.858755 141.76546) (xy 210.858755 141.75173) (xy 210.858755 141.738) (xy 209.526775 141.738)
			(xy 209.526775 141.72427) (xy 209.526775 141.71054) (xy 209.526775 141.69681) (xy 209.526775 141.68307)
			(xy 209.526775 141.66934) (xy 209.526775 141.65561) (xy 209.526775 141.64188) (xy 209.526775 141.62815)
			(xy 209.526775 141.61441) (xy 209.526775 141.60068) (xy 209.526775 141.58695) (xy 209.526775 141.57322)
			(xy 209.526775 141.55949) (xy 209.526775 141.54575) (xy 209.526775 141.53202) (xy 209.526775 141.51829)
			(xy 209.526775 141.50456) (xy 209.526775 141.49083) (xy 209.526775 141.4771) (xy 209.526775 141.46336)
			(xy 209.526775 141.44963) (xy 209.526775 141.4359) (xy 209.526775 141.42217) (xy 209.526775 141.40844)
			(xy 209.526775 141.39471) (xy 210.858755 141.39471) (xy 210.858755 141.38097) (xy 210.858755 141.36724)
			(xy 210.858755 141.35351) (xy 210.858755 141.33978) (xy 210.858755 141.32605) (xy 210.858755 141.31232)
			(xy 210.858755 141.29858) (xy 210.858755 141.28485) (xy 210.858755 141.27112) (xy 210.858755 141.25739)
			(xy 210.858755 141.24366) (xy 210.858755 141.22993) (xy 210.858755 141.21619) (xy 210.858755 141.20246)
			(xy 210.858755 141.18873) (xy 210.858755 141.175) (xy 210.858755 141.16127) (xy 210.858755 141.14754)
			(xy 210.858755 141.1338) (xy 210.858755 141.12007) (xy 210.858755 141.10634) (xy 210.858755 141.09261)
			(xy 210.858755 141.07888) (xy 210.858755 141.06514) (xy 210.858755 141.05141) (xy 210.858755 141.03768)
			(xy 210.858755 141.02395) (xy 210.858755 141.01022) (xy 210.858755 140.99648) (xy 210.858755 140.98275)
			(xy 210.858755 140.96902) (xy 210.858755 140.95529) (xy 210.858755 140.94156) (xy 210.858755 140.92783)
			(xy 210.858755 140.91409) (xy 210.858755 140.90036) (xy 210.858755 140.88663) (xy 210.858755 140.8729)
			(xy 210.858755 140.85917) (xy 210.858755 140.84544) (xy 210.858755 140.8317) (xy 210.858755 140.81797)
			(xy 210.858755 140.80424) (xy 210.858755 140.79051) (xy 210.858755 140.77678) (xy 210.858755 140.76305)
			(xy 210.858755 140.74931) (xy 210.858755 140.73558) (xy 210.858755 140.72185) (xy 210.858755 140.70812)
			(xy 210.858755 140.69439) (xy 210.858755 140.68066) (xy 210.858755 140.66693) (xy 210.858755 140.65319)
			(xy 210.858755 140.63946) (xy 210.858755 140.62573) (xy 210.858755 140.612) (xy 210.858755 140.59827)
			(xy 210.858755 140.58453) (xy 210.858755 140.5708) (xy 210.858755 140.55707) (xy 210.858755 140.54334)
			(xy 210.858755 140.5296) (xy 210.858755 140.51587) (xy 210.858755 140.50214) (xy 210.858755 140.48841)
			(xy 210.858755 140.47468) (xy 210.858755 140.46095) (xy 210.858755 140.44722) (xy 210.858755 140.43348)
			(xy 210.858755 140.41975) (xy 210.858755 140.40602) (xy 210.858755 140.39229) (xy 210.858755 140.37856)
			(xy 210.858755 140.36483) (xy 210.858755 140.35109) (xy 210.858755 140.33736) (xy 210.858755 140.32363)
			(xy 210.858755 140.3099) (xy 210.858755 140.29617) (xy 210.858755 140.28244) (xy 210.858755 140.2687)
			(xy 210.858755 140.25497) (xy 210.858755 140.24124) (xy 210.858755 140.22751) (xy 210.858755 140.21378)
			(xy 210.858755 140.20005) (xy 210.858755 140.18631) (xy 210.858755 140.17258) (xy 210.858755 140.15885)
			(xy 210.858755 140.14512) (xy 210.858755 140.13139) (xy 210.858755 140.11765) (xy 210.858755 140.10392)
			(xy 210.858755 140.09019) (xy 210.858755 140.07646) (xy 210.858755 140.06273) (xy 210.858755 140.04899)
			(xy 210.858755 140.03526) (xy 210.858755 140.02153) (xy 210.858755 140.0078) (xy 210.858755 139.99407)
			(xy 210.858755 139.98034) (xy 210.858755 139.9666) (xy 210.858755 139.95287) (xy 210.858755 139.93914)
			(xy 210.858755 139.92541) (xy 210.858755 139.91168) (xy 210.858755 139.89795) (xy 210.858755 139.88421)
			(xy 209.540505 139.88421) (xy 209.540505 139.87048) (xy 209.526775 139.87048) (xy 209.526775 139.85675)
			(xy 209.526775 139.84302) (xy 209.526775 139.82929) (xy 209.526775 139.81556) (xy 209.526775 139.80182)
			(xy 209.526775 139.78809) (xy 209.526775 139.77436) (xy 209.526775 139.76063) (xy 209.526775 139.7469)
			(xy 209.526775 139.73317) (xy 209.526775 139.71943) (xy 209.526775 139.7057) (xy 209.526775 139.69197)
			(xy 209.526775 139.67824) (xy 209.526775 139.66451) (xy 209.526775 139.65078) (xy 209.526775 139.63704)
			(xy 209.526775 139.62331) (xy 209.526775 139.60958) (xy 209.526775 139.59585) (xy 209.526775 139.58212)
			(xy 209.526775 139.56838) (xy 209.526775 139.55465) (xy 209.526775 139.54092) (xy 210.858755 139.54092)
			(xy 210.858755 139.52719) (xy 210.858755 139.51346) (xy 210.858755 139.49972) (xy 210.858755 139.48599)
			(xy 210.858755 139.47226) (xy 210.858755 139.45853) (xy 210.858755 139.4448) (xy 210.858755 139.43107)
			(xy 210.858755 139.41733) (xy 210.858755 139.4036) (xy 210.858755 139.38987) (xy 210.858755 139.37614)
			(xy 210.858755 139.36241) (xy 210.858755 139.34868) (xy 210.858755 139.33494) (xy 210.858755 139.32121)
			(xy 210.858755 139.30748) (xy 210.858755 139.29375) (xy 210.858755 139.28002) (xy 210.858755 139.26629)
			(xy 210.858755 139.25255) (xy 210.858755 139.23882) (xy 210.858755 139.22509) (xy 210.858755 139.21136)
			(xy 210.858755 139.19763) (xy 210.858755 139.1839) (xy 210.858755 139.17016) (xy 210.858755 139.15643)
			(xy 210.858755 139.1427) (xy 210.858755 139.12897) (xy 210.858755 139.11524) (xy 210.858755 139.10151)
			(xy 210.858755 139.08777) (xy 210.858755 139.07404) (xy 210.858755 139.06031) (xy 210.858755 139.04658)
			(xy 210.858755 139.03285) (xy 210.858755 139.01911) (xy 210.858755 139.00538) (xy 210.858755 138.99165)
			(xy 210.858755 138.97792) (xy 210.858755 138.96419) (xy 210.858755 138.95045) (xy 210.858755 138.93672)
			(xy 210.858755 138.92299) (xy 210.858755 138.90926) (xy 210.858755 138.89553) (xy 210.858755 138.8818)
			(xy 210.858755 138.86806) (xy 210.858755 138.85433) (xy 210.858755 138.8406) (xy 210.858755 138.82687)
			(xy 210.858755 138.81314) (xy 210.858755 138.79941) (xy 210.858755 138.78567) (xy 210.858755 138.77194)
			(xy 210.858755 138.75821) (xy 210.858755 138.74448) (xy 210.858755 138.73075) (xy 210.858755 138.71702)
			(xy 210.858755 138.70328) (xy 210.858755 138.68955) (xy 210.858755 138.67582) (xy 210.858755 138.66209)
			(xy 210.858755 138.64836) (xy 210.858755 138.63463) (xy 210.858755 138.62089) (xy 210.858755 138.60716)
			(xy 210.858755 138.59343) (xy 210.858755 138.5797) (xy 210.858755 138.56597) (xy 210.858755 138.55224)
			(xy 210.858755 138.5385) (xy 210.858755 138.52477) (xy 210.858755 138.51104) (xy 210.858755 138.49731)
			(xy 210.858755 138.48358) (xy 210.858755 138.46984) (xy 210.858755 138.45611) (xy 210.858755 138.44238)
			(xy 210.858755 138.42865) (xy 210.858755 138.41492) (xy 210.858755 138.40118) (xy 210.858755 138.38745)
			(xy 210.858755 138.37372) (xy 210.858755 138.35999) (xy 210.858755 138.34626) (xy 210.858755 138.33253)
			(xy 210.858755 138.31879) (xy 210.858755 138.30506) (xy 210.858755 138.29133) (xy 210.858755 138.2776)
			(xy 210.858755 138.26387) (xy 210.858755 138.25014) (xy 210.858755 138.2364) (xy 210.858755 138.22267)
			(xy 210.858755 138.20894) (xy 210.858755 138.19521) (xy 210.858755 138.18148) (xy 210.858755 138.16775)
			(xy 210.858755 138.15401) (xy 210.858755 138.14028) (xy 210.858755 138.12655) (xy 210.858755 138.11282)
			(xy 210.858755 138.09909) (xy 210.858755 138.08536) (xy 210.858755 138.07162) (xy 210.858755 138.05789)
			(xy 210.858755 138.04416) (xy 210.858755 138.03043) (xy 210.858755 138.0167) (xy 209.526775 138.0167)
			(xy 209.526775 138.00296) (xy 209.526775 137.98923) (xy 209.526775 137.9755) (xy 209.526775 137.96177)
			(xy 209.526775 137.94804) (xy 209.526775 137.9343) (xy 209.526775 137.92057) (xy 209.526775 137.90684)
			(xy 209.526775 137.89311) (xy 209.526775 137.87938) (xy 209.526775 137.86565) (xy 209.526775 137.85191)
			(xy 209.526775 137.83818) (xy 209.526775 137.82445) (xy 209.526775 137.81072) (xy 209.526775 137.79699)
			(xy 209.526775 137.78326) (xy 209.526775 137.76952) (xy 209.526775 137.75579) (xy 209.526775 137.74206)
			(xy 209.526775 137.72833) (xy 209.526775 137.7146) (xy 209.526775 137.70087) (xy 209.526775 137.68713)
			(xy 209.540505 137.68713) (xy 209.540505 137.6734) (xy 210.858755 137.6734) (xy 210.858755 137.65967)
			(xy 210.858755 137.64594) (xy 210.858755 137.63221) (xy 210.858755 137.61848) (xy 210.858755 137.60474)
			(xy 210.858755 137.59101) (xy 210.858755 137.57728) (xy 210.858755 137.56355) (xy 210.858755 137.54982)
			(xy 210.858755 137.53609) (xy 210.858755 137.52235) (xy 210.858755 137.50862) (xy 210.858755 137.49489)
			(xy 210.858755 137.48116) (xy 210.858755 137.46743) (xy 210.858755 137.45369) (xy 210.858755 137.43996)
			(xy 210.858755 137.42623) (xy 210.858755 137.4125) (xy 210.858755 137.39877) (xy 210.858755 137.38503)
			(xy 210.858755 137.3713) (xy 210.858755 137.35757) (xy 210.858755 137.34384) (xy 210.858755 137.33011)
			(xy 210.858755 137.31638) (xy 210.858755 137.30264) (xy 210.858755 137.28891) (xy 212.698815 137.28891)
			(xy 212.698815 137.30264) (xy 212.698815 137.31638) (xy 212.698815 137.33011) (xy 212.698815 137.34384)
			(xy 212.698815 137.35757) (xy 212.698815 137.3713) (xy 212.698815 137.38503) (xy 212.698815 137.39877)
			(xy 212.698815 137.4125) (xy 212.698815 137.42623) (xy 212.712545 137.42623) (xy 212.712545 137.43996)
			(xy 212.712545 137.45369) (xy 212.712545 137.46743) (xy 212.712545 137.48116) (xy 212.712545 137.49489)
			(xy 212.712545 137.50862) (xy 212.712545 137.52235) (xy 212.712545 137.53609) (xy 212.712545 137.54982)
			(xy 212.712545 137.56355) (xy 212.712545 137.57728) (xy 212.726275 137.57728) (xy 212.726275 137.59101)
			(xy 212.712545 137.59101) (xy 212.712545 137.60474) (xy 212.726275 137.60474) (xy 212.726275 137.61848)
			(xy 212.726275 137.63221) (xy 212.726275 137.64594) (xy 212.726275 137.65967) (xy 212.726275 137.6734)
			(xy 212.726275 137.68713) (xy 212.726275 137.70087) (xy 212.726275 137.7146) (xy 212.726275 137.72833)
			(xy 212.726275 137.74206) (xy 212.740005 137.74206) (xy 212.740005 137.75579) (xy 212.740005 137.76952)
			(xy 212.740005 137.78326) (xy 212.740005 137.79699) (xy 212.740005 137.81072) (xy 212.740005 137.82445)
			(xy 212.740005 137.83818) (xy 212.740005 137.85191) (xy 212.753735 137.85191) (xy 212.753735 137.86565)
			(xy 212.753735 137.87938) (xy 212.753735 137.89311) (xy 212.753735 137.90684) (xy 212.753735 137.92057)
			(xy 212.753735 137.9343) (xy 212.753735 137.94804) (xy 212.767465 137.94804) (xy 212.767465 137.96177)
			(xy 212.767465 137.9755) (xy 212.767465 137.98923) (xy 212.767465 138.00296) (xy 212.767465 138.0167)
			(xy 212.767465 138.03043) (xy 212.781205 138.03043) (xy 212.781205 138.04416) (xy 212.781205 138.05789)
			(xy 212.781205 138.07162) (xy 212.781205 138.08536) (xy 212.781205 138.09909) (xy 212.794935 138.09909)
			(xy 212.794935 138.11282) (xy 212.794935 138.12655) (xy 212.794935 138.14028) (xy 212.794935 138.15401)
			(xy 212.794935 138.16775) (xy 212.808665 138.16775) (xy 212.808665 138.18148) (xy 212.808665 138.19521)
			(xy 212.808665 138.20894) (xy 212.808665 138.22267) (xy 212.808665 138.2364) (xy 212.822395 138.2364)
			(xy 212.822395 138.25014) (xy 212.822395 138.26387) (xy 212.822395 138.2776) (xy 212.822395 138.29133)
			(xy 212.822395 138.30506) (xy 212.836125 138.30506) (xy 212.836125 138.31879) (xy 212.836125 138.33253)
			(xy 212.836125 138.34626) (xy 212.836125 138.35999) (xy 212.849865 138.35999) (xy 212.849865 138.37372)
			(xy 212.849865 138.38745) (xy 212.849865 138.40118) (xy 212.849865 138.41492) (xy 212.863595 138.41492)
			(xy 212.863595 138.42865) (xy 212.863595 138.44238) (xy 212.863595 138.45611) (xy 212.863595 138.46984)
			(xy 212.877325 138.46984) (xy 212.877325 138.48358) (xy 212.877325 138.49731) (xy 212.877325 138.51104)
			(xy 212.877325 138.52477) (xy 212.891055 138.52477) (xy 212.891055 138.5385) (xy 212.891055 138.55224)
			(xy 212.891055 138.56597) (xy 212.904785 138.56597) (xy 212.904785 138.5797) (xy 212.904785 138.59343)
			(xy 212.904785 138.60716) (xy 212.904785 138.62089) (xy 212.918525 138.62089) (xy 212.918525 138.63463)
			(xy 212.918525 138.64836) (xy 212.918525 138.66209) (xy 212.932255 138.66209) (xy 212.932255 138.67582)
			(xy 212.932255 138.68955) (xy 212.932255 138.70328) (xy 212.945985 138.70328) (xy 212.945985 138.71702)
			(xy 212.945985 138.73075) (xy 212.945985 138.74448) (xy 212.959715 138.74448) (xy 212.959715 138.75821)
			(xy 212.959715 138.77194) (xy 212.959715 138.78567) (xy 212.973445 138.78567) (xy 212.973445 138.79941)
			(xy 212.973445 138.81314) (xy 212.973445 138.82687) (xy 212.987175 138.82687) (xy 212.987175 138.8406)
			(xy 212.987175 138.85433) (xy 212.987175 138.86806) (xy 213.000915 138.86806) (xy 213.000915 138.8818)
			(xy 213.000915 138.89553) (xy 213.000915 138.90926) (xy 213.014645 138.90926) (xy 213.014645 138.92299)
			(xy 213.014645 138.93672) (xy 213.014645 138.95045) (xy 213.028375 138.95045) (xy 213.028375 138.96419)
			(xy 213.028375 138.97792) (xy 213.028375 138.99165) (xy 213.042105 138.99165) (xy 213.042105 139.00538)
			(xy 213.042105 139.01911) (xy 213.055835 139.01911) (xy 213.055835 139.03285) (xy 213.055835 139.04658)
			(xy 213.055835 139.06031) (xy 213.069565 139.06031) (xy 213.069565 139.07404) (xy 213.069565 139.08777)
			(xy 213.083305 139.08777) (xy 213.083305 139.10151) (xy 213.083305 139.11524) (xy 213.083305 139.12897)
			(xy 213.097035 139.12897) (xy 213.097035 139.1427) (xy 213.097035 139.15643) (xy 213.110765 139.15643)
			(xy 213.110765 139.17016) (xy 213.110765 139.1839) (xy 213.110765 139.19763) (xy 213.124495 139.19763)
			(xy 213.124495 139.21136) (xy 213.124495 139.22509) (xy 213.138225 139.22509) (xy 213.138225 139.23882)
			(xy 213.138225 139.25255) (xy 213.151955 139.25255) (xy 213.151955 139.26629) (xy 213.151955 139.28002)
			(xy 213.151955 139.29375) (xy 213.165695 139.29375) (xy 213.165695 139.30748) (xy 213.165695 139.32121)
			(xy 213.179425 139.32121) (xy 213.179425 139.33494) (xy 213.179425 139.34868) (xy 213.193155 139.34868)
			(xy 213.193155 139.36241) (xy 213.193155 139.37614) (xy 213.206885 139.37614) (xy 213.206885 139.38987)
			(xy 213.206885 139.4036) (xy 213.220615 139.4036) (xy 213.220615 139.41733) (xy 213.220615 139.43107)
			(xy 213.234345 139.43107) (xy 213.234345 139.4448) (xy 213.234345 139.45853) (xy 213.248085 139.45853)
			(xy 213.248085 139.47226) (xy 213.248085 139.48599) (xy 213.261815 139.48599) (xy 213.261815 139.49972)
			(xy 213.261815 139.51346) (xy 213.275545 139.51346) (xy 213.275545 139.52719) (xy 213.275545 139.54092)
			(xy 213.289275 139.54092) (xy 213.289275 139.55465) (xy 213.289275 139.56838) (xy 213.303005 139.56838)
			(xy 213.303005 139.58212) (xy 213.303005 139.59585) (xy 213.316735 139.59585) (xy 213.316735 139.60958)
			(xy 213.316735 139.62331) (xy 213.330475 139.62331) (xy 213.330475 139.63704) (xy 213.330475 139.65078)
			(xy 213.344205 139.65078) (xy 213.344205 139.66451) (xy 213.357935 139.66451) (xy 213.357935 139.67824)
			(xy 213.357935 139.69197) (xy 213.371665 139.69197) (xy 213.371665 139.7057) (xy 213.371665 139.71943)
			(xy 213.385395 139.71943) (xy 213.385395 139.73317) (xy 213.385395 139.7469) (xy 213.399135 139.7469)
			(xy 213.399135 139.76063) (xy 213.399135 139.77436) (xy 213.412865 139.77436) (xy 213.412865 139.78809)
			(xy 213.426595 139.78809) (xy 213.426595 139.80182) (xy 213.426595 139.81556) (xy 213.440325 139.81556)
			(xy 213.440325 139.82929) (xy 213.440325 139.84302) (xy 213.454055 139.84302) (xy 213.454055 139.85675)
			(xy 213.454055 139.87048) (xy 213.467795 139.87048) (xy 213.467795 139.88421) (xy 213.481525 139.88421)
			(xy 213.481525 139.89795) (xy 213.481525 139.91168) (xy 213.495255 139.91168) (xy 213.495255 139.92541)
			(xy 213.508985 139.92541) (xy 213.508985 139.93914) (xy 213.508985 139.95287) (xy 213.522715 139.95287)
			(xy 213.522715 139.9666) (xy 213.522715 139.98034) (xy 213.536445 139.98034) (xy 213.536445 139.99407)
			(xy 213.550185 139.99407) (xy 213.550185 140.0078) (xy 213.550185 140.02153) (xy 213.563915 140.02153)
			(xy 213.563915 140.03526) (xy 213.577645 140.03526) (xy 213.577645 140.04899) (xy 213.577645 140.06273)
			(xy 213.591375 140.06273) (xy 213.591375 140.07646) (xy 213.605105 140.07646) (xy 213.605105 140.09019)
			(xy 213.605105 140.10392) (xy 213.618835 140.10392) (xy 213.618835 140.11765) (xy 213.632575 140.11765)
			(xy 213.632575 140.13139) (xy 213.632575 140.14512) (xy 213.646305 140.14512) (xy 213.646305 140.15885)
			(xy 213.660035 140.15885) (xy 213.660035 140.17258) (xy 213.673765 140.17258) (xy 213.673765 140.18631)
			(xy 213.673765 140.20005) (xy 213.687495 140.20005) (xy 213.687495 140.21378) (xy 213.701225 140.21378)
			(xy 213.701225 140.22751) (xy 213.701225 140.24124) (xy 213.714965 140.24124) (xy 213.714965 140.25497)
			(xy 213.728695 140.25497) (xy 213.728695 140.2687) (xy 213.742425 140.2687) (xy 213.742425 140.28244)
			(xy 213.742425 140.29617) (xy 213.756155 140.29617) (xy 213.756155 140.3099) (xy 213.769885 140.3099)
			(xy 213.769885 140.32363) (xy 213.783615 140.32363) (xy 213.783615 140.33736) (xy 213.783615 140.35109)
			(xy 213.797355 140.35109) (xy 213.797355 140.36483) (xy 213.811085 140.36483) (xy 213.811085 140.37856)
			(xy 213.824815 140.37856) (xy 213.824815 140.39229) (xy 213.838545 140.39229) (xy 213.838545 140.40602)
			(xy 213.838545 140.41975) (xy 213.852275 140.41975) (xy 213.852275 140.43348) (xy 213.866005 140.43348)
			(xy 213.866005 140.44722) (xy 213.879745 140.44722) (xy 213.879745 140.46095) (xy 213.893475 140.46095)
			(xy 213.893475 140.47468) (xy 213.893475 140.48841) (xy 213.907205 140.48841) (xy 213.907205 140.50214)
			(xy 213.920935 140.50214) (xy 213.920935 140.51587) (xy 213.934665 140.51587) (xy 213.934665 140.5296)
			(xy 213.948405 140.5296) (xy 213.948405 140.54334) (xy 213.948405 140.55707) (xy 213.962135 140.55707)
			(xy 213.962135 140.5708) (xy 213.975865 140.5708) (xy 213.975865 140.58453) (xy 213.989595 140.58453)
			(xy 213.989595 140.59827) (xy 214.003325 140.59827) (xy 214.003325 140.612) (xy 214.017065 140.612)
			(xy 214.017065 140.62573) (xy 214.030795 140.62573) (xy 214.030795 140.63946) (xy 214.044525 140.63946)
			(xy 214.044525 140.65319) (xy 214.044525 140.66693) (xy 214.058255 140.66693) (xy 214.058255 140.68066)
			(xy 214.071985 140.68066) (xy 214.071985 140.69439) (xy 214.085715 140.69439) (xy 214.085715 140.70812)
			(xy 214.099455 140.70812) (xy 214.099455 140.72185) (xy 214.113185 140.72185) (xy 214.113185 140.73558)
			(xy 214.126915 140.73558) (xy 214.126915 140.74931) (xy 214.140645 140.74931) (xy 214.140645 140.76305)
			(xy 214.154375 140.76305) (xy 214.154375 140.77678) (xy 214.168105 140.77678) (xy 214.168105 140.79051)
			(xy 214.181845 140.79051) (xy 214.181845 140.80424) (xy 214.195575 140.80424) (xy 214.195575 140.81797)
			(xy 214.209305 140.81797) (xy 214.209305 140.8317) (xy 214.223035 140.8317) (xy 214.223035 140.84544)
			(xy 214.236765 140.84544) (xy 214.236765 140.85917) (xy 214.250495 140.85917) (xy 214.250495 140.8729)
			(xy 214.264235 140.8729) (xy 214.264235 140.88663) (xy 214.277965 140.88663) (xy 214.277965 140.90036)
			(xy 214.291695 140.90036) (xy 214.291695 140.91409) (xy 214.305425 140.91409) (xy 214.305425 140.92783)
			(xy 214.319155 140.92783) (xy 214.319155 140.94156) (xy 214.332885 140.94156) (xy 214.332885 140.95529)
			(xy 214.346625 140.95529) (xy 214.346625 140.96902) (xy 214.360355 140.96902) (xy 214.360355 140.98275)
			(xy 214.374085 140.98275) (xy 214.374085 140.99648) (xy 214.387815 140.99648) (xy 214.387815 141.01022)
			(xy 214.401545 141.01022) (xy 214.401545 141.02395) (xy 214.415275 141.02395) (xy 214.415275 141.03768)
			(xy 214.429015 141.03768) (xy 214.429015 141.05141) (xy 214.442745 141.05141) (xy 214.442745 141.06514)
			(xy 214.456475 141.06514) (xy 214.456475 141.07888) (xy 214.483935 141.07888) (xy 214.483935 141.09261)
			(xy 214.497675 141.09261) (xy 214.497675 141.10634) (xy 214.511405 141.10634) (xy 214.511405 141.12007)
			(xy 214.525135 141.12007) (xy 214.525135 141.1338) (xy 214.538865 141.1338) (xy 214.538865 141.14754)
			(xy 214.552595 141.14754) (xy 214.552595 141.16127) (xy 214.566335 141.16127) (xy 214.566335 141.175)
			(xy 214.593795 141.175) (xy 214.593795 141.18873) (xy 214.607525 141.18873) (xy 214.607525 141.20246)
			(xy 214.621255 141.20246) (xy 214.621255 141.21619) (xy 214.634985 141.21619) (xy 214.634985 141.22993)
			(xy 214.648725 141.22993) (xy 214.648725 141.24366) (xy 214.676185 141.24366) (xy 214.676185 141.25739)
			(xy 214.689915 141.25739) (xy 214.689915 141.27112) (xy 214.703645 141.27112) (xy 214.703645 141.28485)
			(xy 214.717375 141.28485) (xy 214.717375 141.29858) (xy 214.744845 141.29858) (xy 214.744845 141.31232)
			(xy 214.758575 141.31232) (xy 214.758575 141.32605) (xy 214.772305 141.32605) (xy 214.772305 141.33978)
			(xy 214.799765 141.33978) (xy 214.799765 141.35351) (xy 214.813505 141.35351) (xy 214.813505 141.36724)
			(xy 214.827235 141.36724) (xy 214.827235 141.38097) (xy 214.854695 141.38097) (xy 214.854695 141.39471)
			(xy 214.868425 141.39471) (xy 214.868425 141.40844) (xy 214.882155 141.40844) (xy 214.882155 141.42217)
			(xy 214.909625 141.42217) (xy 214.909625 141.4359) (xy 214.923355 141.4359) (xy 214.923355 141.44963)
			(xy 214.950815 141.44963) (xy 214.950815 141.46336) (xy 214.964555 141.46336) (xy 214.964555 141.4771)
			(xy 214.978285 141.4771) (xy 214.978285 141.49083) (xy 215.005745 141.49083) (xy 215.005745 141.50456)
			(xy 215.019475 141.50456) (xy 215.019475 141.51829) (xy 215.046945 141.51829) (xy 215.046945 141.53202)
			(xy 215.060675 141.53202) (xy 215.060675 141.54575) (xy 215.088135 141.54575) (xy 215.088135 141.55949)
			(xy 215.101865 141.55949) (xy 215.101865 141.57322) (xy 215.129335 141.57322) (xy 215.129335 141.58695)
			(xy 215.143065 141.58695) (xy 215.143065 141.60068) (xy 215.170525 141.60068) (xy 215.170525 141.61441)
			(xy 215.197995 141.61441) (xy 215.197995 141.62815) (xy 215.211725 141.62815) (xy 215.211725 141.64188)
			(xy 215.239185 141.64188) (xy 215.239185 141.65561) (xy 215.252915 141.65561) (xy 215.252915 141.66934)
			(xy 215.280385 141.66934) (xy 215.280385 141.68307) (xy 215.307845 141.68307) (xy 215.307845 141.69681)
			(xy 215.321575 141.69681) (xy 215.321575 141.71054) (xy 215.349035 141.71054) (xy 215.349035 141.72427)
			(xy 215.376505 141.72427) (xy 215.376505 141.738) (xy 215.403965 141.738) (xy 215.403965 141.75173)
			(xy 215.417695 141.75173) (xy 215.417695 141.76546) (xy 215.445165 141.76546) (xy 215.445165 141.7792)
			(xy 215.472625 141.7792) (xy 215.472625 141.79293) (xy 215.500085 141.79293) (xy 215.500085 141.80666)
			(xy 215.527555 141.80666) (xy 215.527555 141.82039) (xy 215.555015 141.82039) (xy 215.555015 141.83412)
			(xy 215.582485 141.83412) (xy 215.582485 141.84785) (xy 215.609945 141.84785) (xy 215.609945 141.86159)
			(xy 215.637405 141.86159) (xy 215.637405 141.87532) (xy 215.664875 141.87532) (xy 215.664875 141.88905)
			(xy 215.692335 141.88905) (xy 215.692335 141.90278) (xy 215.719795 141.90278) (xy 215.719795 141.91651)
			(xy 215.747265 141.91651) (xy 215.747265 141.93024) (xy 215.774725 141.93024) (xy 215.774725 141.94398)
			(xy 215.802185 141.94398) (xy 215.802185 141.95771) (xy 215.829655 141.95771) (xy 215.829655 141.97144)
			(xy 215.870845 141.97144) (xy 215.870845 141.98517) (xy 215.898305 141.98517) (xy 215.898305 141.9989)
			(xy 215.925775 141.9989) (xy 215.925775 142.01263) (xy 215.966965 142.01263) (xy 215.966965 142.02637)
			(xy 215.994435 142.02637) (xy 215.994435 142.0401) (xy 216.035625 142.0401) (xy 216.035625 142.05383)
			(xy 216.063095 142.05383) (xy 216.063095 142.06756) (xy 216.104285 142.06756) (xy 216.104285 142.08129)
			(xy 216.131755 142.08129) (xy 216.131755 142.09502) (xy 216.172945 142.09502) (xy 216.172945 142.10876)
			(xy 216.214145 142.10876) (xy 216.214145 142.12249) (xy 216.255335 142.12249) (xy 216.255335 142.13622)
			(xy 216.282795 142.13622) (xy 216.282795 142.14995) (xy 216.323995 142.14995) (xy 216.323995 142.16368)
			(xy 216.365185 142.16368) (xy 216.365185 142.17742) (xy 216.420115 142.17742) (xy 216.420115 142.19115)
			(xy 216.461315 142.19115) (xy 216.461315 142.20488) (xy 216.502505 142.20488) (xy 216.502505 142.21861)
			(xy 216.557435 142.21861) (xy 216.557435 142.23234) (xy 216.598625 142.23234) (xy 216.598625 142.24608)
			(xy 216.653555 142.24608) (xy 216.653555 142.25981) (xy 216.708485 142.25981) (xy 216.708485 142.27354)
			(xy 216.763415 142.27354) (xy 216.763415 142.28727) (xy 216.818335 142.28727) (xy 216.818335 142.301)
			(xy 216.886995 142.301) (xy 216.886995 142.31473) (xy 216.941925 142.31473) (xy 216.941925 142.32847)
			(xy 217.010585 142.32847) (xy 217.010585 142.3422) (xy 217.092975 142.3422) (xy 217.092975 142.35593)
			(xy 217.175365 142.35593) (xy 217.175365 142.36966) (xy 217.271485 142.36966) (xy 217.271485 142.38339)
			(xy 217.367605 142.38339) (xy 217.367605 142.39712) (xy 217.504925 142.39712) (xy 217.504925 142.41086)
			(xy 217.669705 142.41086) (xy 217.669705 142.42459) (xy 218.328835 142.42459) (xy 218.328835 142.41086)
			(xy 218.507345 142.41086) (xy 218.507345 142.39712) (xy 218.630925 142.39712) (xy 218.630925 142.38339)
			(xy 218.740785 142.38339) (xy 218.740785 142.36966) (xy 218.836905 142.36966) (xy 218.836905 142.35593)
			(xy 218.919295 142.35593) (xy 218.919295 142.3422) (xy 218.987955 142.3422) (xy 218.987955 142.32847)
			(xy 219.070345 142.32847) (xy 219.070345 142.31473) (xy 219.125265 142.31473) (xy 219.125265 142.301)
			(xy 219.180195 142.301) (xy 219.180195 142.28727) (xy 219.248855 142.28727) (xy 219.248855 142.27354)
			(xy 219.303785 142.27354) (xy 219.303785 142.25981) (xy 219.358715 142.25981) (xy 219.358715 142.24608)
			(xy 219.413635 142.24608) (xy 219.413635 142.23234) (xy 219.454835 142.23234) (xy 219.454835 142.21861)
			(xy 219.509755 142.21861) (xy 219.509755 142.20488) (xy 219.550955 142.20488) (xy 219.550955 142.19115)
			(xy 219.592145 142.19115) (xy 219.592145 142.17742) (xy 219.633345 142.17742) (xy 219.633345 142.16368)
			(xy 219.674545 142.16368) (xy 219.674545 142.14995) (xy 219.715735 142.14995) (xy 219.715735 142.13622)
			(xy 219.756935 142.13622) (xy 219.756935 142.12249) (xy 219.798125 142.12249) (xy 219.798125 142.10876)
			(xy 219.839325 142.10876) (xy 219.839325 142.09502) (xy 219.880515 142.09502) (xy 219.880515 142.08129)
			(xy 219.907985 142.08129) (xy 219.907985 142.06756) (xy 219.949175 142.06756) (xy 219.949175 142.05383)
			(xy 219.976635 142.05383) (xy 219.976635 142.0401) (xy 220.017835 142.0401) (xy 220.017835 142.02637)
			(xy 220.045295 142.02637) (xy 220.045295 142.01263) (xy 220.086495 142.01263) (xy 220.086495 141.9989)
			(xy 220.113955 141.9989) (xy 220.113955 141.98517) (xy 220.141415 141.98517) (xy 220.141415 141.97144)
			(xy 220.182615 141.97144) (xy 220.182615 141.95771) (xy 220.210075 141.95771) (xy 220.210075 141.94398)
			(xy 220.237545 141.94398) (xy 220.237545 141.93024) (xy 220.265005 141.93024) (xy 220.265005 141.91651)
			(xy 220.292475 141.91651) (xy 220.292475 141.90278) (xy 220.319935 141.90278) (xy 220.319935 141.88905)
			(xy 220.347395 141.88905) (xy 220.347395 141.87532) (xy 220.374865 141.87532) (xy 220.374865 141.86159)
			(xy 220.402325 141.86159) (xy 220.402325 141.84785) (xy 220.429785 141.84785) (xy 220.429785 141.83412)
			(xy 220.457255 141.83412) (xy 220.457255 141.82039) (xy 220.484715 141.82039) (xy 220.484715 141.80666)
			(xy 220.512175 141.80666) (xy 220.512175 141.79293) (xy 220.539645 141.79293) (xy 220.539645 141.7792)
			(xy 220.567105 141.7792) (xy 220.567105 141.76546) (xy 220.580835 141.76546) (xy 220.580835 141.75173)
			(xy 220.608295 141.75173) (xy 220.608295 141.738) (xy 220.635765 141.738) (xy 220.635765 141.72427)
			(xy 220.663225 141.72427) (xy 220.663225 141.71054) (xy 220.676955 141.71054) (xy 220.676955 141.69681)
			(xy 220.704425 141.69681) (xy 220.704425 141.68307) (xy 220.731885 141.68307) (xy 220.731885 141.66934)
			(xy 220.745615 141.66934) (xy 220.745615 141.65561) (xy 220.773085 141.65561) (xy 220.773085 141.64188)
			(xy 220.800545 141.64188) (xy 220.800545 141.62815) (xy 220.814275 141.62815) (xy 220.814275 141.61441)
			(xy 220.841745 141.61441) (xy 220.841745 141.60068) (xy 220.855475 141.60068) (xy 220.855475 141.58695)
			(xy 220.882935 141.58695) (xy 220.882935 141.57322) (xy 220.910395 141.57322) (xy 220.910395 141.55949)
			(xy 220.924135 141.55949) (xy 220.924135 141.54575) (xy 220.951595 141.54575) (xy 220.951595 141.53202)
			(xy 220.965325 141.53202) (xy 220.965325 141.51829) (xy 220.992785 141.51829) (xy 220.992785 141.50456)
			(xy 221.006525 141.50456) (xy 221.006525 141.49083) (xy 221.020255 141.49083) (xy 221.020255 141.4771)
			(xy 221.047715 141.4771) (xy 221.047715 141.46336) (xy 221.061445 141.46336) (xy 221.061445 141.44963)
			(xy 221.088915 141.44963) (xy 221.088915 141.4359) (xy 221.102645 141.4359) (xy 221.102645 141.42217)
			(xy 221.130105 141.42217) (xy 221.130105 141.40844) (xy 221.143835 141.40844) (xy 221.143835 141.39471)
			(xy 221.157565 141.39471) (xy 221.157565 141.38097) (xy 221.185035 141.38097) (xy 221.185035 141.36724)
			(xy 221.198765 141.36724) (xy 221.198765 141.35351) (xy 221.212495 141.35351) (xy 221.212495 141.33978)
			(xy 221.239955 141.33978) (xy 221.239955 141.32605) (xy 221.253695 141.32605) (xy 221.253695 141.31232)
			(xy 221.267425 141.31232) (xy 221.267425 141.29858) (xy 221.281155 141.29858) (xy 221.281155 141.28485)
			(xy 221.308615 141.28485) (xy 221.308615 141.27112) (xy 221.322355 141.27112) (xy 221.322355 141.25739)
			(xy 221.336085 141.25739) (xy 221.336085 141.24366) (xy 221.349815 141.24366) (xy 221.349815 141.22993)
			(xy 221.377275 141.22993) (xy 221.377275 141.21619) (xy 221.391015 141.21619) (xy 221.391015 141.20246)
			(xy 221.404745 141.20246) (xy 221.404745 141.18873) (xy 221.418475 141.18873) (xy 221.418475 141.175)
			(xy 221.432205 141.175) (xy 221.432205 141.16127) (xy 221.459665 141.16127) (xy 221.459665 141.14754)
			(xy 221.473405 141.14754) (xy 221.473405 141.1338) (xy 221.487135 141.1338) (xy 221.487135 141.12007)
			(xy 221.500865 141.12007) (xy 221.500865 141.10634) (xy 221.514595 141.10634) (xy 221.514595 141.09261)
			(xy 221.528325 141.09261) (xy 221.528325 141.07888) (xy 221.542055 141.07888) (xy 221.542055 141.06514)
			(xy 221.569525 141.06514) (xy 221.569525 141.05141) (xy 221.583255 141.05141) (xy 221.583255 141.03768)
			(xy 221.596985 141.03768) (xy 221.596985 141.02395) (xy 221.610715 141.02395) (xy 221.610715 141.01022)
			(xy 221.624445 141.01022) (xy 221.624445 140.99648) (xy 221.638185 140.99648) (xy 221.638185 140.98275)
			(xy 221.651915 140.98275) (xy 221.651915 140.96902) (xy 221.665645 140.96902) (xy 221.665645 140.95529)
			(xy 221.679375 140.95529) (xy 221.679375 140.94156) (xy 221.693105 140.94156) (xy 221.693105 140.92783)
			(xy 221.706835 140.92783) (xy 221.706835 140.91409) (xy 221.720575 140.91409) (xy 221.720575 140.90036)
			(xy 221.734305 140.90036) (xy 221.734305 140.88663) (xy 221.748035 140.88663) (xy 221.748035 140.8729)
			(xy 221.761765 140.8729) (xy 221.761765 140.85917) (xy 221.775495 140.85917) (xy 221.775495 140.84544)
			(xy 221.789235 140.84544) (xy 221.789235 140.8317) (xy 221.802965 140.8317) (xy 221.802965 140.81797)
			(xy 221.816695 140.81797) (xy 221.816695 140.80424) (xy 221.830425 140.80424) (xy 221.830425 140.79051)
			(xy 221.844155 140.79051) (xy 221.844155 140.77678) (xy 221.857895 140.77678) (xy 221.857895 140.76305)
			(xy 221.871625 140.76305) (xy 221.871625 140.74931) (xy 221.885355 140.74931) (xy 221.885355 140.73558)
			(xy 221.899085 140.73558) (xy 221.899085 140.72185) (xy 221.912815 140.72185) (xy 221.912815 140.70812)
			(xy 221.926545 140.70812) (xy 221.926545 140.69439) (xy 221.940285 140.69439) (xy 221.940285 140.68066)
			(xy 221.954015 140.68066) (xy 221.954015 140.66693) (xy 221.954015 140.65319) (xy 221.967745 140.65319)
			(xy 221.967745 140.63946) (xy 221.981475 140.63946) (xy 221.981475 140.62573) (xy 221.995205 140.62573)
			(xy 221.995205 140.612) (xy 222.008935 140.612) (xy 222.008935 140.59827) (xy 222.022675 140.59827)
			(xy 222.022675 140.58453) (xy 222.036405 140.58453) (xy 222.036405 140.5708) (xy 222.050135 140.5708)
			(xy 222.050135 140.55707) (xy 222.050135 140.54334) (xy 222.063865 140.54334) (xy 222.063865 140.5296)
			(xy 221.844155 140.5296) (xy 221.844155 140.54334) (xy 221.830425 140.54334) (xy 221.830425 140.55707)
			(xy 221.816695 140.55707) (xy 221.816695 140.5708) (xy 221.816695 140.58453) (xy 221.802965 140.58453)
			(xy 221.802965 140.59827) (xy 221.789235 140.59827) (xy 221.789235 140.612) (xy 221.775495 140.612)
			(xy 221.775495 140.62573) (xy 221.761765 140.62573) (xy 221.761765 140.63946) (xy 221.748035 140.63946)
			(xy 221.748035 140.65319) (xy 221.734305 140.65319) (xy 221.734305 140.66693) (xy 221.720575 140.66693)
			(xy 221.720575 140.68066) (xy 221.706835 140.68066) (xy 221.706835 140.69439) (xy 221.693105 140.69439)
			(xy 221.693105 140.70812) (xy 221.679375 140.70812) (xy 221.679375 140.72185) (xy 221.665645 140.72185)
			(xy 221.665645 140.73558) (xy 221.651915 140.73558) (xy 221.651915 140.74931) (xy 221.638185 140.74931)
			(xy 221.638185 140.76305) (xy 221.624445 140.76305) (xy 221.624445 140.77678) (xy 221.610715 140.77678)
			(xy 221.610715 140.79051) (xy 221.596985 140.79051) (xy 221.596985 140.80424) (xy 221.583255 140.80424)
			(xy 221.583255 140.81797) (xy 221.569525 140.81797) (xy 221.569525 140.8317) (xy 221.555795 140.8317)
			(xy 221.555795 140.84544) (xy 221.542055 140.84544) (xy 221.542055 140.85917) (xy 221.528325 140.85917)
			(xy 221.528325 140.8729) (xy 221.514595 140.8729) (xy 221.514595 140.88663) (xy 221.500865 140.88663)
			(xy 221.500865 140.90036) (xy 221.487135 140.90036) (xy 221.487135 140.91409) (xy 221.473405 140.91409)
			(xy 221.473405 140.92783) (xy 221.445935 140.92783) (xy 221.445935 140.94156) (xy 221.432205 140.94156)
			(xy 221.432205 140.95529) (xy 221.418475 140.95529) (xy 221.418475 140.96902) (xy 221.404745 140.96902)
			(xy 221.404745 140.98275) (xy 221.391015 140.98275) (xy 221.391015 140.99648) (xy 221.377275 140.99648)
			(xy 221.377275 141.01022) (xy 221.363545 141.01022) (xy 221.363545 141.02395) (xy 221.336085 141.02395)
			(xy 221.336085 141.03768) (xy 221.322355 141.03768) (xy 221.322355 141.05141) (xy 221.308615 141.05141)
			(xy 221.308615 141.06514) (xy 221.294885 141.06514) (xy 221.294885 141.07888) (xy 221.281155 141.07888)
			(xy 221.281155 141.09261) (xy 221.253695 141.09261) (xy 221.253695 141.10634) (xy 221.239955 141.10634)
			(xy 221.239955 141.12007) (xy 221.226225 141.12007) (xy 221.226225 141.1338) (xy 221.212495 141.1338)
			(xy 221.212495 141.14754) (xy 221.185035 141.14754) (xy 221.185035 141.16127) (xy 221.171305 141.16127)
			(xy 221.171305 141.175) (xy 221.157565 141.175) (xy 221.157565 141.18873) (xy 221.143835 141.18873)
			(xy 221.143835 141.20246) (xy 221.116375 141.20246) (xy 221.116375 141.21619) (xy 221.102645 141.21619)
			(xy 221.102645 141.22993) (xy 221.088915 141.22993) (xy 221.088915 141.24366) (xy 221.061445 141.24366)
			(xy 221.061445 141.25739) (xy 221.047715 141.25739) (xy 221.047715 141.27112) (xy 221.033985 141.27112)
			(xy 221.033985 141.28485) (xy 221.006525 141.28485) (xy 221.006525 141.29858) (xy 220.992785 141.29858)
			(xy 220.992785 141.31232) (xy 220.965325 141.31232) (xy 220.965325 141.32605) (xy 220.951595 141.32605)
			(xy 220.951595 141.33978) (xy 220.937865 141.33978) (xy 220.937865 141.35351) (xy 220.910395 141.35351)
			(xy 220.910395 141.36724) (xy 220.896665 141.36724) (xy 220.896665 141.38097) (xy 220.869205 141.38097)
			(xy 220.869205 141.39471) (xy 220.855475 141.39471) (xy 220.855475 141.40844) (xy 220.828005 141.40844)
			(xy 220.828005 141.42217) (xy 220.814275 141.42217) (xy 220.814275 141.4359) (xy 220.786815 141.4359)
			(xy 220.786815 141.44963) (xy 220.773085 141.44963) (xy 220.773085 141.46336) (xy 220.745615 141.46336)
			(xy 220.745615 141.4771) (xy 220.718155 141.4771) (xy 220.718155 141.49083) (xy 220.704425 141.49083)
			(xy 220.704425 141.50456) (xy 220.676955 141.50456) (xy 220.676955 141.51829) (xy 220.649495 141.51829)
			(xy 220.649495 141.53202) (xy 220.635765 141.53202) (xy 220.635765 141.54575) (xy 220.608295 141.54575)
			(xy 220.608295 141.55949) (xy 220.580835 141.55949) (xy 220.580835 141.57322) (xy 220.567105 141.57322)
			(xy 220.567105 141.58695) (xy 220.539645 141.58695) (xy 220.539645 141.60068) (xy 220.512175 141.60068)
			(xy 220.512175 141.61441) (xy 220.484715 141.61441) (xy 220.484715 141.62815) (xy 220.470985 141.62815)
			(xy 220.470985 141.64188) (xy 220.443515 141.64188) (xy 220.443515 141.65561) (xy 220.416055 141.65561)
			(xy 220.416055 141.66934) (xy 220.388595 141.66934) (xy 220.388595 141.68307) (xy 220.361125 141.68307)
			(xy 220.361125 141.69681) (xy 220.333665 141.69681) (xy 220.333665 141.71054) (xy 220.306205 141.71054)
			(xy 220.306205 141.72427) (xy 220.278735 141.72427) (xy 220.278735 141.738) (xy 220.251275 141.738)
			(xy 220.251275 141.75173) (xy 220.223815 141.75173) (xy 220.223815 141.76546) (xy 220.196345 141.76546)
			(xy 220.196345 141.7792) (xy 220.168885 141.7792) (xy 220.168885 141.79293) (xy 220.141415 141.79293)
			(xy 220.141415 141.80666) (xy 220.113955 141.80666) (xy 220.113955 141.82039) (xy 220.072765 141.82039)
			(xy 220.072765 141.83412) (xy 220.045295 141.83412) (xy 220.045295 141.84785) (xy 220.004105 141.84785)
			(xy 220.004105 141.86159) (xy 219.976635 141.86159) (xy 219.976635 141.87532) (xy 219.949175 141.87532)
			(xy 219.949175 141.88905) (xy 219.907985 141.88905) (xy 219.907985 141.90278) (xy 219.880515 141.90278)
			(xy 219.880515 141.91651) (xy 219.839325 141.91651) (xy 219.839325 141.93024) (xy 219.798125 141.93024)
			(xy 219.798125 141.94398) (xy 219.770665 141.94398) (xy 219.770665 141.95771) (xy 219.729465 141.95771)
			(xy 219.729465 141.97144) (xy 219.688275 141.97144) (xy 219.688275 141.98517) (xy 219.647075 141.98517)
			(xy 219.647075 141.9989) (xy 219.605885 141.9989) (xy 219.605885 142.01263) (xy 219.564685 142.01263)
			(xy 219.564685 142.02637) (xy 219.523495 142.02637) (xy 219.523495 142.0401) (xy 219.482295 142.0401)
			(xy 219.482295 142.05383) (xy 219.427365 142.05383) (xy 219.427365 142.06756) (xy 219.386175 142.06756)
			(xy 219.386175 142.08129) (xy 219.331245 142.08129) (xy 219.331245 142.09502) (xy 219.276325 142.09502)
			(xy 219.276325 142.10876) (xy 219.221395 142.10876) (xy 219.221395 142.12249) (xy 219.166465 142.12249)
			(xy 219.166465 142.13622) (xy 219.097805 142.13622) (xy 219.097805 142.14995) (xy 219.042875 142.14995)
			(xy 219.042875 142.16368) (xy 218.974225 142.16368) (xy 218.974225 142.17742) (xy 218.891835 142.17742)
			(xy 218.891835 142.19115) (xy 218.809445 142.19115) (xy 218.809445 142.20488) (xy 218.713315 142.20488)
			(xy 218.713315 142.21861) (xy 218.630925 142.21861) (xy 218.630925 142.23234) (xy 218.466145 142.23234)
			(xy 218.466145 142.24608) (xy 218.315095 142.24608) (xy 218.315095 142.25981) (xy 218.301365 142.25981)
			(xy 218.301365 142.24608) (xy 218.273905 142.24608) (xy 218.273905 142.25981) (xy 217.738365 142.25981)
			(xy 217.738365 142.24608) (xy 217.532385 142.24608) (xy 217.532385 142.23234) (xy 217.408805 142.23234)
			(xy 217.408805 142.21861) (xy 217.298945 142.21861) (xy 217.298945 142.20488) (xy 217.202825 142.20488)
			(xy 217.202825 142.19115) (xy 217.120435 142.19115) (xy 217.120435 142.17742) (xy 217.038045 142.17742)
			(xy 217.038045 142.16368) (xy 216.969385 142.16368) (xy 216.969385 142.14995) (xy 216.900725 142.14995)
			(xy 216.900725 142.13622) (xy 216.845805 142.13622) (xy 216.845805 142.12249) (xy 216.790875 142.12249)
			(xy 216.790875 142.10876) (xy 216.735945 142.10876) (xy 216.735945 142.09502) (xy 216.681025 142.09502)
			(xy 216.681025 142.08129) (xy 216.626095 142.08129) (xy 216.626095 142.06756) (xy 216.584895 142.06756)
			(xy 216.584895 142.05383) (xy 216.529965 142.05383) (xy 216.529965 142.0401) (xy 216.488775 142.0401)
			(xy 216.488775 142.02637) (xy 216.447575 142.02637) (xy 216.447575 142.01263) (xy 216.406385 142.01263)
			(xy 216.406385 141.9989) (xy 216.365185 141.9989) (xy 216.365185 141.98517) (xy 216.323995 141.98517)
			(xy 216.323995 141.97144) (xy 216.282795 141.97144) (xy 216.282795 141.95771) (xy 216.241605 141.95771)
			(xy 216.241605 141.94398) (xy 216.200405 141.94398) (xy 216.200405 141.93024) (xy 216.172945 141.93024)
			(xy 216.172945 141.91651) (xy 216.131755 141.91651) (xy 216.131755 141.90278) (xy 216.104285 141.90278)
			(xy 216.104285 141.88905) (xy 216.063095 141.88905) (xy 216.063095 141.87532) (xy 216.035625 141.87532)
			(xy 216.035625 141.86159) (xy 215.994435 141.86159) (xy 215.994435 141.84785) (xy 215.966965 141.84785)
			(xy 215.966965 141.83412) (xy 215.939505 141.83412) (xy 215.939505 141.82039) (xy 215.912045 141.82039)
			(xy 215.912045 141.80666) (xy 215.870845 141.80666) (xy 215.870845 141.79293) (xy 215.843385 141.79293)
			(xy 215.843385 141.7792) (xy 215.815915 141.7792) (xy 215.815915 141.76546) (xy 215.788455 141.76546)
			(xy 215.788455 141.75173) (xy 215.760995 141.75173) (xy 215.760995 141.738) (xy 215.733525 141.738)
			(xy 215.733525 141.72427) (xy 215.706065 141.72427) (xy 215.706065 141.71054) (xy 215.678605 141.71054)
			(xy 215.678605 141.69681) (xy 215.651135 141.69681) (xy 215.651135 141.68307) (xy 215.623675 141.68307)
			(xy 215.623675 141.66934) (xy 215.596215 141.66934) (xy 215.596215 141.65561) (xy 215.568745 141.65561)
			(xy 215.568745 141.64188) (xy 215.541285 141.64188) (xy 215.541285 141.62815) (xy 215.527555 141.62815)
			(xy 215.527555 141.61441) (xy 215.500085 141.61441) (xy 215.500085 141.60068) (xy 215.472625 141.60068)
			(xy 215.472625 141.58695) (xy 215.445165 141.58695) (xy 215.445165 141.57322) (xy 215.417695 141.57322)
			(xy 215.417695 141.55949) (xy 215.403965 141.55949) (xy 215.403965 141.54575) (xy 215.376505 141.54575)
			(xy 215.376505 141.53202) (xy 215.349035 141.53202) (xy 215.349035 141.51829) (xy 215.335305 141.51829)
			(xy 215.335305 141.50456) (xy 215.307845 141.50456) (xy 215.307845 141.49083) (xy 215.294115 141.49083)
			(xy 215.294115 141.4771) (xy 215.266645 141.4771) (xy 215.266645 141.46336) (xy 215.239185 141.46336)
			(xy 215.239185 141.44963) (xy 215.225455 141.44963) (xy 215.225455 141.4359) (xy 215.197995 141.4359)
			(xy 215.197995 141.42217) (xy 215.184255 141.42217) (xy 215.184255 141.40844) (xy 215.156795 141.40844)
			(xy 215.156795 141.39471) (xy 215.143065 141.39471) (xy 215.143065 141.38097) (xy 215.115605 141.38097)
			(xy 215.115605 141.36724) (xy 215.101865 141.36724) (xy 215.101865 141.35351) (xy 215.074405 141.35351)
			(xy 215.074405 141.33978) (xy 215.060675 141.33978) (xy 215.060675 141.32605) (xy 215.033215 141.32605)
			(xy 215.033215 141.31232) (xy 215.019475 141.31232) (xy 215.019475 141.29858) (xy 215.005745 141.29858)
			(xy 215.005745 141.28485) (xy 214.978285 141.28485) (xy 214.978285 141.27112) (xy 214.964555 141.27112)
			(xy 214.964555 141.25739) (xy 214.950815 141.25739) (xy 214.950815 141.24366) (xy 214.923355 141.24366)
			(xy 214.923355 141.22993) (xy 214.909625 141.22993) (xy 214.909625 141.21619) (xy 214.895895 141.21619)
			(xy 214.895895 141.20246) (xy 214.868425 141.20246) (xy 214.868425 141.18873) (xy 214.854695 141.18873)
			(xy 214.854695 141.175) (xy 214.840965 141.175) (xy 214.840965 141.16127) (xy 214.813505 141.16127)
			(xy 214.813505 141.14754) (xy 214.799765 141.14754) (xy 214.799765 141.1338) (xy 214.786035 141.1338)
			(xy 214.786035 141.12007) (xy 214.772305 141.12007) (xy 214.772305 141.10634) (xy 214.744845 141.10634)
			(xy 214.744845 141.09261) (xy 214.731115 141.09261) (xy 214.731115 141.07888) (xy 214.717375 141.07888)
			(xy 214.717375 141.06514) (xy 214.703645 141.06514) (xy 214.703645 141.05141) (xy 214.689915 141.05141)
			(xy 214.689915 141.03768) (xy 214.662455 141.03768) (xy 214.662455 141.02395) (xy 214.648725 141.02395)
			(xy 214.648725 141.01022) (xy 214.634985 141.01022) (xy 214.634985 140.99648) (xy 214.621255 140.99648)
			(xy 214.621255 140.98275) (xy 214.607525 140.98275) (xy 214.607525 140.96902) (xy 214.593795 140.96902)
			(xy 214.593795 140.95529) (xy 214.580065 140.95529) (xy 214.580065 140.94156) (xy 214.552595 140.94156)
			(xy 214.552595 140.92783) (xy 214.538865 140.92783) (xy 214.538865 140.91409) (xy 214.525135 140.91409)
			(xy 214.525135 140.90036) (xy 214.511405 140.90036) (xy 214.511405 140.88663) (xy 214.497675 140.88663)
			(xy 214.497675 140.8729) (xy 214.483935 140.8729) (xy 214.483935 140.85917) (xy 214.470205 140.85917)
			(xy 214.470205 140.84544) (xy 214.456475 140.84544) (xy 214.456475 140.8317) (xy 214.442745 140.8317)
			(xy 214.442745 140.81797) (xy 214.429015 140.81797) (xy 214.429015 140.80424) (xy 214.415275 140.80424)
			(xy 214.415275 140.79051) (xy 214.401545 140.79051) (xy 214.401545 140.77678) (xy 214.387815 140.77678)
			(xy 214.387815 140.76305) (xy 214.374085 140.76305) (xy 214.374085 140.74931) (xy 214.360355 140.74931)
			(xy 214.360355 140.73558) (xy 214.346625 140.73558) (xy 214.346625 140.72185) (xy 214.332885 140.72185)
			(xy 214.332885 140.70812) (xy 214.319155 140.70812) (xy 214.319155 140.69439) (xy 214.305425 140.69439)
			(xy 214.305425 140.68066) (xy 214.291695 140.68066) (xy 214.291695 140.66693) (xy 214.277965 140.66693)
			(xy 214.277965 140.65319) (xy 214.264235 140.65319) (xy 214.264235 140.63946) (xy 214.250495 140.63946)
			(xy 214.250495 140.62573) (xy 214.236765 140.62573) (xy 214.236765 140.612) (xy 214.223035 140.612)
			(xy 214.223035 140.59827) (xy 214.209305 140.59827) (xy 214.209305 140.58453) (xy 214.195575 140.58453)
			(xy 214.195575 140.5708) (xy 214.181845 140.5708) (xy 214.181845 140.55707) (xy 214.181845 140.54334)
			(xy 214.168105 140.54334) (xy 214.168105 140.5296) (xy 214.154375 140.5296) (xy 214.154375 140.51587)
			(xy 214.140645 140.51587) (xy 214.140645 140.50214) (xy 214.126915 140.50214) (xy 214.126915 140.48841)
			(xy 214.113185 140.48841) (xy 214.113185 140.47468) (xy 214.099455 140.47468) (xy 214.099455 140.46095)
			(xy 214.085715 140.46095) (xy 214.085715 140.44722) (xy 214.085715 140.43348) (xy 214.071985 140.43348)
			(xy 214.071985 140.41975) (xy 214.058255 140.41975) (xy 214.058255 140.40602) (xy 214.044525 140.40602)
			(xy 214.044525 140.39229) (xy 214.030795 140.39229) (xy 214.030795 140.37856) (xy 214.017065 140.37856)
			(xy 214.017065 140.36483) (xy 214.017065 140.35109) (xy 214.003325 140.35109) (xy 214.003325 140.33736)
			(xy 213.989595 140.33736) (xy 213.989595 140.32363) (xy 213.975865 140.32363) (xy 213.975865 140.3099)
			(xy 213.962135 140.3099) (xy 213.962135 140.29617) (xy 213.962135 140.28244) (xy 213.948405 140.28244)
			(xy 213.948405 140.2687) (xy 213.934665 140.2687) (xy 213.934665 140.25497) (xy 213.920935 140.25497)
			(xy 213.920935 140.24124) (xy 213.920935 140.22751) (xy 213.907205 140.22751) (xy 213.907205 140.21378)
			(xy 213.893475 140.21378) (xy 213.893475 140.20005) (xy 213.879745 140.20005) (xy 213.879745 140.18631)
			(xy 213.879745 140.17258) (xy 213.866005 140.17258) (xy 213.866005 140.15885) (xy 213.852275 140.15885)
			(xy 213.852275 140.14512) (xy 213.838545 140.14512) (xy 213.838545 140.13139) (xy 213.838545 140.11765)
			(xy 213.824815 140.11765) (xy 213.824815 140.10392) (xy 213.811085 140.10392) (xy 213.811085 140.09019)
			(xy 213.797355 140.09019) (xy 213.797355 140.07646) (xy 213.797355 140.06273) (xy 213.783615 140.06273)
			(xy 213.783615 140.04899) (xy 213.769885 140.04899) (xy 213.769885 140.03526) (xy 213.769885 140.02153)
			(xy 213.756155 140.02153) (xy 213.756155 140.0078) (xy 213.742425 140.0078) (xy 213.742425 139.99407)
			(xy 213.742425 139.98034) (xy 213.728695 139.98034) (xy 213.728695 139.9666) (xy 213.714965 139.9666)
			(xy 213.714965 139.95287) (xy 213.714965 139.93914) (xy 213.701225 139.93914) (xy 213.701225 139.92541)
			(xy 213.687495 139.92541) (xy 213.687495 139.91168) (xy 213.687495 139.89795) (xy 213.673765 139.89795)
			(xy 213.673765 139.88421) (xy 213.660035 139.88421) (xy 213.660035 139.87048) (xy 213.660035 139.85675)
			(xy 213.646305 139.85675) (xy 213.646305 139.84302) (xy 213.646305 139.82929) (xy 213.632575 139.82929)
			(xy 213.632575 139.81556) (xy 213.618835 139.81556) (xy 213.618835 139.80182) (xy 213.618835 139.78809)
			(xy 213.605105 139.78809) (xy 213.605105 139.77436) (xy 213.591375 139.77436) (xy 213.591375 139.76063)
			(xy 213.591375 139.7469) (xy 213.577645 139.7469) (xy 213.577645 139.73317) (xy 213.577645 139.71943)
			(xy 213.563915 139.71943) (xy 213.563915 139.7057) (xy 213.563915 139.69197) (xy 213.550185 139.69197)
			(xy 213.550185 139.67824) (xy 213.536445 139.67824) (xy 213.536445 139.66451) (xy 213.536445 139.65078)
			(xy 213.522715 139.65078) (xy 213.522715 139.63704) (xy 213.522715 139.62331) (xy 213.508985 139.62331)
			(xy 213.508985 139.60958) (xy 213.508985 139.59585) (xy 213.495255 139.59585) (xy 213.495255 139.58212)
			(xy 213.481525 139.58212) (xy 213.481525 139.56838) (xy 213.481525 139.55465) (xy 213.467795 139.55465)
			(xy 213.467795 139.54092) (xy 213.467795 139.52719) (xy 213.454055 139.52719) (xy 213.454055 139.51346)
			(xy 213.454055 139.49972) (xy 213.440325 139.49972) (xy 213.440325 139.48599) (xy 213.440325 139.47226)
			(xy 213.426595 139.47226) (xy 213.426595 139.45853) (xy 213.426595 139.4448) (xy 213.412865 139.4448)
			(xy 213.412865 139.43107) (xy 213.412865 139.41733) (xy 213.399135 139.41733) (xy 213.399135 139.4036)
			(xy 213.399135 139.38987) (xy 213.385395 139.38987) (xy 213.385395 139.37614) (xy 213.385395 139.36241)
			(xy 213.371665 139.36241) (xy 213.371665 139.34868) (xy 213.371665 139.33494) (xy 213.357935 139.33494)
			(xy 213.357935 139.32121) (xy 213.357935 139.30748) (xy 213.344205 139.30748) (xy 213.344205 139.29375)
			(xy 213.344205 139.28002) (xy 213.330475 139.28002) (xy 213.330475 139.26629) (xy 213.330475 139.25255)
			(xy 213.316735 139.25255) (xy 213.316735 139.23882) (xy 213.316735 139.22509) (xy 213.316735 139.21136)
			(xy 213.303005 139.21136) (xy 213.303005 139.19763) (xy 213.303005 139.1839) (xy 213.289275 139.1839)
			(xy 213.289275 139.17016) (xy 213.289275 139.15643) (xy 213.275545 139.15643) (xy 213.275545 139.1427)
			(xy 213.275545 139.12897) (xy 213.275545 139.11524) (xy 213.261815 139.11524) (xy 213.261815 139.10151)
			(xy 213.261815 139.08777) (xy 213.248085 139.08777) (xy 213.248085 139.07404) (xy 213.248085 139.06031)
			(xy 213.234345 139.06031) (xy 213.234345 139.04658) (xy 213.234345 139.03285) (xy 213.234345 139.01911)
			(xy 213.220615 139.01911) (xy 213.220615 139.00538) (xy 213.220615 138.99165) (xy 213.206885 138.99165)
			(xy 213.206885 138.97792) (xy 213.206885 138.96419) (xy 213.206885 138.95045) (xy 213.193155 138.95045)
			(xy 213.193155 138.93672) (xy 213.193155 138.92299) (xy 213.193155 138.90926) (xy 213.179425 138.90926)
			(xy 213.179425 138.89553) (xy 213.179425 138.8818) (xy 213.165695 138.8818) (xy 213.165695 138.86806)
			(xy 213.165695 138.85433) (xy 213.165695 138.8406) (xy 213.151955 138.8406) (xy 213.151955 138.82687)
			(xy 213.151955 138.81314) (xy 213.151955 138.79941) (xy 213.138225 138.79941) (xy 213.138225 138.78567)
			(xy 213.138225 138.77194) (xy 213.138225 138.75821) (xy 213.124495 138.75821) (xy 213.124495 138.74448)
			(xy 213.124495 138.73075) (xy 213.124495 138.71702) (xy 213.110765 138.71702) (xy 213.110765 138.70328)
			(xy 213.110765 138.68955) (xy 213.110765 138.67582) (xy 213.097035 138.67582) (xy 213.097035 138.66209)
			(xy 213.097035 138.64836) (xy 213.097035 138.63463) (xy 213.083305 138.63463) (xy 213.083305 138.62089)
			(xy 213.083305 138.60716) (xy 213.083305 138.59343) (xy 213.069565 138.59343) (xy 213.069565 138.5797)
			(xy 213.069565 138.56597) (xy 213.069565 138.55224) (xy 213.069565 138.5385) (xy 213.055835 138.5385)
			(xy 213.055835 138.52477) (xy 213.055835 138.51104) (xy 213.055835 138.49731) (xy 213.042105 138.49731)
			(xy 213.042105 138.48358) (xy 213.042105 138.46984) (xy 213.042105 138.45611) (xy 213.042105 138.44238)
			(xy 213.028375 138.44238) (xy 213.028375 138.42865) (xy 213.028375 138.41492) (xy 213.028375 138.40118)
			(xy 213.028375 138.38745) (xy 213.014645 138.38745) (xy 213.014645 138.37372) (xy 213.014645 138.35999)
			(xy 213.014645 138.34626) (xy 213.014645 138.33253) (xy 213.000915 138.33253) (xy 213.000915 138.31879)
			(xy 213.000915 138.30506) (xy 213.000915 138.29133) (xy 213.000915 138.2776) (xy 212.987175 138.2776)
			(xy 212.987175 138.26387) (xy 212.987175 138.25014) (xy 212.987175 138.2364) (xy 212.987175 138.22267)
			(xy 212.987175 138.20894) (xy 212.973445 138.20894) (xy 212.973445 138.19521) (xy 212.973445 138.18148)
			(xy 212.973445 138.16775) (xy 212.973445 138.15401) (xy 212.973445 138.14028) (xy 212.959715 138.14028)
			(xy 212.959715 138.12655) (xy 212.959715 138.11282) (xy 212.959715 138.09909) (xy 212.959715 138.08536)
			(xy 212.959715 138.07162) (xy 212.945985 138.07162) (xy 212.945985 138.05789) (xy 212.945985 138.04416)
			(xy 212.945985 138.03043) (xy 212.945985 138.0167) (xy 212.945985 138.00296) (xy 212.932255 138.00296)
			(xy 212.932255 137.98923) (xy 212.932255 137.9755) (xy 212.932255 137.96177) (xy 212.932255 137.94804)
			(xy 212.932255 137.9343) (xy 212.932255 137.92057) (xy 212.918525 137.92057) (xy 212.918525 137.90684)
			(xy 212.918525 137.89311) (xy 212.918525 137.87938) (xy 212.918525 137.86565) (xy 212.918525 137.85191)
			(xy 212.918525 137.83818) (xy 212.918525 137.82445) (xy 212.904785 137.82445) (xy 212.904785 137.81072)
			(xy 212.904785 137.79699) (xy 212.904785 137.78326) (xy 212.904785 137.76952) (xy 214.126915 137.76952)
			(xy 214.126915 137.78326) (xy 214.126915 137.79699) (xy 214.126915 137.81072) (xy 214.126915 137.82445)
			(xy 214.126915 137.83818) (xy 214.126915 137.85191) (xy 214.126915 137.86565) (xy 214.126915 137.87938)
			(xy 214.126915 137.89311) (xy 214.126915 137.90684) (xy 214.126915 137.92057) (xy 214.126915 137.9343)
			(xy 214.126915 137.94804) (xy 214.126915 137.96177) (xy 214.126915 137.9755) (xy 214.126915 137.98923)
			(xy 214.126915 138.00296) (xy 214.126915 138.0167) (xy 214.126915 138.03043) (xy 214.126915 138.04416)
			(xy 214.126915 138.05789) (xy 214.126915 138.07162) (xy 214.126915 138.08536) (xy 214.126915 138.09909)
			(xy 214.126915 138.11282) (xy 214.126915 138.12655) (xy 214.126915 138.14028) (xy 214.126915 138.15401)
			(xy 214.126915 138.16775) (xy 214.126915 138.18148) (xy 214.126915 138.19521) (xy 214.126915 138.20894)
			(xy 214.126915 138.22267) (xy 214.126915 138.2364) (xy 214.126915 138.25014) (xy 214.126915 138.26387)
			(xy 214.126915 138.2776) (xy 214.126915 138.29133) (xy 214.126915 138.30506) (xy 214.126915 138.31879)
			(xy 214.126915 138.33253) (xy 214.126915 138.34626) (xy 214.126915 138.35999) (xy 214.126915 138.37372)
			(xy 214.126915 138.38745) (xy 214.126915 138.40118) (xy 214.126915 138.41492) (xy 214.126915 138.42865)
			(xy 214.126915 138.44238) (xy 214.126915 138.45611) (xy 214.126915 138.46984) (xy 214.126915 138.48358)
			(xy 214.126915 138.49731) (xy 214.126915 138.51104) (xy 214.126915 138.52477) (xy 214.126915 138.5385)
			(xy 214.126915 138.55224) (xy 214.126915 138.56597) (xy 214.126915 138.5797) (xy 214.126915 138.59343)
			(xy 214.126915 138.60716) (xy 214.126915 138.62089) (xy 214.126915 138.63463) (xy 214.126915 138.64836)
			(xy 214.126915 138.66209) (xy 214.126915 138.67582) (xy 214.126915 138.68955) (xy 214.126915 138.70328)
			(xy 214.126915 138.71702) (xy 214.126915 138.73075) (xy 214.126915 138.74448) (xy 214.126915 138.75821)
			(xy 214.126915 138.77194) (xy 214.126915 138.78567) (xy 214.126915 138.79941) (xy 214.126915 138.81314)
			(xy 214.126915 138.82687) (xy 214.126915 138.8406) (xy 214.126915 138.85433) (xy 214.126915 138.86806)
			(xy 214.126915 138.8818) (xy 214.126915 138.89553) (xy 214.126915 138.90926) (xy 214.126915 138.92299)
			(xy 214.126915 138.93672) (xy 214.126915 138.95045) (xy 214.126915 138.96419) (xy 214.126915 138.97792)
			(xy 214.126915 138.99165) (xy 214.126915 139.00538) (xy 214.126915 139.01911) (xy 214.126915 139.03285)
			(xy 214.126915 139.04658) (xy 214.126915 139.06031) (xy 214.126915 139.07404) (xy 214.126915 139.08777)
			(xy 214.126915 139.10151) (xy 214.126915 139.11524) (xy 214.126915 139.12897) (xy 214.126915 139.1427)
			(xy 214.126915 139.15643) (xy 214.126915 139.17016) (xy 214.126915 139.1839) (xy 214.126915 139.19763)
			(xy 214.126915 139.21136) (xy 214.126915 139.22509) (xy 214.126915 139.23882) (xy 214.126915 139.25255)
			(xy 214.126915 139.26629) (xy 214.126915 139.28002) (xy 214.126915 139.29375) (xy 214.126915 139.30748)
			(xy 214.126915 139.32121) (xy 214.126915 139.33494) (xy 214.126915 139.34868) (xy 214.126915 139.36241)
			(xy 214.126915 139.37614) (xy 214.126915 139.38987) (xy 214.126915 139.4036) (xy 214.126915 139.41733)
			(xy 214.126915 139.43107) (xy 214.126915 139.4448) (xy 214.126915 139.45853) (xy 214.126915 139.47226)
			(xy 214.126915 139.48599) (xy 214.126915 139.49972) (xy 214.126915 139.51346) (xy 214.126915 139.52719)
			(xy 214.126915 139.54092) (xy 214.126915 139.55465) (xy 214.126915 139.56838) (xy 214.126915 139.58212)
			(xy 214.126915 139.59585) (xy 214.126915 139.60958) (xy 214.126915 139.62331) (xy 214.126915 139.63704)
			(xy 214.126915 139.65078) (xy 214.126915 139.66451) (xy 214.126915 139.67824) (xy 214.126915 139.69197)
			(xy 214.126915 139.7057) (xy 214.126915 139.71943) (xy 214.126915 139.73317) (xy 214.126915 139.7469)
			(xy 214.126915 139.76063) (xy 214.140645 139.76063) (xy 214.140645 139.77436) (xy 214.140645 139.78809)
			(xy 214.140645 139.80182) (xy 214.154375 139.80182) (xy 214.154375 139.81556) (xy 214.154375 139.82929)
			(xy 214.168105 139.82929) (xy 214.168105 139.84302) (xy 214.181845 139.84302) (xy 214.181845 139.85675)
			(xy 214.195575 139.85675) (xy 214.195575 139.87048) (xy 214.209305 139.87048) (xy 214.209305 139.88421)
			(xy 214.223035 139.88421) (xy 214.223035 139.89795) (xy 214.236765 139.89795) (xy 214.236765 139.91168)
			(xy 214.250495 139.91168) (xy 214.250495 139.92541) (xy 214.264235 139.92541) (xy 214.264235 139.93914)
			(xy 214.277965 139.93914) (xy 214.277965 139.95287) (xy 214.291695 139.95287) (xy 214.291695 139.9666)
			(xy 214.305425 139.9666) (xy 214.305425 139.98034) (xy 214.319155 139.98034) (xy 214.319155 139.99407)
			(xy 214.332885 139.99407) (xy 214.332885 140.0078) (xy 214.346625 140.0078) (xy 214.346625 140.02153)
			(xy 214.360355 140.02153) (xy 214.360355 140.03526) (xy 214.374085 140.03526) (xy 214.374085 140.04899)
			(xy 214.387815 140.04899) (xy 214.387815 140.06273) (xy 214.401545 140.06273) (xy 214.401545 140.07646)
			(xy 214.415275 140.07646) (xy 214.415275 140.09019) (xy 214.429015 140.09019) (xy 214.429015 140.10392)
			(xy 214.442745 140.10392) (xy 214.442745 140.11765) (xy 214.456475 140.11765) (xy 214.456475 140.13139)
			(xy 214.470205 140.13139) (xy 214.470205 140.14512) (xy 214.483935 140.14512) (xy 214.483935 140.15885)
			(xy 214.497675 140.15885) (xy 214.497675 140.17258) (xy 214.511405 140.17258) (xy 214.511405 140.18631)
			(xy 214.525135 140.18631) (xy 214.525135 140.20005) (xy 214.538865 140.20005) (xy 214.538865 140.21378)
			(xy 214.552595 140.21378) (xy 214.552595 140.22751) (xy 214.580065 140.22751) (xy 214.580065 140.24124)
			(xy 214.621255 140.24124) (xy 214.621255 140.25497) (xy 216.365185 140.25497) (xy 216.365185 140.24124)
			(xy 216.378925 140.24124) (xy 216.378925 140.22751) (xy 216.392655 140.22751) (xy 216.392655 140.21378)
			(xy 216.406385 140.21378) (xy 216.406385 140.20005) (xy 216.406385 140.18631) (xy 216.406385 140.17258)
			(xy 216.406385 140.15885) (xy 216.406385 140.14512) (xy 216.406385 140.13139) (xy 216.406385 140.11765)
			(xy 216.406385 140.10392) (xy 216.406385 140.09019) (xy 216.406385 140.07646) (xy 216.406385 140.06273)
			(xy 216.406385 140.04899) (xy 216.406385 140.03526) (xy 216.406385 140.02153) (xy 216.406385 140.0078)
			(xy 216.406385 139.99407) (xy 216.406385 139.98034) (xy 216.406385 139.9666) (xy 216.406385 139.95287)
			(xy 216.406385 139.93914) (xy 216.406385 139.92541) (xy 216.406385 139.91168) (xy 216.406385 139.89795)
			(xy 216.406385 139.88421) (xy 216.406385 139.87048) (xy 216.406385 139.85675) (xy 216.406385 139.84302)
			(xy 216.406385 139.82929) (xy 216.406385 139.81556) (xy 216.406385 139.80182) (xy 216.406385 139.78809)
			(xy 216.406385 139.77436) (xy 216.406385 139.76063) (xy 216.406385 139.7469) (xy 216.406385 139.73317)
			(xy 216.406385 139.71943) (xy 216.406385 139.7057) (xy 216.406385 139.69197) (xy 216.406385 139.67824)
			(xy 216.406385 139.66451) (xy 216.406385 139.65078) (xy 216.406385 139.63704) (xy 216.406385 139.62331)
			(xy 216.406385 139.60958) (xy 216.406385 139.59585) (xy 216.406385 139.58212) (xy 216.406385 139.56838)
			(xy 216.392655 139.56838) (xy 216.392655 139.55465) (xy 216.378925 139.55465) (xy 216.378925 139.54092)
			(xy 216.351455 139.54092) (xy 216.351455 139.52719) (xy 214.923355 139.52719) (xy 214.923355 139.51346)
			(xy 214.895895 139.51346) (xy 214.895895 139.49972) (xy 214.895895 139.48599) (xy 214.882155 139.48599)
			(xy 214.882155 139.47226) (xy 214.882155 139.45853) (xy 214.882155 139.4448) (xy 214.882155 139.43107)
			(xy 214.882155 139.41733) (xy 214.882155 139.4036) (xy 214.882155 139.38987) (xy 214.882155 139.37614)
			(xy 214.882155 139.36241) (xy 214.882155 139.34868) (xy 214.882155 139.33494) (xy 214.882155 139.32121)
			(xy 214.882155 139.30748) (xy 214.882155 139.29375) (xy 214.882155 139.28002) (xy 214.882155 139.26629)
			(xy 214.882155 139.25255) (xy 214.882155 139.23882) (xy 214.882155 139.22509) (xy 214.882155 139.21136)
			(xy 214.882155 139.19763) (xy 214.882155 139.1839) (xy 214.882155 139.17016) (xy 214.882155 139.15643)
			(xy 214.882155 139.1427) (xy 214.882155 139.12897) (xy 214.882155 139.11524) (xy 214.882155 139.10151)
			(xy 214.882155 139.08777) (xy 214.882155 139.07404) (xy 214.882155 139.06031) (xy 214.882155 139.04658)
			(xy 214.882155 139.03285) (xy 214.882155 139.01911) (xy 214.882155 139.00538) (xy 214.882155 138.99165)
			(xy 214.882155 138.97792) (xy 214.882155 138.96419) (xy 214.882155 138.95045) (xy 214.882155 138.93672)
			(xy 214.882155 138.92299) (xy 214.882155 138.90926) (xy 214.882155 138.89553) (xy 214.882155 138.8818)
			(xy 214.882155 138.86806) (xy 214.882155 138.85433) (xy 214.882155 138.8406) (xy 214.882155 138.82687)
			(xy 214.882155 138.81314) (xy 214.882155 138.79941) (xy 214.882155 138.78567) (xy 214.882155 138.77194)
			(xy 214.882155 138.75821) (xy 214.882155 138.74448) (xy 214.882155 138.73075) (xy 214.882155 138.71702)
			(xy 214.882155 138.70328) (xy 214.882155 138.68955) (xy 214.882155 138.67582) (xy 214.882155 138.66209)
			(xy 214.882155 138.64836) (xy 214.882155 138.63463) (xy 214.882155 138.62089) (xy 214.882155 138.60716)
			(xy 214.882155 138.59343) (xy 214.882155 138.5797) (xy 214.882155 138.56597) (xy 214.882155 138.55224)
			(xy 214.882155 138.5385) (xy 214.882155 138.52477) (xy 214.882155 138.51104) (xy 214.882155 138.49731)
			(xy 214.882155 138.48358) (xy 214.882155 138.46984) (xy 214.882155 138.45611) (xy 214.882155 138.44238)
			(xy 214.882155 138.42865) (xy 214.882155 138.41492) (xy 214.882155 138.40118) (xy 216.076825 138.40118)
			(xy 216.076825 138.41492) (xy 216.076825 138.42865) (xy 216.076825 138.44238) (xy 216.076825 138.45611)
			(xy 216.076825 138.46984) (xy 216.076825 138.48358) (xy 216.076825 138.49731) (xy 216.076825 138.51104)
			(xy 216.076825 138.52477) (xy 216.076825 138.5385) (xy 216.076825 138.55224) (xy 216.076825 138.56597)
			(xy 216.076825 138.5797) (xy 216.076825 138.59343) (xy 216.076825 138.60716) (xy 216.076825 138.62089)
			(xy 216.076825 138.63463) (xy 216.076825 138.64836) (xy 216.076825 138.66209) (xy 216.076825 138.67582)
			(xy 216.076825 138.68955) (xy 216.076825 138.70328) (xy 216.076825 138.71702) (xy 216.076825 138.73075)
			(xy 216.076825 138.74448) (xy 216.076825 138.75821) (xy 216.076825 138.77194) (xy 216.076825 138.78567)
			(xy 216.076825 138.79941) (xy 216.076825 138.81314) (xy 216.076825 138.82687) (xy 216.076825 138.8406)
			(xy 216.076825 138.85433) (xy 216.076825 138.86806) (xy 216.076825 138.8818) (xy 216.076825 138.89553)
			(xy 216.076825 138.90926) (xy 216.076825 138.92299) (xy 216.076825 138.93672) (xy 216.076825 138.95045)
			(xy 216.076825 138.96419) (xy 216.076825 138.97792) (xy 216.076825 138.99165) (xy 216.076825 139.00538)
			(xy 216.076825 139.01911) (xy 216.090555 139.01911) (xy 216.090555 139.03285) (xy 216.104285 139.03285)
			(xy 216.104285 139.04658) (xy 216.104285 139.06031) (xy 216.118015 139.06031) (xy 216.118015 139.07404)
			(xy 216.131755 139.07404) (xy 216.131755 139.08777) (xy 216.131755 139.10151) (xy 216.145485 139.10151)
			(xy 216.145485 139.11524) (xy 216.159215 139.11524) (xy 216.159215 139.12897) (xy 216.172945 139.12897)
			(xy 216.172945 139.1427) (xy 216.186675 139.1427) (xy 216.186675 139.15643) (xy 216.200405 139.15643)
			(xy 216.200405 139.17016) (xy 216.214145 139.17016) (xy 216.214145 139.1839) (xy 216.227875 139.1839)
			(xy 216.227875 139.19763) (xy 216.241605 139.19763) (xy 216.241605 139.21136) (xy 216.255335 139.21136)
			(xy 216.255335 139.22509) (xy 216.282795 139.22509) (xy 216.282795 139.21136) (xy 216.296535 139.21136)
			(xy 216.296535 139.19763) (xy 216.310265 139.19763) (xy 216.310265 139.1839) (xy 216.323995 139.1839)
			(xy 216.323995 139.17016) (xy 216.337725 139.17016) (xy 216.337725 139.15643) (xy 216.351455 139.15643)
			(xy 216.351455 139.1427) (xy 216.365185 139.1427) (xy 216.365185 139.12897) (xy 216.378925 139.12897)
			(xy 216.378925 139.11524) (xy 216.392655 139.11524) (xy 216.749675 139.11524) (xy 216.749675 139.12897)
			(xy 216.749675 139.1427) (xy 216.749675 139.15643) (xy 216.749675 139.17016) (xy 216.749675 139.1839)
			(xy 216.749675 139.19763) (xy 216.749675 139.21136) (xy 216.749675 139.22509) (xy 216.749675 139.23882)
			(xy 216.749675 139.25255) (xy 216.749675 139.26629) (xy 216.749675 139.28002) (xy 216.749675 139.29375)
			(xy 216.749675 139.30748) (xy 216.749675 139.32121) (xy 216.749675 139.33494) (xy 216.749675 139.34868)
			(xy 216.749675 139.36241) (xy 216.749675 139.37614) (xy 216.749675 139.38987) (xy 216.749675 139.4036)
			(xy 216.749675 139.41733) (xy 216.749675 139.43107) (xy 216.749675 139.4448) (xy 216.749675 139.45853)
			(xy 216.749675 139.47226) (xy 216.749675 139.48599) (xy 216.749675 139.49972) (xy 216.749675 139.51346)
			(xy 216.749675 139.52719) (xy 216.749675 139.54092) (xy 216.749675 139.55465) (xy 216.749675 139.56838)
			(xy 216.749675 139.58212) (xy 216.749675 139.59585) (xy 216.749675 139.60958) (xy 216.749675 139.62331)
			(xy 216.749675 139.63704) (xy 216.749675 139.65078) (xy 216.749675 139.66451) (xy 216.749675 139.67824)
			(xy 216.749675 139.69197) (xy 216.749675 139.7057) (xy 216.749675 139.71943) (xy 216.749675 139.73317)
			(xy 216.749675 139.7469) (xy 216.749675 139.76063) (xy 216.749675 139.77436) (xy 216.749675 139.78809)
			(xy 216.749675 139.80182) (xy 216.749675 139.81556) (xy 216.749675 139.82929) (xy 216.749675 139.84302)
			(xy 216.749675 139.85675) (xy 216.749675 139.87048) (xy 216.749675 139.88421) (xy 216.749675 139.89795)
			(xy 216.749675 139.91168) (xy 216.749675 139.92541) (xy 216.749675 139.93914) (xy 216.749675 139.95287)
			(xy 216.749675 139.9666) (xy 216.749675 139.98034) (xy 216.749675 139.99407) (xy 216.749675 140.0078)
			(xy 216.749675 140.02153) (xy 216.749675 140.03526) (xy 216.749675 140.04899) (xy 216.749675 140.06273)
			(xy 216.749675 140.07646) (xy 216.749675 140.09019) (xy 216.749675 140.10392) (xy 216.749675 140.11765)
			(xy 216.749675 140.13139) (xy 216.749675 140.14512) (xy 216.749675 140.15885) (xy 216.749675 140.17258)
			(xy 216.749675 140.18631) (xy 216.749675 140.20005) (xy 216.749675 140.21378) (xy 216.763415 140.21378)
			(xy 216.763415 140.22751) (xy 216.777145 140.22751) (xy 216.777145 140.24124) (xy 216.804605 140.24124)
			(xy 216.804605 140.25497) (xy 217.449995 140.25497) (xy 217.449995 140.24124) (xy 217.477465 140.24124)
			(xy 217.477465 140.22751) (xy 217.491195 140.22751) (xy 217.491195 140.21378) (xy 217.491195 140.20005)
			(xy 217.504925 140.20005) (xy 217.504925 140.18631) (xy 217.504925 140.17258) (xy 217.504925 140.15885)
			(xy 217.504925 140.14512) (xy 217.504925 140.13139) (xy 217.504925 140.11765) (xy 217.504925 140.10392)
			(xy 217.504925 140.09019) (xy 217.504925 140.07646) (xy 217.504925 140.06273) (xy 217.504925 140.04899)
			(xy 217.504925 140.03526) (xy 217.504925 140.02153) (xy 217.504925 140.0078) (xy 217.504925 139.99407)
			(xy 217.504925 139.98034) (xy 217.504925 139.9666) (xy 217.504925 139.95287) (xy 217.504925 139.93914)
			(xy 217.504925 139.92541) (xy 217.504925 139.91168) (xy 217.504925 139.89795) (xy 217.504925 139.88421)
			(xy 217.504925 139.87048) (xy 217.504925 139.85675) (xy 217.504925 139.84302) (xy 217.504925 139.82929)
			(xy 217.504925 139.81556) (xy 217.504925 139.80182) (xy 217.504925 139.78809) (xy 217.504925 139.77436)
			(xy 217.504925 139.76063) (xy 217.504925 139.7469) (xy 217.504925 139.73317) (xy 217.504925 139.71943)
			(xy 217.504925 139.7057) (xy 217.504925 139.69197) (xy 217.504925 139.67824) (xy 217.504925 139.66451)
			(xy 217.504925 139.65078) (xy 217.504925 139.63704) (xy 217.504925 139.62331) (xy 217.504925 139.60958)
			(xy 217.504925 139.59585) (xy 217.504925 139.58212) (xy 217.504925 139.56838) (xy 217.504925 139.55465)
			(xy 217.504925 139.54092) (xy 217.504925 139.52719) (xy 217.504925 139.51346) (xy 217.504925 139.49972)
			(xy 217.504925 139.48599) (xy 217.504925 139.47226) (xy 217.504925 139.45853) (xy 217.504925 139.4448)
			(xy 217.504925 139.43107) (xy 217.504925 139.41733) (xy 217.504925 139.4036) (xy 217.504925 139.38987)
			(xy 217.504925 139.37614) (xy 217.518655 139.37614) (xy 217.518655 139.36241) (xy 217.518655 139.34868)
			(xy 217.546115 139.34868) (xy 217.546115 139.33494) (xy 218.466145 139.33494) (xy 218.466145 139.34868)
			(xy 218.493615 139.34868) (xy 218.493615 139.36241) (xy 218.493615 139.37614) (xy 218.507345 139.37614)
			(xy 218.507345 139.38987) (xy 218.507345 139.4036) (xy 218.507345 139.41733) (xy 218.507345 139.43107)
			(xy 218.507345 139.4448) (xy 218.507345 139.45853) (xy 218.507345 139.47226) (xy 218.507345 139.48599)
			(xy 218.507345 139.49972) (xy 218.507345 139.51346) (xy 218.507345 139.52719) (xy 218.507345 139.54092)
			(xy 218.507345 139.55465) (xy 218.507345 139.56838) (xy 218.507345 139.58212) (xy 218.507345 139.59585)
			(xy 218.507345 139.60958) (xy 218.507345 139.62331) (xy 218.507345 139.63704) (xy 218.507345 139.65078)
			(xy 218.507345 139.66451) (xy 218.507345 139.67824) (xy 218.507345 139.69197) (xy 218.507345 139.7057)
			(xy 218.507345 139.71943) (xy 218.507345 139.73317) (xy 218.507345 139.7469) (xy 218.507345 139.76063)
			(xy 218.507345 139.77436) (xy 218.507345 139.78809) (xy 218.507345 139.80182) (xy 218.507345 139.81556)
			(xy 218.507345 139.82929) (xy 218.507345 139.84302) (xy 218.507345 139.85675) (xy 218.507345 139.87048)
			(xy 218.507345 139.88421) (xy 218.507345 139.89795) (xy 218.507345 139.91168) (xy 218.507345 139.92541)
			(xy 218.507345 139.93914) (xy 218.507345 139.95287) (xy 218.507345 139.9666) (xy 218.507345 139.98034)
			(xy 218.507345 139.99407) (xy 218.507345 140.0078) (xy 218.507345 140.02153) (xy 218.507345 140.03526)
			(xy 218.507345 140.04899) (xy 218.507345 140.06273) (xy 218.507345 140.07646) (xy 218.507345 140.09019)
			(xy 218.507345 140.10392) (xy 218.507345 140.11765) (xy 218.507345 140.13139) (xy 218.507345 140.14512)
			(xy 218.507345 140.15885) (xy 218.507345 140.17258) (xy 218.507345 140.18631) (xy 218.507345 140.20005)
			(xy 218.507345 140.21378) (xy 218.521075 140.21378) (xy 218.521075 140.22751) (xy 218.534805 140.22751)
			(xy 218.534805 140.24124) (xy 218.562265 140.24124) (xy 218.562265 140.25497) (xy 219.207665 140.25497)
			(xy 219.207665 140.24124) (xy 219.235125 140.24124) (xy 219.235125 140.22751) (xy 219.248855 140.22751)
			(xy 219.248855 140.21378) (xy 219.248855 140.20005) (xy 219.262585 140.20005) (xy 219.262585 140.18631)
			(xy 219.262585 140.17258) (xy 219.262585 140.15885) (xy 219.262585 140.14512) (xy 219.262585 140.13139)
			(xy 219.262585 140.11765) (xy 219.262585 140.10392) (xy 219.262585 140.09019) (xy 219.262585 140.07646)
			(xy 219.262585 140.06273) (xy 219.262585 140.04899) (xy 219.262585 140.03526) (xy 219.262585 140.02153)
			(xy 219.262585 140.0078) (xy 219.262585 139.99407) (xy 219.262585 139.98034) (xy 219.262585 139.9666)
			(xy 219.262585 139.95287) (xy 219.262585 139.93914) (xy 219.262585 139.92541) (xy 219.262585 139.91168)
			(xy 219.262585 139.89795) (xy 219.262585 139.88421) (xy 219.262585 139.87048) (xy 219.262585 139.85675)
			(xy 219.262585 139.84302) (xy 219.262585 139.82929) (xy 219.262585 139.81556) (xy 219.262585 139.80182)
			(xy 219.262585 139.78809) (xy 219.262585 139.77436) (xy 219.262585 139.76063) (xy 219.262585 139.7469)
			(xy 219.262585 139.73317) (xy 219.262585 139.71943) (xy 219.262585 139.7057) (xy 219.262585 139.69197)
			(xy 219.262585 139.67824) (xy 219.262585 139.66451) (xy 219.262585 139.65078) (xy 219.262585 139.63704)
			(xy 219.262585 139.62331) (xy 219.262585 139.60958) (xy 219.262585 139.59585) (xy 219.262585 139.58212)
			(xy 219.262585 139.56838) (xy 219.262585 139.55465) (xy 219.262585 139.54092) (xy 219.262585 139.52719)
			(xy 219.262585 139.51346) (xy 219.262585 139.49972) (xy 219.262585 139.48599) (xy 219.262585 139.47226)
			(xy 219.262585 139.45853) (xy 219.262585 139.4448) (xy 219.262585 139.43107) (xy 219.262585 139.41733)
			(xy 219.262585 139.4036) (xy 219.262585 139.38987) (xy 219.262585 139.37614) (xy 219.262585 139.36241)
			(xy 219.262585 139.34868) (xy 219.262585 139.33494) (xy 219.262585 139.32121) (xy 219.262585 139.30748)
			(xy 219.262585 139.29375) (xy 219.262585 139.28002) (xy 219.262585 139.26629) (xy 219.262585 139.25255)
			(xy 219.262585 139.23882) (xy 219.262585 139.22509) (xy 219.262585 139.21136) (xy 219.262585 139.19763)
			(xy 219.262585 139.1839) (xy 219.262585 139.17016) (xy 219.262585 139.15643) (xy 219.262585 139.1427)
			(xy 219.262585 139.12897) (xy 219.262585 139.11524) (xy 219.262585 139.10151) (xy 219.262585 139.08777)
			(xy 219.262585 139.07404) (xy 219.262585 139.06031) (xy 219.262585 139.04658) (xy 219.262585 139.03285)
			(xy 219.262585 139.01911) (xy 219.262585 139.00538) (xy 219.262585 138.99165) (xy 219.262585 138.97792)
			(xy 219.262585 138.96419) (xy 219.262585 138.95045) (xy 219.262585 138.93672) (xy 219.262585 138.92299)
			(xy 219.262585 138.90926) (xy 219.262585 138.89553) (xy 219.262585 138.8818) (xy 219.262585 138.86806)
			(xy 219.262585 138.85433) (xy 219.262585 138.8406) (xy 219.262585 138.82687) (xy 219.262585 138.81314)
			(xy 219.262585 138.79941) (xy 219.262585 138.78567) (xy 219.262585 138.77194) (xy 219.262585 138.75821)
			(xy 219.262585 138.74448) (xy 219.262585 138.73075) (xy 219.262585 138.71702) (xy 219.262585 138.70328)
			(xy 219.262585 138.68955) (xy 219.262585 138.67582) (xy 219.262585 138.66209) (xy 219.262585 138.64836)
			(xy 219.262585 138.63463) (xy 219.262585 138.62089) (xy 219.262585 138.60716) (xy 219.262585 138.59343)
			(xy 219.262585 138.5797) (xy 219.262585 138.56597) (xy 219.262585 138.55224) (xy 219.262585 138.5385)
			(xy 219.262585 138.52477) (xy 219.262585 138.51104) (xy 219.262585 138.49731) (xy 219.262585 138.48358)
			(xy 219.262585 138.46984) (xy 219.262585 138.45611) (xy 219.262585 138.44238) (xy 219.262585 138.42865)
			(xy 219.262585 138.41492) (xy 219.262585 138.40118) (xy 219.262585 138.38745) (xy 219.262585 138.37372)
			(xy 219.262585 138.35999) (xy 219.262585 138.34626) (xy 219.262585 138.33253) (xy 219.262585 138.31879)
			(xy 219.262585 138.30506) (xy 219.262585 138.29133) (xy 219.262585 138.2776) (xy 219.262585 138.26387)
			(xy 219.262585 138.25014) (xy 219.262585 138.2364) (xy 219.262585 138.22267) (xy 219.262585 138.20894)
			(xy 219.262585 138.19521) (xy 219.262585 138.18148) (xy 219.262585 138.16775) (xy 219.262585 138.15401)
			(xy 219.262585 138.14028) (xy 219.262585 138.12655) (xy 219.262585 138.11282) (xy 219.262585 138.09909)
			(xy 219.262585 138.08536) (xy 219.262585 138.07162) (xy 219.262585 138.05789) (xy 219.262585 138.04416)
			(xy 219.262585 138.03043) (xy 219.262585 138.0167) (xy 219.262585 138.00296) (xy 219.262585 137.98923)
			(xy 219.262585 137.9755) (xy 219.262585 137.96177) (xy 219.262585 137.94804) (xy 219.262585 137.9343)
			(xy 219.262585 137.92057) (xy 219.262585 137.90684) (xy 219.262585 137.89311) (xy 219.262585 137.87938)
			(xy 219.262585 137.86565) (xy 219.262585 137.85191) (xy 219.262585 137.83818) (xy 219.262585 137.82445)
			(xy 219.262585 137.81072) (xy 219.262585 137.79699) (xy 219.262585 137.78326) (xy 219.248855 137.78326)
			(xy 219.248855 137.76952) (xy 219.248855 137.75579) (xy 219.248855 137.74206) (xy 219.248855 137.72833)
			(xy 219.235125 137.72833) (xy 219.235125 137.7146) (xy 219.235125 137.70087) (xy 219.235125 137.68713)
			(xy 219.221395 137.68713) (xy 219.221395 137.6734) (xy 219.207665 137.6734) (xy 219.207665 137.65967)
			(xy 219.193925 137.65967) (xy 219.193925 137.64594) (xy 219.180195 137.64594) (xy 219.180195 137.63221)
			(xy 219.166465 137.63221) (xy 219.166465 137.61848) (xy 219.152735 137.61848) (xy 219.152735 137.60474)
			(xy 219.139005 137.60474) (xy 219.139005 137.59101) (xy 219.125265 137.59101) (xy 219.125265 137.57728)
			(xy 219.111535 137.57728) (xy 219.111535 137.56355) (xy 219.097805 137.56355) (xy 219.097805 137.54982)
			(xy 219.084075 137.54982) (xy 219.084075 137.53609) (xy 219.070345 137.53609) (xy 219.070345 137.52235)
			(xy 219.056615 137.52235) (xy 219.056615 137.50862) (xy 219.042875 137.50862) (xy 219.042875 137.49489)
			(xy 219.029145 137.49489) (xy 219.029145 137.48116) (xy 219.015415 137.48116) (xy 219.015415 137.46743)
			(xy 219.001685 137.46743) (xy 219.001685 137.45369) (xy 218.987955 137.45369) (xy 218.987955 137.43996)
			(xy 218.974225 137.43996) (xy 218.974225 137.42623) (xy 218.960485 137.42623) (xy 218.960485 137.4125)
			(xy 218.946755 137.4125) (xy 218.946755 137.39877) (xy 218.933025 137.39877) (xy 218.933025 137.38503)
			(xy 218.919295 137.38503) (xy 218.919295 137.3713) (xy 218.905565 137.3713) (xy 218.905565 137.35757)
			(xy 218.891835 137.35757) (xy 218.891835 137.34384) (xy 219.550955 137.34384) (xy 219.550955 137.35757)
			(xy 219.550955 137.3713) (xy 219.550955 137.38503) (xy 219.550955 137.39877) (xy 219.550955 137.4125)
			(xy 219.550955 137.42623) (xy 219.550955 137.43996) (xy 219.550955 137.45369) (xy 219.550955 137.46743)
			(xy 219.550955 137.48116) (xy 219.550955 137.49489) (xy 219.550955 137.50862) (xy 219.550955 137.52235)
			(xy 219.550955 137.53609) (xy 219.550955 137.54982) (xy 219.550955 137.56355) (xy 219.550955 137.57728)
			(xy 219.550955 137.59101) (xy 219.550955 137.60474) (xy 219.550955 137.61848) (xy 219.550955 137.63221)
			(xy 219.550955 137.64594) (xy 219.550955 137.65967) (xy 219.550955 137.6734) (xy 219.550955 137.68713)
			(xy 219.550955 137.70087) (xy 219.550955 137.7146) (xy 219.550955 137.72833) (xy 219.550955 137.74206)
			(xy 219.550955 137.75579) (xy 219.550955 137.76952) (xy 219.550955 137.78326) (xy 219.550955 137.79699)
			(xy 219.550955 137.81072) (xy 219.550955 137.82445) (xy 219.550955 137.83818) (xy 219.550955 137.85191)
			(xy 219.550955 137.86565) (xy 219.550955 137.87938) (xy 219.550955 137.89311) (xy 219.550955 137.90684)
			(xy 219.550955 137.92057) (xy 219.550955 137.9343) (xy 219.550955 137.94804) (xy 219.550955 137.96177)
			(xy 219.550955 137.9755) (xy 219.550955 137.98923) (xy 219.550955 138.00296) (xy 219.550955 138.0167)
			(xy 219.550955 138.03043) (xy 219.550955 138.04416) (xy 219.550955 138.05789) (xy 219.550955 138.07162)
			(xy 219.550955 138.08536) (xy 219.550955 138.09909) (xy 219.550955 138.11282) (xy 219.550955 138.12655)
			(xy 219.550955 138.14028) (xy 219.550955 138.15401) (xy 219.550955 138.16775) (xy 219.550955 138.18148)
			(xy 219.550955 138.19521) (xy 219.550955 138.20894) (xy 219.550955 138.22267) (xy 219.550955 138.2364)
			(xy 219.550955 138.25014) (xy 219.550955 138.26387) (xy 219.550955 138.2776) (xy 219.550955 138.29133)
			(xy 219.550955 138.30506) (xy 219.550955 138.31879) (xy 219.550955 138.33253) (xy 219.550955 138.34626)
			(xy 219.550955 138.35999) (xy 219.550955 138.37372) (xy 219.550955 138.38745) (xy 219.550955 138.40118)
			(xy 219.550955 138.41492) (xy 219.550955 138.42865) (xy 219.550955 138.44238) (xy 219.550955 138.45611)
			(xy 219.550955 138.46984) (xy 219.550955 138.48358) (xy 219.550955 138.49731) (xy 219.550955 138.51104)
			(xy 219.550955 138.52477) (xy 219.550955 138.5385) (xy 219.550955 138.55224) (xy 219.550955 138.56597)
			(xy 219.550955 138.5797) (xy 219.550955 138.59343) (xy 219.550955 138.60716) (xy 219.550955 138.62089)
			(xy 219.550955 138.63463) (xy 219.550955 138.64836) (xy 219.550955 138.66209) (xy 219.550955 138.67582)
			(xy 219.550955 138.68955) (xy 219.550955 138.70328) (xy 219.550955 138.71702) (xy 219.550955 138.73075)
			(xy 219.550955 138.74448) (xy 219.550955 138.75821) (xy 219.550955 138.77194) (xy 219.550955 138.78567)
			(xy 219.550955 138.79941) (xy 219.550955 138.81314) (xy 219.550955 138.82687) (xy 219.550955 138.8406)
			(xy 219.550955 138.85433) (xy 219.550955 138.86806) (xy 219.550955 138.8818) (xy 219.550955 138.89553)
			(xy 219.550955 138.90926) (xy 219.550955 138.92299) (xy 219.550955 138.93672) (xy 219.550955 138.95045)
			(xy 219.550955 138.96419) (xy 219.550955 138.97792) (xy 219.550955 138.99165) (xy 219.550955 139.00538)
			(xy 219.550955 139.01911) (xy 219.550955 139.03285) (xy 219.550955 139.04658) (xy 219.550955 139.06031)
			(xy 219.550955 139.07404) (xy 219.550955 139.08777) (xy 219.550955 139.10151) (xy 219.550955 139.11524)
			(xy 219.550955 139.12897) (xy 219.550955 139.1427) (xy 219.550955 139.15643) (xy 219.550955 139.17016)
			(xy 219.550955 139.1839) (xy 219.550955 139.19763) (xy 219.550955 139.21136) (xy 219.550955 139.22509)
			(xy 219.550955 139.23882) (xy 219.550955 139.25255) (xy 219.550955 139.26629) (xy 219.550955 139.28002)
			(xy 219.550955 139.29375) (xy 219.550955 139.30748) (xy 219.550955 139.32121) (xy 219.550955 139.33494)
			(xy 219.550955 139.34868) (xy 219.550955 139.36241) (xy 219.550955 139.37614) (xy 219.550955 139.38987)
			(xy 219.550955 139.4036) (xy 219.550955 139.41733) (xy 219.550955 139.43107) (xy 219.550955 139.4448)
			(xy 219.550955 139.45853) (xy 219.550955 139.47226) (xy 219.550955 139.48599) (xy 219.550955 139.49972)
			(xy 219.550955 139.51346) (xy 219.550955 139.52719) (xy 219.550955 139.54092) (xy 219.550955 139.55465)
			(xy 219.550955 139.56838) (xy 219.550955 139.58212) (xy 219.550955 139.59585) (xy 219.550955 139.60958)
			(xy 219.550955 139.62331) (xy 219.550955 139.63704) (xy 219.550955 139.65078) (xy 219.550955 139.66451)
			(xy 219.550955 139.67824) (xy 219.550955 139.69197) (xy 219.550955 139.7057) (xy 219.550955 139.71943)
			(xy 219.550955 139.73317) (xy 219.550955 139.7469) (xy 219.550955 139.76063) (xy 219.550955 139.77436)
			(xy 219.550955 139.78809) (xy 219.550955 139.80182) (xy 219.550955 139.81556) (xy 219.550955 139.82929)
			(xy 219.550955 139.84302) (xy 219.550955 139.85675) (xy 219.550955 139.87048) (xy 219.550955 139.88421)
			(xy 219.550955 139.89795) (xy 219.550955 139.91168) (xy 219.550955 139.92541) (xy 219.550955 139.93914)
			(xy 219.550955 139.95287) (xy 219.550955 139.9666) (xy 219.550955 139.98034) (xy 219.550955 139.99407)
			(xy 219.550955 140.0078) (xy 219.550955 140.02153) (xy 219.550955 140.03526) (xy 219.550955 140.04899)
			(xy 219.550955 140.06273) (xy 219.550955 140.07646) (xy 219.550955 140.09019) (xy 219.550955 140.10392)
			(xy 219.550955 140.11765) (xy 219.550955 140.13139) (xy 219.550955 140.14512) (xy 219.550955 140.15885)
			(xy 219.564685 140.15885) (xy 219.564685 140.17258) (xy 219.550955 140.17258) (xy 219.550955 140.18631)
			(xy 219.564685 140.18631) (xy 219.564685 140.20005) (xy 219.564685 140.21378) (xy 219.564685 140.22751)
			(xy 219.578415 140.22751) (xy 219.578415 140.24124) (xy 219.605885 140.24124) (xy 219.605885 140.25497)
			(xy 220.278735 140.25497) (xy 220.278735 140.24124) (xy 220.292475 140.24124) (xy 220.292475 140.22751)
			(xy 220.306205 140.22751) (xy 220.306205 140.21378) (xy 220.306205 140.20005) (xy 220.306205 140.18631)
			(xy 220.319935 140.18631) (xy 220.319935 140.17258) (xy 220.319935 140.15885) (xy 220.319935 140.14512)
			(xy 220.319935 140.13139) (xy 220.319935 140.11765) (xy 220.319935 140.10392) (xy 220.319935 140.09019)
			(xy 220.319935 140.07646) (xy 220.319935 140.06273) (xy 220.319935 140.04899) (xy 220.319935 140.03526)
			(xy 220.319935 140.02153) (xy 220.319935 140.0078) (xy 220.319935 139.99407) (xy 220.319935 139.98034)
			(xy 220.319935 139.9666) (xy 220.319935 139.95287) (xy 220.319935 139.93914) (xy 220.319935 139.92541)
			(xy 220.319935 139.91168) (xy 220.319935 139.89795) (xy 220.319935 139.88421) (xy 220.319935 139.87048)
			(xy 220.319935 139.85675) (xy 220.319935 139.84302) (xy 220.319935 139.82929) (xy 220.319935 139.81556)
			(xy 220.319935 139.80182) (xy 220.319935 139.78809) (xy 220.319935 139.77436) (xy 220.319935 139.76063)
			(xy 220.319935 139.7469) (xy 220.319935 139.73317) (xy 220.319935 139.71943) (xy 220.319935 139.7057)
			(xy 220.319935 139.69197) (xy 220.319935 139.67824) (xy 220.319935 139.66451) (xy 220.319935 139.65078)
			(xy 220.319935 139.63704) (xy 220.319935 139.62331) (xy 220.319935 139.60958) (xy 220.319935 139.59585)
			(xy 220.319935 139.58212) (xy 220.319935 139.56838) (xy 220.319935 139.55465) (xy 220.319935 139.54092)
			(xy 220.319935 139.52719) (xy 220.319935 139.51346) (xy 220.319935 139.49972) (xy 220.319935 139.48599)
			(xy 220.319935 139.47226) (xy 220.319935 139.45853) (xy 220.319935 139.4448) (xy 220.306205 139.4448)
			(xy 220.306205 139.43107) (xy 220.319935 139.43107) (xy 220.319935 139.41733) (xy 220.319935 139.4036)
			(xy 220.319935 139.38987) (xy 220.319935 139.37614) (xy 220.319935 139.36241) (xy 220.841745 139.36241)
			(xy 220.841745 139.37614) (xy 220.841745 139.38987) (xy 220.855475 139.38987) (xy 220.855475 139.4036)
			(xy 220.855475 139.41733) (xy 220.869205 139.41733) (xy 220.869205 139.43107) (xy 220.882935 139.43107)
			(xy 220.882935 139.4448) (xy 220.882935 139.45853) (xy 220.896665 139.45853) (xy 220.896665 139.47226)
			(xy 220.896665 139.48599) (xy 220.910395 139.48599) (xy 220.910395 139.49972) (xy 220.924135 139.49972)
			(xy 220.924135 139.51346) (xy 220.924135 139.52719) (xy 220.937865 139.52719) (xy 220.937865 139.54092)
			(xy 220.937865 139.55465) (xy 220.951595 139.55465) (xy 220.951595 139.56838) (xy 220.951595 139.58212)
			(xy 220.965325 139.58212) (xy 220.965325 139.59585) (xy 220.979055 139.59585) (xy 220.979055 139.60958)
			(xy 220.979055 139.62331) (xy 220.992785 139.62331) (xy 220.992785 139.63704) (xy 220.992785 139.65078)
			(xy 221.006525 139.65078) (xy 221.006525 139.66451) (xy 221.020255 139.66451) (xy 221.020255 139.67824)
			(xy 221.020255 139.69197) (xy 221.033985 139.69197) (xy 221.033985 139.7057) (xy 221.033985 139.71943)
			(xy 221.047715 139.71943) (xy 221.047715 139.73317) (xy 221.061445 139.73317) (xy 221.061445 139.7469)
			(xy 221.061445 139.76063) (xy 221.075175 139.76063) (xy 221.075175 139.77436) (xy 221.075175 139.78809)
			(xy 221.088915 139.78809) (xy 221.088915 139.80182) (xy 221.088915 139.81556) (xy 221.102645 139.81556)
			(xy 221.102645 139.82929) (xy 221.116375 139.82929) (xy 221.116375 139.84302) (xy 221.116375 139.85675)
			(xy 221.130105 139.85675) (xy 221.130105 139.87048) (xy 221.130105 139.88421) (xy 221.143835 139.88421)
			(xy 221.143835 139.89795) (xy 221.157565 139.89795) (xy 221.157565 139.91168) (xy 221.157565 139.92541)
			(xy 221.171305 139.92541) (xy 221.171305 139.93914) (xy 221.171305 139.95287) (xy 221.185035 139.95287)
			(xy 221.185035 139.9666) (xy 221.198765 139.9666) (xy 221.198765 139.98034) (xy 221.198765 139.99407)
			(xy 221.212495 139.99407) (xy 221.212495 140.0078) (xy 221.212495 140.02153) (xy 221.226225 140.02153)
			(xy 221.226225 140.03526) (xy 221.239955 140.03526) (xy 221.239955 140.04899) (xy 221.239955 140.06273)
			(xy 221.253695 140.06273) (xy 221.253695 140.07646) (xy 221.253695 140.09019) (xy 221.267425 140.09019)
			(xy 221.267425 140.10392) (xy 221.267425 140.11765) (xy 221.281155 140.11765) (xy 221.281155 140.13139)
			(xy 221.294885 140.13139) (xy 221.294885 140.14512) (xy 221.294885 140.15885) (xy 221.308615 140.15885)
			(xy 221.308615 140.17258) (xy 221.308615 140.18631) (xy 221.322355 140.18631) (xy 221.322355 140.20005)
			(xy 221.336085 140.20005) (xy 221.336085 140.21378) (xy 221.349815 140.21378) (xy 221.349815 140.22751)
			(xy 221.363545 140.22751) (xy 221.363545 140.24124) (xy 221.391015 140.24124) (xy 221.391015 140.25497)
			(xy 222.159985 140.25497) (xy 222.159985 140.24124) (xy 222.173715 140.24124) (xy 222.173715 140.22751)
			(xy 222.173715 140.21378) (xy 222.173715 140.20005) (xy 222.173715 140.18631) (xy 222.159985 140.18631)
			(xy 222.159985 140.17258) (xy 222.146255 140.17258) (xy 222.146255 140.15885) (xy 222.146255 140.14512)
			(xy 222.132525 140.14512) (xy 222.132525 140.13139) (xy 222.132525 140.11765) (xy 222.118795 140.11765)
			(xy 222.118795 140.10392) (xy 222.105065 140.10392) (xy 222.105065 140.09019) (xy 222.105065 140.07646)
			(xy 222.091325 140.07646) (xy 222.091325 140.06273) (xy 222.091325 140.04899) (xy 222.077595 140.04899)
			(xy 222.077595 140.03526) (xy 222.063865 140.03526) (xy 222.063865 140.02153) (xy 222.063865 140.0078)
			(xy 222.050135 140.0078) (xy 222.050135 139.99407) (xy 222.050135 139.98034) (xy 222.036405 139.98034)
			(xy 222.036405 139.9666) (xy 222.022675 139.9666) (xy 222.022675 139.95287) (xy 222.022675 139.93914)
			(xy 222.008935 139.93914) (xy 222.008935 139.92541) (xy 222.008935 139.91168) (xy 221.995205 139.91168)
			(xy 221.995205 139.89795) (xy 221.981475 139.89795) (xy 221.981475 139.88421) (xy 221.981475 139.87048)
			(xy 221.967745 139.87048) (xy 221.967745 139.85675) (xy 221.967745 139.84302) (xy 221.954015 139.84302)
			(xy 221.954015 139.82929) (xy 221.940285 139.82929) (xy 221.940285 139.81556) (xy 221.940285 139.80182)
			(xy 221.926545 139.80182) (xy 221.926545 139.78809) (xy 221.926545 139.77436) (xy 221.912815 139.77436)
			(xy 221.912815 139.76063) (xy 221.899085 139.76063) (xy 221.899085 139.7469) (xy 221.899085 139.73317)
			(xy 221.885355 139.73317) (xy 221.885355 139.71943) (xy 221.885355 139.7057) (xy 221.871625 139.7057)
			(xy 221.871625 139.69197) (xy 221.857895 139.69197) (xy 221.857895 139.67824) (xy 221.857895 139.66451)
			(xy 221.844155 139.66451) (xy 221.844155 139.65078) (xy 221.844155 139.63704) (xy 221.830425 139.63704)
			(xy 221.830425 139.62331) (xy 221.816695 139.62331) (xy 221.816695 139.60958) (xy 221.816695 139.59585)
			(xy 221.802965 139.59585) (xy 221.802965 139.58212) (xy 221.802965 139.56838) (xy 221.789235 139.56838)
			(xy 221.789235 139.55465) (xy 221.775495 139.55465) (xy 221.775495 139.54092) (xy 221.775495 139.52719)
			(xy 221.761765 139.52719) (xy 221.761765 139.51346) (xy 221.761765 139.49972) (xy 221.748035 139.49972)
			(xy 221.748035 139.48599) (xy 221.734305 139.48599) (xy 221.734305 139.47226) (xy 221.734305 139.45853)
			(xy 221.720575 139.45853) (xy 221.720575 139.4448) (xy 221.720575 139.43107) (xy 221.706835 139.43107)
			(xy 221.706835 139.41733) (xy 221.706835 139.4036) (xy 221.693105 139.4036) (xy 221.693105 139.38987)
			(xy 221.679375 139.38987) (xy 221.679375 139.37614) (xy 221.679375 139.36241) (xy 221.665645 139.36241)
			(xy 221.665645 139.34868) (xy 221.665645 139.33494) (xy 221.651915 139.33494) (xy 221.651915 139.32121)
			(xy 221.638185 139.32121) (xy 221.638185 139.30748) (xy 221.638185 139.29375) (xy 221.651915 139.29375)
			(xy 221.651915 139.28002) (xy 221.665645 139.28002) (xy 221.665645 139.26629) (xy 221.679375 139.26629)
			(xy 221.679375 139.25255) (xy 221.693105 139.25255) (xy 221.693105 139.23882) (xy 221.706835 139.23882)
			(xy 221.706835 139.22509) (xy 221.720575 139.22509) (xy 221.720575 139.21136) (xy 221.734305 139.21136)
			(xy 221.734305 139.19763) (xy 221.748035 139.19763) (xy 221.748035 139.1839) (xy 221.761765 139.1839)
			(xy 221.761765 139.17016) (xy 221.775495 139.17016) (xy 221.775495 139.15643) (xy 221.789235 139.15643)
			(xy 221.789235 139.1427) (xy 221.802965 139.1427) (xy 221.802965 139.12897) (xy 221.816695 139.12897)
			(xy 221.816695 139.11524) (xy 221.830425 139.11524) (xy 221.830425 139.10151) (xy 221.844155 139.10151)
			(xy 221.844155 139.08777) (xy 221.857895 139.08777) (xy 221.857895 139.07404) (xy 221.871625 139.07404)
			(xy 221.871625 139.06031) (xy 221.885355 139.06031) (xy 221.885355 139.04658) (xy 221.899085 139.04658)
			(xy 221.899085 139.03285) (xy 221.912815 139.03285) (xy 221.912815 139.01911) (xy 221.926545 139.01911)
			(xy 221.926545 139.00538) (xy 221.940285 139.00538) (xy 221.940285 138.99165) (xy 221.954015 138.99165)
			(xy 221.954015 138.97792) (xy 221.954015 138.96419) (xy 221.967745 138.96419) (xy 221.967745 138.95045)
			(xy 221.981475 138.95045) (xy 221.981475 138.93672) (xy 221.995205 138.93672) (xy 221.995205 138.92299)
			(xy 222.008935 138.92299) (xy 222.008935 138.90926) (xy 222.022675 138.90926) (xy 222.022675 138.89553)
			(xy 222.036405 138.89553) (xy 222.036405 138.8818) (xy 222.036405 138.86806) (xy 222.050135 138.86806)
			(xy 222.050135 138.85433) (xy 222.050135 138.8406) (xy 222.063865 138.8406) (xy 222.063865 138.82687)
			(xy 222.063865 138.81314) (xy 222.063865 138.79941) (xy 222.063865 138.78567) (xy 222.063865 138.77194)
			(xy 222.063865 138.75821) (xy 222.063865 138.74448) (xy 222.063865 138.73075) (xy 222.063865 138.71702)
			(xy 222.063865 138.70328) (xy 222.063865 138.68955) (xy 222.063865 138.67582) (xy 222.063865 138.66209)
			(xy 222.063865 138.64836) (xy 222.063865 138.63463) (xy 222.063865 138.62089) (xy 222.063865 138.60716)
			(xy 222.063865 138.59343) (xy 222.063865 138.5797) (xy 222.063865 138.56597) (xy 222.063865 138.55224)
			(xy 222.063865 138.5385) (xy 222.063865 138.52477) (xy 222.063865 138.51104) (xy 222.063865 138.49731)
			(xy 222.063865 138.48358) (xy 222.063865 138.46984) (xy 222.063865 138.45611) (xy 222.063865 138.44238)
			(xy 222.063865 138.42865) (xy 222.063865 138.41492) (xy 222.063865 138.40118) (xy 222.063865 138.38745)
			(xy 222.063865 138.37372) (xy 222.063865 138.35999) (xy 222.063865 138.34626) (xy 222.063865 138.33253)
			(xy 222.063865 138.31879) (xy 222.063865 138.30506) (xy 222.063865 138.29133) (xy 222.063865 138.2776)
			(xy 222.063865 138.26387) (xy 222.063865 138.25014) (xy 222.063865 138.2364) (xy 222.063865 138.22267)
			(xy 222.063865 138.20894) (xy 222.063865 138.19521) (xy 222.063865 138.18148) (xy 222.063865 138.16775)
			(xy 222.063865 138.15401) (xy 222.063865 138.14028) (xy 222.063865 138.12655) (xy 222.063865 138.11282)
			(xy 222.063865 138.09909) (xy 222.063865 138.08536) (xy 222.063865 138.07162) (xy 222.063865 138.05789)
			(xy 222.063865 138.04416) (xy 222.063865 138.03043) (xy 222.063865 138.0167) (xy 222.063865 138.00296)
			(xy 222.063865 137.98923) (xy 222.063865 137.9755) (xy 222.063865 137.96177) (xy 222.063865 137.94804)
			(xy 222.063865 137.9343) (xy 222.063865 137.92057) (xy 222.063865 137.90684) (xy 222.063865 137.89311)
			(xy 222.063865 137.87938) (xy 222.063865 137.86565) (xy 222.063865 137.85191) (xy 222.063865 137.83818)
			(xy 222.063865 137.82445) (xy 222.063865 137.81072) (xy 222.063865 137.79699) (xy 222.063865 137.78326)
			(xy 222.063865 137.76952) (xy 222.063865 137.75579) (xy 222.050135 137.75579) (xy 222.050135 137.74206)
			(xy 222.050135 137.72833) (xy 222.050135 137.7146) (xy 222.036405 137.7146) (xy 222.036405 137.70087)
			(xy 222.036405 137.68713) (xy 222.022675 137.68713) (xy 222.022675 137.6734) (xy 222.008935 137.6734)
			(xy 222.008935 137.65967) (xy 221.995205 137.65967) (xy 221.995205 137.64594) (xy 221.981475 137.64594)
			(xy 221.981475 137.63221) (xy 221.967745 137.63221) (xy 221.967745 137.61848) (xy 221.954015 137.61848)
			(xy 221.954015 137.60474) (xy 221.940285 137.60474) (xy 221.940285 137.59101) (xy 221.926545 137.59101)
			(xy 221.926545 137.57728) (xy 221.912815 137.57728) (xy 221.912815 137.56355) (xy 221.899085 137.56355)
			(xy 221.899085 137.54982) (xy 221.885355 137.54982) (xy 221.885355 137.53609) (xy 221.871625 137.53609)
			(xy 221.871625 137.52235) (xy 221.857895 137.52235) (xy 221.857895 137.50862) (xy 221.844155 137.50862)
			(xy 221.844155 137.49489) (xy 221.830425 137.49489) (xy 221.830425 137.48116) (xy 221.816695 137.48116)
			(xy 221.816695 137.46743) (xy 221.802965 137.46743) (xy 221.802965 137.45369) (xy 221.789235 137.45369)
			(xy 221.789235 137.43996) (xy 221.775495 137.43996) (xy 221.775495 137.42623) (xy 221.761765 137.42623)
			(xy 221.761765 137.4125) (xy 221.748035 137.4125) (xy 221.748035 137.39877) (xy 221.734305 137.39877)
			(xy 221.734305 137.38503) (xy 221.720575 137.38503) (xy 221.720575 137.3713) (xy 221.706835 137.3713)
			(xy 221.706835 137.35757) (xy 221.693105 137.35757) (xy 221.693105 137.34384) (xy 221.679375 137.34384)
			(xy 221.679375 137.33011) (xy 221.665645 137.33011) (xy 221.665645 137.31638) (xy 222.475815 137.31638)
			(xy 222.475815 137.33011) (xy 222.475815 137.34384) (xy 222.475815 137.35757) (xy 222.475815 137.3713)
			(xy 222.475815 137.38503) (xy 222.475815 137.39877) (xy 222.475815 137.4125) (xy 222.475815 137.42623)
			(xy 222.475815 137.43996) (xy 222.475815 137.45369) (xy 222.475815 137.46743) (xy 222.475815 137.48116)
			(xy 222.475815 137.49489) (xy 222.475815 137.50862) (xy 222.475815 137.52235) (xy 222.475815 137.53609)
			(xy 222.475815 137.54982) (xy 222.475815 137.56355) (xy 222.475815 137.57728) (xy 222.475815 137.59101)
			(xy 222.475815 137.60474) (xy 222.475815 137.61848) (xy 222.475815 137.63221) (xy 222.475815 137.64594)
			(xy 222.475815 137.65967) (xy 222.475815 137.6734) (xy 222.475815 137.68713) (xy 222.475815 137.70087)
			(xy 222.475815 137.7146) (xy 222.475815 137.72833) (xy 222.475815 137.74206) (xy 222.475815 137.75579)
			(xy 222.475815 137.76952) (xy 222.475815 137.78326) (xy 222.475815 137.79699) (xy 222.475815 137.81072)
			(xy 222.475815 137.82445) (xy 222.475815 137.83818) (xy 222.475815 137.85191) (xy 222.475815 137.86565)
			(xy 222.475815 137.87938) (xy 222.475815 137.89311) (xy 222.475815 137.90684) (xy 222.475815 137.92057)
			(xy 222.475815 137.9343) (xy 222.475815 137.94804) (xy 222.475815 137.96177) (xy 222.475815 137.9755)
			(xy 222.475815 137.98923) (xy 222.475815 138.00296) (xy 222.475815 138.0167) (xy 222.475815 138.03043)
			(xy 222.475815 138.04416) (xy 222.475815 138.05789) (xy 222.475815 138.07162) (xy 222.475815 138.08536)
			(xy 222.475815 138.09909) (xy 222.475815 138.11282) (xy 222.475815 138.12655) (xy 222.475815 138.14028)
			(xy 222.475815 138.15401) (xy 222.475815 138.16775) (xy 222.475815 138.18148) (xy 222.475815 138.19521)
			(xy 222.475815 138.20894) (xy 222.475815 138.22267) (xy 222.475815 138.2364) (xy 222.475815 138.25014)
			(xy 222.475815 138.26387) (xy 222.475815 138.2776) (xy 222.475815 138.29133) (xy 222.475815 138.30506)
			(xy 222.475815 138.31879) (xy 222.475815 138.33253) (xy 222.475815 138.34626) (xy 222.475815 138.35999)
			(xy 222.475815 138.37372) (xy 222.475815 138.38745) (xy 222.475815 138.40118) (xy 222.475815 138.41492)
			(xy 222.475815 138.42865) (xy 222.475815 138.44238) (xy 222.475815 138.45611) (xy 222.475815 138.46984)
			(xy 222.475815 138.48358) (xy 222.475815 138.49731) (xy 222.475815 138.51104) (xy 222.475815 138.52477)
			(xy 222.475815 138.5385) (xy 222.475815 138.55224) (xy 222.475815 138.56597) (xy 222.475815 138.5797)
			(xy 222.475815 138.59343) (xy 222.475815 138.60716) (xy 222.475815 138.62089) (xy 222.475815 138.63463)
			(xy 222.475815 138.64836) (xy 222.475815 138.66209) (xy 222.475815 138.67582) (xy 222.475815 138.68955)
			(xy 222.475815 138.70328) (xy 222.475815 138.71702) (xy 222.475815 138.73075) (xy 222.475815 138.74448)
			(xy 222.475815 138.75821) (xy 222.475815 138.77194) (xy 222.475815 138.78567) (xy 222.475815 138.79941)
			(xy 222.475815 138.81314) (xy 222.475815 138.82687) (xy 222.475815 138.8406) (xy 222.475815 138.85433)
			(xy 222.475815 138.86806) (xy 222.475815 138.8818) (xy 222.475815 138.89553) (xy 222.475815 138.90926)
			(xy 222.475815 138.92299) (xy 222.475815 138.93672) (xy 222.475815 138.95045) (xy 222.475815 138.96419)
			(xy 222.475815 138.97792) (xy 222.475815 138.99165) (xy 222.475815 139.00538) (xy 222.475815 139.01911)
			(xy 222.475815 139.03285) (xy 222.475815 139.04658) (xy 222.475815 139.06031) (xy 222.475815 139.07404)
			(xy 222.475815 139.08777) (xy 222.475815 139.10151) (xy 222.475815 139.11524) (xy 222.475815 139.12897)
			(xy 222.475815 139.1427) (xy 222.475815 139.15643) (xy 222.475815 139.17016) (xy 222.475815 139.1839)
			(xy 222.475815 139.19763) (xy 222.475815 139.21136) (xy 222.475815 139.22509) (xy 222.475815 139.23882)
			(xy 222.475815 139.25255) (xy 222.475815 139.26629) (xy 222.475815 139.28002) (xy 222.475815 139.29375)
			(xy 222.475815 139.30748) (xy 222.475815 139.32121) (xy 222.475815 139.33494) (xy 222.475815 139.34868)
			(xy 222.475815 139.36241) (xy 222.475815 139.37614) (xy 222.475815 139.38987) (xy 222.475815 139.4036)
			(xy 222.475815 139.41733) (xy 222.475815 139.43107) (xy 222.475815 139.4448) (xy 222.475815 139.45853)
			(xy 222.475815 139.47226) (xy 222.475815 139.48599) (xy 222.475815 139.49972) (xy 222.475815 139.51346)
			(xy 222.475815 139.52719) (xy 222.475815 139.54092) (xy 222.475815 139.55465) (xy 222.475815 139.56838)
			(xy 222.475815 139.58212) (xy 222.475815 139.59585) (xy 222.475815 139.60958) (xy 222.475815 139.62331)
			(xy 222.475815 139.63704) (xy 222.475815 139.65078) (xy 222.475815 139.66451) (xy 222.475815 139.67824)
			(xy 222.475815 139.69197) (xy 222.475815 139.7057) (xy 222.475815 139.71943) (xy 222.475815 139.73317)
			(xy 222.475815 139.7469) (xy 222.475815 139.76063) (xy 222.475815 139.77436) (xy 222.475815 139.78809)
			(xy 222.475815 139.80182) (xy 222.475815 139.81556) (xy 222.475815 139.82929) (xy 222.475815 139.84302)
			(xy 222.475815 139.85675) (xy 222.475815 139.87048) (xy 222.475815 139.88421) (xy 222.475815 139.89795)
			(xy 222.475815 139.91168) (xy 222.475815 139.92541) (xy 222.475815 139.93914) (xy 222.475815 139.95287)
			(xy 222.475815 139.9666) (xy 222.475815 139.98034) (xy 222.475815 139.99407) (xy 222.475815 140.0078)
			(xy 222.475815 140.02153) (xy 222.475815 140.03526) (xy 222.475815 140.04899) (xy 222.475815 140.06273)
			(xy 222.475815 140.07646) (xy 222.475815 140.09019) (xy 222.475815 140.10392) (xy 222.475815 140.11765)
			(xy 222.475815 140.13139) (xy 222.475815 140.14512) (xy 222.475815 140.15885) (xy 222.475815 140.17258)
			(xy 222.475815 140.18631) (xy 222.475815 140.20005) (xy 222.475815 140.21378) (xy 222.489555 140.21378)
			(xy 222.489555 140.22751) (xy 222.503285 140.22751) (xy 222.503285 140.24124) (xy 222.517015 140.24124)
			(xy 222.517015 140.25497) (xy 224.480655 140.25497) (xy 224.480655 140.24124) (xy 224.535585 140.24124)
			(xy 224.535585 140.22751) (xy 224.563045 140.22751) (xy 224.563045 140.21378) (xy 224.576775 140.21378)
			(xy 224.576775 140.20005) (xy 224.590505 140.20005) (xy 224.590505 140.18631) (xy 224.604245 140.18631)
			(xy 224.604245 140.17258) (xy 224.617975 140.17258) (xy 224.617975 140.15885) (xy 224.631705 140.15885)
			(xy 224.631705 140.14512) (xy 224.645435 140.14512) (xy 224.645435 140.13139) (xy 224.659165 140.13139)
			(xy 224.659165 140.11765) (xy 224.672895 140.11765) (xy 224.672895 140.10392) (xy 224.686635 140.10392)
			(xy 224.686635 140.09019) (xy 224.700365 140.09019) (xy 224.700365 140.07646) (xy 224.714095 140.07646)
			(xy 224.714095 140.06273) (xy 224.727825 140.06273) (xy 224.727825 140.04899) (xy 224.741555 140.04899)
			(xy 224.741555 140.03526) (xy 224.755285 140.03526) (xy 224.755285 140.02153) (xy 224.769025 140.02153)
			(xy 224.769025 140.0078) (xy 224.782755 140.0078) (xy 224.782755 139.99407) (xy 224.796485 139.99407)
			(xy 224.796485 139.98034) (xy 224.810215 139.98034) (xy 224.810215 139.9666) (xy 224.823945 139.9666)
			(xy 224.823945 139.95287) (xy 224.837675 139.95287) (xy 224.837675 139.93914) (xy 224.851415 139.93914)
			(xy 224.851415 139.92541) (xy 224.865145 139.92541) (xy 224.865145 139.91168) (xy 224.878875 139.91168)
			(xy 224.878875 139.89795) (xy 224.892605 139.89795) (xy 224.892605 139.88421) (xy 224.906335 139.88421)
			(xy 224.906335 139.87048) (xy 224.920065 139.87048) (xy 224.920065 139.85675) (xy 224.933805 139.85675)
			(xy 224.933805 139.84302) (xy 224.947535 139.84302) (xy 224.947535 139.82929) (xy 224.961265 139.82929)
			(xy 224.961265 139.81556) (xy 224.961265 139.80182) (xy 224.961265 139.78809) (xy 224.974995 139.78809)
			(xy 224.974995 139.77436) (xy 224.974995 139.76063) (xy 224.974995 139.7469) (xy 224.974995 139.73317)
			(xy 224.988725 139.73317) (xy 224.988725 139.71943) (xy 224.988725 139.7057) (xy 224.988725 139.69197)
			(xy 224.988725 139.67824) (xy 224.988725 139.66451) (xy 224.988725 139.65078) (xy 224.988725 139.63704)
			(xy 224.988725 139.62331) (xy 224.988725 139.60958) (xy 224.988725 139.59585) (xy 224.988725 139.58212)
			(xy 224.988725 139.56838) (xy 224.988725 139.55465) (xy 224.988725 139.54092) (xy 224.988725 139.52719)
			(xy 224.988725 139.51346) (xy 224.988725 139.49972) (xy 224.988725 139.48599) (xy 224.988725 139.47226)
			(xy 224.988725 139.45853) (xy 224.988725 139.4448) (xy 224.988725 139.43107) (xy 224.988725 139.41733)
			(xy 224.988725 139.4036) (xy 224.988725 139.38987) (xy 224.988725 139.37614) (xy 224.988725 139.36241)
			(xy 224.988725 139.34868) (xy 224.988725 139.33494) (xy 224.988725 139.32121) (xy 224.988725 139.30748)
			(xy 224.988725 139.29375) (xy 224.988725 139.28002) (xy 224.988725 139.26629) (xy 224.988725 139.25255)
			(xy 224.988725 139.23882) (xy 224.988725 139.22509) (xy 224.988725 139.21136) (xy 224.988725 139.19763)
			(xy 224.988725 139.1839) (xy 224.988725 139.17016) (xy 224.988725 139.15643) (xy 224.988725 139.1427)
			(xy 224.988725 139.12897) (xy 224.988725 139.11524) (xy 224.988725 139.10151) (xy 224.988725 139.08777)
			(xy 224.988725 139.07404) (xy 224.988725 139.06031) (xy 224.988725 139.04658) (xy 224.988725 139.03285)
			(xy 224.988725 139.01911) (xy 224.988725 139.00538) (xy 224.988725 138.99165) (xy 224.988725 138.97792)
			(xy 224.988725 138.96419) (xy 224.988725 138.95045) (xy 224.988725 138.93672) (xy 224.988725 138.92299)
			(xy 224.988725 138.90926) (xy 224.988725 138.89553) (xy 224.988725 138.8818) (xy 224.988725 138.86806)
			(xy 224.988725 138.85433) (xy 224.988725 138.8406) (xy 224.988725 138.82687) (xy 224.988725 138.81314)
			(xy 224.988725 138.79941) (xy 224.988725 138.78567) (xy 224.988725 138.77194) (xy 224.988725 138.75821)
			(xy 224.988725 138.74448) (xy 224.988725 138.73075) (xy 224.988725 138.71702) (xy 224.988725 138.70328)
			(xy 224.988725 138.68955) (xy 224.988725 138.67582) (xy 224.988725 138.66209) (xy 224.988725 138.64836)
			(xy 224.988725 138.63463) (xy 224.988725 138.62089) (xy 224.988725 138.60716) (xy 224.988725 138.59343)
			(xy 224.988725 138.5797) (xy 224.988725 138.56597) (xy 224.988725 138.55224) (xy 224.988725 138.5385)
			(xy 224.988725 138.52477) (xy 224.988725 138.51104) (xy 224.988725 138.49731) (xy 224.988725 138.48358)
			(xy 224.988725 138.46984) (xy 224.988725 138.45611) (xy 224.988725 138.44238) (xy 224.988725 138.42865)
			(xy 224.988725 138.41492) (xy 224.988725 138.40118) (xy 224.988725 138.38745) (xy 224.988725 138.37372)
			(xy 224.988725 138.35999) (xy 224.988725 138.34626) (xy 224.988725 138.33253) (xy 224.988725 138.31879)
			(xy 224.988725 138.30506) (xy 224.988725 138.29133) (xy 224.988725 138.2776) (xy 224.988725 138.26387)
			(xy 224.988725 138.25014) (xy 224.988725 138.2364) (xy 224.988725 138.22267) (xy 224.988725 138.20894)
			(xy 224.988725 138.19521) (xy 224.988725 138.18148) (xy 224.988725 138.16775) (xy 224.988725 138.15401)
			(xy 224.988725 138.14028) (xy 224.988725 138.12655) (xy 224.988725 138.11282) (xy 224.988725 138.09909)
			(xy 224.988725 138.08536) (xy 224.988725 138.07162) (xy 224.988725 138.05789) (xy 224.988725 138.04416)
			(xy 224.988725 138.03043) (xy 224.988725 138.0167) (xy 224.988725 138.00296) (xy 224.988725 137.98923)
			(xy 224.988725 137.9755) (xy 224.988725 137.96177) (xy 224.988725 137.94804) (xy 224.988725 137.9343)
			(xy 224.988725 137.92057) (xy 224.988725 137.90684) (xy 224.988725 137.89311) (xy 224.988725 137.87938)
			(xy 224.988725 137.86565) (xy 224.988725 137.85191) (xy 224.988725 137.83818) (xy 224.988725 137.82445)
			(xy 224.988725 137.81072) (xy 224.988725 137.79699) (xy 224.988725 137.78326) (xy 224.974995 137.78326)
			(xy 224.974995 137.76952) (xy 224.974995 137.75579) (xy 224.974995 137.74206) (xy 224.974995 137.72833)
			(xy 224.961265 137.72833) (xy 224.961265 137.7146) (xy 224.961265 137.70087) (xy 224.947535 137.70087)
			(xy 224.947535 137.68713) (xy 224.933805 137.68713) (xy 224.933805 137.6734) (xy 224.920065 137.6734)
			(xy 224.920065 137.65967) (xy 224.906335 137.65967) (xy 224.906335 137.64594) (xy 224.892605 137.64594)
			(xy 224.892605 137.63221) (xy 224.878875 137.63221) (xy 224.878875 137.61848) (xy 224.865145 137.61848)
			(xy 224.865145 137.60474) (xy 224.851415 137.60474) (xy 224.851415 137.59101) (xy 224.837675 137.59101)
			(xy 224.837675 137.57728) (xy 224.823945 137.57728) (xy 224.823945 137.56355) (xy 224.810215 137.56355)
			(xy 224.810215 137.54982) (xy 224.796485 137.54982) (xy 224.796485 137.53609) (xy 224.782755 137.53609)
			(xy 224.782755 137.52235) (xy 224.769025 137.52235) (xy 224.769025 137.50862) (xy 224.755285 137.50862)
			(xy 224.755285 137.49489) (xy 224.741555 137.49489) (xy 224.741555 137.48116) (xy 224.727825 137.48116)
			(xy 224.727825 137.46743) (xy 224.714095 137.46743) (xy 224.714095 137.45369) (xy 224.700365 137.45369)
			(xy 224.700365 137.43996) (xy 224.686635 137.43996) (xy 224.686635 137.42623) (xy 224.672895 137.42623)
			(xy 224.672895 137.4125) (xy 224.659165 137.4125) (xy 224.659165 137.39877) (xy 224.645435 137.39877)
			(xy 224.645435 137.38503) (xy 224.631705 137.38503) (xy 224.631705 137.3713) (xy 224.617975 137.3713)
			(xy 224.617975 137.35757) (xy 224.604245 137.35757) (xy 224.604245 137.34384) (xy 224.590505 137.34384)
			(xy 224.590505 137.33011) (xy 224.576775 137.33011) (xy 224.576775 137.31638) (xy 224.563045 137.31638)
			(xy 224.563045 137.30264) (xy 224.549315 137.30264) (xy 224.549315 137.28891) (xy 224.508115 137.28891)
			(xy 224.508115 137.27518) (xy 224.439455 137.27518) (xy 224.439455 137.26145) (xy 222.544475 137.26145)
			(xy 222.544475 137.27518) (xy 222.517015 137.27518) (xy 222.517015 137.28891) (xy 222.503285 137.28891)
			(xy 222.503285 137.30264) (xy 222.489555 137.30264) (xy 222.489555 137.31638) (xy 222.475815 137.31638)
			(xy 221.665645 137.31638) (xy 221.651915 137.31638) (xy 221.651915 137.30264) (xy 221.624445 137.30264)
			(xy 221.624445 137.28891) (xy 221.583255 137.28891) (xy 221.583255 137.27518) (xy 221.514595 137.27518)
			(xy 221.514595 137.26145) (xy 219.619615 137.26145) (xy 219.619615 137.27518) (xy 219.592145 137.27518)
			(xy 219.592145 137.28891) (xy 219.578415 137.28891) (xy 219.578415 137.30264) (xy 219.564685 137.30264)
			(xy 219.564685 137.31638) (xy 219.564685 137.33011) (xy 219.564685 137.34384) (xy 219.550955 137.34384)
			(xy 218.891835 137.34384) (xy 218.878095 137.34384) (xy 218.878095 137.33011) (xy 218.864365 137.33011)
			(xy 218.864365 137.31638) (xy 218.850635 137.31638) (xy 218.850635 137.30264) (xy 218.823175 137.30264)
			(xy 218.823175 137.28891) (xy 218.795705 137.28891) (xy 218.795705 137.27518) (xy 218.740785 137.27518)
			(xy 218.740785 137.26145) (xy 218.548535 137.26145) (xy 218.548535 137.27518) (xy 218.534805 137.27518)
			(xy 218.534805 137.28891) (xy 218.521075 137.28891) (xy 218.521075 137.30264) (xy 218.507345 137.30264)
			(xy 218.507345 137.31638) (xy 218.493615 137.31638) (xy 218.493615 137.33011) (xy 218.479875 137.33011)
			(xy 218.479875 137.34384) (xy 218.466145 137.34384) (xy 218.466145 137.35757) (xy 218.452415 137.35757)
			(xy 218.452415 137.3713) (xy 218.438685 137.3713) (xy 218.438685 137.38503) (xy 218.424955 137.38503)
			(xy 218.424955 137.39877) (xy 218.411225 137.39877) (xy 218.411225 137.4125) (xy 218.397485 137.4125)
			(xy 218.397485 137.42623) (xy 218.383755 137.42623) (xy 218.383755 137.43996) (xy 218.370025 137.43996)
			(xy 218.370025 137.45369) (xy 218.356295 137.45369) (xy 218.356295 137.46743) (xy 218.342565 137.46743)
			(xy 218.342565 137.48116) (xy 218.328835 137.48116) (xy 218.328835 137.49489) (xy 218.315095 137.49489)
			(xy 218.315095 137.50862) (xy 218.301365 137.50862) (xy 218.301365 137.52235) (xy 218.287635 137.52235)
			(xy 218.287635 137.53609) (xy 218.273905 137.53609) (xy 218.273905 137.54982) (xy 218.260175 137.54982)
			(xy 218.260175 137.56355) (xy 218.246445 137.56355) (xy 218.246445 137.57728) (xy 218.232705 137.57728)
			(xy 218.232705 137.59101) (xy 218.218975 137.59101) (xy 218.218975 137.60474) (xy 218.205245 137.60474)
			(xy 218.205245 137.61848) (xy 218.191515 137.61848) (xy 218.191515 137.63221) (xy 218.177785 137.63221)
			(xy 218.177785 137.64594) (xy 218.164045 137.64594) (xy 218.164045 137.65967) (xy 218.150315 137.65967)
			(xy 218.150315 137.6734) (xy 218.136585 137.6734) (xy 218.136585 137.68713) (xy 218.122855 137.68713)
			(xy 218.122855 137.70087) (xy 218.109125 137.70087) (xy 218.109125 137.7146) (xy 218.095385 137.7146)
			(xy 218.095385 137.72833) (xy 218.081655 137.72833) (xy 218.081655 137.74206) (xy 218.067925 137.74206)
			(xy 218.067925 137.75579) (xy 218.054195 137.75579) (xy 218.054195 137.76952) (xy 218.040465 137.76952)
			(xy 218.040465 137.78326) (xy 218.026735 137.78326) (xy 218.026735 137.79699) (xy 218.012995 137.79699)
			(xy 218.012995 137.81072) (xy 217.999265 137.81072) (xy 217.999265 137.82445) (xy 217.985535 137.82445)
			(xy 217.985535 137.83818) (xy 217.971805 137.83818) (xy 217.971805 137.85191) (xy 217.958075 137.85191)
			(xy 217.958075 137.86565) (xy 217.944345 137.86565) (xy 217.944345 137.87938) (xy 217.930605 137.87938)
			(xy 217.930605 137.89311) (xy 217.916875 137.89311) (xy 217.916875 137.90684) (xy 217.903145 137.90684)
			(xy 217.903145 137.92057) (xy 217.889415 137.92057) (xy 217.889415 137.9343) (xy 218.507345 137.9343)
			(xy 218.507345 137.94804) (xy 218.507345 137.96177) (xy 218.507345 137.9755) (xy 218.507345 137.98923)
			(xy 218.507345 138.00296) (xy 218.507345 138.0167) (xy 218.507345 138.03043) (xy 218.507345 138.04416)
			(xy 218.507345 138.05789) (xy 218.507345 138.07162) (xy 218.507345 138.08536) (xy 218.507345 138.09909)
			(xy 218.507345 138.11282) (xy 218.507345 138.12655) (xy 218.507345 138.14028) (xy 218.507345 138.15401)
			(xy 218.507345 138.16775) (xy 218.507345 138.18148) (xy 218.507345 138.19521) (xy 218.507345 138.20894)
			(xy 218.507345 138.22267) (xy 218.507345 138.2364) (xy 218.507345 138.25014) (xy 218.507345 138.26387)
			(xy 218.507345 138.2776) (xy 218.507345 138.29133) (xy 218.507345 138.30506) (xy 218.507345 138.31879)
			(xy 218.507345 138.33253) (xy 218.507345 138.34626) (xy 218.507345 138.35999) (xy 218.507345 138.37372)
			(xy 218.507345 138.38745) (xy 218.507345 138.40118) (xy 218.507345 138.41492) (xy 218.507345 138.42865)
			(xy 218.507345 138.44238) (xy 218.507345 138.45611) (xy 218.507345 138.46984) (xy 218.507345 138.48358)
			(xy 218.507345 138.49731) (xy 218.507345 138.51104) (xy 218.507345 138.52477) (xy 218.507345 138.5385)
			(xy 218.507345 138.55224) (xy 218.507345 138.56597) (xy 218.507345 138.5797) (xy 218.507345 138.59343)
			(xy 218.507345 138.60716) (xy 218.507345 138.62089) (xy 218.507345 138.63463) (xy 218.507345 138.64836)
			(xy 218.507345 138.66209) (xy 218.507345 138.67582) (xy 218.507345 138.68955) (xy 217.504925 138.68955)
			(xy 217.504925 138.67582) (xy 217.504925 138.66209) (xy 217.504925 138.64836) (xy 217.504925 138.63463)
			(xy 217.504925 138.62089) (xy 217.504925 138.60716) (xy 217.504925 138.59343) (xy 217.504925 138.5797)
			(xy 217.504925 138.56597) (xy 217.504925 138.55224) (xy 217.504925 138.5385) (xy 217.504925 138.52477)
			(xy 217.504925 138.51104) (xy 217.504925 138.49731) (xy 217.504925 138.48358) (xy 217.504925 138.46984)
			(xy 217.504925 138.45611) (xy 217.504925 138.44238) (xy 217.504925 138.42865) (xy 217.504925 138.41492)
			(xy 217.504925 138.40118) (xy 217.504925 138.38745) (xy 217.491195 138.38745) (xy 217.491195 138.40118)
			(xy 217.477465 138.40118) (xy 217.477465 138.41492) (xy 217.463725 138.41492) (xy 217.463725 138.42865)
			(xy 217.449995 138.42865) (xy 217.449995 138.44238) (xy 217.436265 138.44238) (xy 217.436265 138.45611)
			(xy 217.422535 138.45611) (xy 217.422535 138.46984) (xy 217.408805 138.46984) (xy 217.408805 138.48358)
			(xy 217.395075 138.48358) (xy 217.395075 138.49731) (xy 217.381335 138.49731) (xy 217.381335 138.51104)
			(xy 217.367605 138.51104) (xy 217.367605 138.52477) (xy 217.353875 138.52477) (xy 217.353875 138.5385)
			(xy 217.340145 138.5385) (xy 217.340145 138.55224) (xy 217.326415 138.55224) (xy 217.326415 138.56597)
			(xy 217.312685 138.56597) (xy 217.312685 138.5797) (xy 217.298945 138.5797) (xy 217.298945 138.59343)
			(xy 217.285215 138.59343) (xy 217.285215 138.60716) (xy 217.271485 138.60716) (xy 217.271485 138.62089)
			(xy 217.257755 138.62089) (xy 217.257755 138.63463) (xy 217.244025 138.63463) (xy 217.244025 138.64836)
			(xy 217.230295 138.64836) (xy 217.230295 138.66209) (xy 217.216555 138.66209) (xy 217.216555 138.67582)
			(xy 217.202825 138.67582) (xy 217.202825 138.68955) (xy 217.189095 138.68955) (xy 217.189095 138.70328)
			(xy 217.175365 138.70328) (xy 217.175365 138.71702) (xy 217.161635 138.71702) (xy 217.161635 138.73075)
			(xy 217.147905 138.73075) (xy 217.147905 138.74448) (xy 217.134165 138.74448) (xy 217.134165 138.75821)
			(xy 217.120435 138.75821) (xy 217.120435 138.77194) (xy 217.106705 138.77194) (xy 217.106705 138.78567)
			(xy 217.092975 138.78567) (xy 217.092975 138.79941) (xy 217.079245 138.79941) (xy 217.079245 138.81314)
			(xy 217.065505 138.81314) (xy 217.065505 138.82687) (xy 217.051775 138.82687) (xy 217.051775 138.8406)
			(xy 217.038045 138.8406) (xy 217.038045 138.85433) (xy 217.024315 138.85433) (xy 217.024315 138.86806)
			(xy 217.010585 138.86806) (xy 217.010585 138.8818) (xy 216.996845 138.8818) (xy 216.996845 138.89553)
			(xy 216.983115 138.89553) (xy 216.983115 138.90926) (xy 216.969385 138.90926) (xy 216.969385 138.92299)
			(xy 216.955655 138.92299) (xy 216.955655 138.93672) (xy 216.941925 138.93672) (xy 216.941925 138.95045)
			(xy 216.928195 138.95045) (xy 216.928195 138.96419) (xy 216.914455 138.96419) (xy 216.914455 138.97792)
			(xy 216.900725 138.97792) (xy 216.900725 138.99165) (xy 216.886995 138.99165) (xy 216.886995 139.00538)
			(xy 216.873265 139.00538) (xy 216.873265 139.01911) (xy 216.859535 139.01911) (xy 216.859535 139.03285)
			(xy 216.832065 139.03285) (xy 216.832065 139.04658) (xy 216.818335 139.04658) (xy 216.818335 139.06031)
			(xy 216.804605 139.06031) (xy 216.804605 139.07404) (xy 216.790875 139.07404) (xy 216.790875 139.08777)
			(xy 216.777145 139.08777) (xy 216.777145 139.10151) (xy 216.763415 139.10151) (xy 216.763415 139.11524)
			(xy 216.749675 139.11524) (xy 216.392655 139.11524) (xy 216.392655 139.10151) (xy 216.406385 139.10151)
			(xy 216.406385 139.08777) (xy 216.420115 139.08777) (xy 216.420115 139.07404) (xy 216.433845 139.07404)
			(xy 216.433845 139.06031) (xy 216.447575 139.06031) (xy 216.447575 139.04658) (xy 216.461315 139.04658)
			(xy 216.461315 139.03285) (xy 216.475045 139.03285) (xy 216.475045 139.01911) (xy 216.488775 139.01911)
			(xy 216.488775 139.00538) (xy 216.502505 139.00538) (xy 216.502505 138.99165) (xy 216.516235 138.99165)
			(xy 216.516235 138.97792) (xy 216.529965 138.97792) (xy 216.529965 138.96419) (xy 216.543705 138.96419)
			(xy 216.543705 138.95045) (xy 216.557435 138.95045) (xy 216.557435 138.93672) (xy 216.571165 138.93672)
			(xy 216.571165 138.92299) (xy 216.584895 138.92299) (xy 216.584895 138.90926) (xy 216.598625 138.90926)
			(xy 216.598625 138.89553) (xy 216.626095 138.89553) (xy 216.626095 138.8818) (xy 216.639825 138.8818)
			(xy 216.639825 138.86806) (xy 216.653555 138.86806) (xy 216.653555 138.85433) (xy 216.667285 138.85433)
			(xy 216.667285 138.8406) (xy 216.681025 138.8406) (xy 216.681025 138.82687) (xy 216.694755 138.82687)
			(xy 216.694755 138.81314) (xy 216.708485 138.81314) (xy 216.708485 138.79941) (xy 216.722215 138.79941)
			(xy 216.722215 138.78567) (xy 216.735945 138.78567) (xy 216.735945 138.77194) (xy 216.749675 138.77194)
			(xy 216.749675 138.75821) (xy 216.763415 138.75821) (xy 216.763415 138.74448) (xy 216.777145 138.74448)
			(xy 216.777145 138.73075) (xy 216.790875 138.73075) (xy 216.790875 138.71702) (xy 216.804605 138.71702)
			(xy 216.804605 138.70328) (xy 216.818335 138.70328) (xy 216.818335 138.68955) (xy 216.832065 138.68955)
			(xy 216.832065 138.67582) (xy 216.845805 138.67582) (xy 216.845805 138.66209) (xy 216.859535 138.66209)
			(xy 216.859535 138.64836) (xy 216.873265 138.64836) (xy 216.873265 138.63463) (xy 216.886995 138.63463)
			(xy 216.886995 138.62089) (xy 216.900725 138.62089) (xy 216.900725 138.60716) (xy 216.914455 138.60716)
			(xy 216.914455 138.59343) (xy 216.928195 138.59343) (xy 216.928195 138.5797) (xy 216.941925 138.5797)
			(xy 216.941925 138.56597) (xy 216.955655 138.56597) (xy 216.955655 138.55224) (xy 216.969385 138.55224)
			(xy 216.969385 138.5385) (xy 216.983115 138.5385) (xy 216.983115 138.52477) (xy 216.996845 138.52477)
			(xy 216.996845 138.51104) (xy 217.010585 138.51104) (xy 217.010585 138.49731) (xy 217.024315 138.49731)
			(xy 217.024315 138.48358) (xy 217.038045 138.48358) (xy 217.038045 138.46984) (xy 217.051775 138.46984)
			(xy 217.051775 138.45611) (xy 217.065505 138.45611) (xy 217.065505 138.44238) (xy 217.079245 138.44238)
			(xy 217.079245 138.42865) (xy 217.092975 138.42865) (xy 217.092975 138.41492) (xy 217.106705 138.41492)
			(xy 217.106705 138.40118) (xy 217.120435 138.40118) (xy 217.120435 138.38745) (xy 217.134165 138.38745)
			(xy 217.134165 138.37372) (xy 217.147905 138.37372) (xy 217.147905 138.35999) (xy 217.161635 138.35999)
			(xy 217.161635 138.34626) (xy 217.175365 138.34626) (xy 217.175365 138.33253) (xy 217.189095 138.33253)
			(xy 217.189095 138.31879) (xy 217.202825 138.31879) (xy 217.202825 138.30506) (xy 217.216555 138.30506)
			(xy 217.216555 138.29133) (xy 217.230295 138.29133) (xy 217.230295 138.2776) (xy 217.244025 138.2776)
			(xy 217.244025 138.26387) (xy 217.257755 138.26387) (xy 217.257755 138.25014) (xy 217.271485 138.25014)
			(xy 217.271485 138.2364) (xy 217.285215 138.2364) (xy 217.285215 138.22267) (xy 217.298945 138.22267)
			(xy 217.298945 138.20894) (xy 217.312685 138.20894) (xy 217.312685 138.19521) (xy 217.326415 138.19521)
			(xy 217.326415 138.18148) (xy 217.340145 138.18148) (xy 217.340145 138.16775) (xy 217.353875 138.16775)
			(xy 217.353875 138.15401) (xy 217.367605 138.15401) (xy 217.367605 138.14028) (xy 217.381335 138.14028)
			(xy 217.381335 138.12655) (xy 217.395075 138.12655) (xy 217.395075 138.11282) (xy 217.408805 138.11282)
			(xy 217.408805 138.09909) (xy 217.422535 138.09909) (xy 217.422535 138.08536) (xy 217.436265 138.08536)
			(xy 217.436265 138.07162) (xy 217.449995 138.07162) (xy 217.449995 138.05789) (xy 217.463725 138.05789)
			(xy 217.463725 138.04416) (xy 217.477465 138.04416) (xy 217.477465 138.03043) (xy 217.491195 138.03043)
			(xy 217.491195 138.0167) (xy 217.504925 138.0167) (xy 217.504925 138.00296) (xy 217.518655 138.00296)
			(xy 217.518655 137.98923) (xy 217.532385 137.98923) (xy 217.532385 137.9755) (xy 217.546115 137.9755)
			(xy 217.546115 137.96177) (xy 217.559855 137.96177) (xy 217.559855 137.94804) (xy 217.573585 137.94804)
			(xy 217.573585 137.9343) (xy 217.587315 137.9343) (xy 217.587315 137.92057) (xy 217.601045 137.92057)
			(xy 217.601045 137.90684) (xy 217.614775 137.90684) (xy 217.614775 137.89311) (xy 217.628515 137.89311)
			(xy 217.628515 137.87938) (xy 217.642245 137.87938) (xy 217.642245 137.86565) (xy 217.655975 137.86565)
			(xy 217.655975 137.85191) (xy 217.669705 137.85191) (xy 217.669705 137.83818) (xy 217.683435 137.83818)
			(xy 217.683435 137.82445) (xy 217.697175 137.82445) (xy 217.697175 137.81072) (xy 217.710905 137.81072)
			(xy 217.710905 137.79699) (xy 217.724635 137.79699) (xy 217.724635 137.78326) (xy 217.738365 137.78326)
			(xy 217.738365 137.76952) (xy 217.752095 137.76952) (xy 217.752095 137.75579) (xy 217.765825 137.75579)
			(xy 217.765825 137.74206) (xy 217.793295 137.74206) (xy 217.793295 137.72833) (xy 217.807025 137.72833)
			(xy 217.807025 137.7146) (xy 217.820755 137.7146) (xy 217.820755 137.70087) (xy 217.834485 137.70087)
			(xy 217.834485 137.68713) (xy 217.848215 137.68713) (xy 217.848215 137.6734) (xy 217.861955 137.6734)
			(xy 217.861955 137.65967) (xy 217.875685 137.65967) (xy 217.875685 137.64594) (xy 217.889415 137.64594)
			(xy 217.889415 137.63221) (xy 217.903145 137.63221) (xy 217.903145 137.61848) (xy 217.916875 137.61848)
			(xy 217.916875 137.60474) (xy 217.930605 137.60474) (xy 217.930605 137.59101) (xy 217.944345 137.59101)
			(xy 217.944345 137.57728) (xy 217.958075 137.57728) (xy 217.958075 137.56355) (xy 217.971805 137.56355)
			(xy 217.971805 137.54982) (xy 217.985535 137.54982) (xy 217.985535 137.53609) (xy 217.999265 137.53609)
			(xy 217.999265 137.52235) (xy 218.012995 137.52235) (xy 218.012995 137.50862) (xy 218.026735 137.50862)
			(xy 218.026735 137.49489) (xy 218.040465 137.49489) (xy 218.040465 137.48116) (xy 218.054195 137.48116)
			(xy 218.054195 137.46743) (xy 218.067925 137.46743) (xy 218.067925 137.45369) (xy 218.081655 137.45369)
			(xy 218.081655 137.43996) (xy 218.095385 137.43996) (xy 218.095385 137.42623) (xy 218.109125 137.42623)
			(xy 218.109125 137.4125) (xy 218.122855 137.4125) (xy 218.122855 137.39877) (xy 218.136585 137.39877)
			(xy 218.136585 137.38503) (xy 218.150315 137.38503) (xy 218.150315 137.3713) (xy 218.164045 137.3713)
			(xy 218.164045 137.35757) (xy 218.177785 137.35757) (xy 218.177785 137.34384) (xy 218.191515 137.34384)
			(xy 218.191515 137.33011) (xy 218.205245 137.33011) (xy 218.205245 137.31638) (xy 218.205245 137.30264)
			(xy 218.218975 137.30264) (xy 218.218975 137.28891) (xy 218.232705 137.28891) (xy 218.232705 137.27518)
			(xy 218.232705 137.26145) (xy 218.246445 137.26145) (xy 218.246445 137.24772) (xy 218.246445 137.23399)
			(xy 218.260175 137.23399) (xy 218.260175 137.22025) (xy 218.260175 137.20652) (xy 218.273905 137.20652)
			(xy 218.273905 137.19279) (xy 218.273905 137.17906) (xy 218.273905 137.16533) (xy 218.273905 137.1516)
			(xy 218.287635 137.1516) (xy 218.287635 137.13786) (xy 218.287635 137.12413) (xy 218.287635 137.1104)
			(xy 218.287635 137.09667) (xy 218.287635 137.08294) (xy 218.287635 137.06921) (xy 218.287635 137.05547)
			(xy 218.287635 137.04174) (xy 218.287635 137.02801) (xy 218.287635 137.01428) (xy 218.287635 137.00055)
			(xy 218.287635 136.98682) (xy 218.287635 136.97308) (xy 218.287635 136.95935) (xy 218.287635 136.94562)
			(xy 218.287635 136.93189) (xy 218.287635 136.91816) (xy 218.287635 136.90442) (xy 218.287635 136.89069)
			(xy 218.287635 136.87696) (xy 218.287635 136.86323) (xy 218.287635 136.8495) (xy 218.287635 136.83576)
			(xy 218.287635 136.82203) (xy 218.287635 136.8083) (xy 218.287635 136.79457) (xy 218.287635 136.78084)
			(xy 218.287635 136.76711) (xy 218.287635 136.75337) (xy 218.287635 136.73964) (xy 218.287635 136.72591)
			(xy 218.287635 136.71218) (xy 218.287635 136.69845) (xy 218.287635 136.68472) (xy 218.287635 136.67098)
			(xy 218.287635 136.65725) (xy 218.287635 136.64352) (xy 218.287635 136.62979) (xy 218.287635 136.61606)
			(xy 218.287635 136.60233) (xy 218.287635 136.58859) (xy 218.287635 136.57486) (xy 218.287635 136.56113)
			(xy 218.287635 136.5474) (xy 218.287635 136.53367) (xy 218.287635 136.51994) (xy 218.287635 136.5062)
			(xy 218.287635 136.49247) (xy 218.287635 136.47874) (xy 218.287635 136.46501) (xy 218.287635 136.45128)
			(xy 218.287635 136.43755) (xy 218.287635 136.42381) (xy 218.287635 136.41008) (xy 218.287635 136.39635)
			(xy 218.287635 136.38262) (xy 218.287635 136.36889) (xy 218.287635 136.35515) (xy 218.287635 136.34142)
			(xy 218.287635 136.32769) (xy 218.287635 136.31396) (xy 218.287635 136.30023) (xy 218.287635 136.28649)
			(xy 218.287635 136.27276) (xy 218.287635 136.25903) (xy 218.287635 136.2453) (xy 218.287635 136.23157)
			(xy 218.287635 136.21784) (xy 218.287635 136.2041) (xy 218.287635 136.19037) (xy 218.287635 136.17664)
			(xy 218.287635 136.16291) (xy 218.287635 136.14918) (xy 218.287635 136.13545) (xy 218.287635 136.12171)
			(xy 218.287635 136.10798) (xy 218.287635 136.09425) (xy 218.287635 136.08052) (xy 218.287635 136.06679)
			(xy 218.287635 136.05306) (xy 218.287635 136.03932) (xy 218.287635 136.02559) (xy 218.287635 136.01186)
			(xy 218.287635 135.99813) (xy 218.287635 135.9844) (xy 218.287635 135.97067) (xy 218.287635 135.95693)
			(xy 218.287635 135.9432) (xy 218.287635 135.92947) (xy 218.287635 135.91574) (xy 218.287635 135.90201)
			(xy 218.287635 135.88827) (xy 218.287635 135.87454) (xy 218.287635 135.86081) (xy 218.287635 135.84708)
			(xy 218.287635 135.83335) (xy 218.287635 135.81961) (xy 218.287635 135.80588) (xy 218.287635 135.79215)
			(xy 218.287635 135.77842) (xy 218.287635 135.76469) (xy 218.287635 135.75096) (xy 218.287635 135.73722)
			(xy 218.287635 135.72349) (xy 218.287635 135.70976) (xy 218.287635 135.69603) (xy 218.287635 135.6823)
			(xy 218.287635 135.66857) (xy 218.287635 135.65483) (xy 218.287635 135.6411) (xy 218.287635 135.62737)
			(xy 218.287635 135.61364) (xy 218.287635 135.59991) (xy 218.287635 135.58618) (xy 218.287635 135.57244)
			(xy 218.287635 135.55871) (xy 218.287635 135.54498) (xy 218.287635 135.53125) (xy 218.287635 135.51752)
			(xy 218.287635 135.50379) (xy 218.287635 135.49005) (xy 218.287635 135.47632) (xy 218.287635 135.46259)
			(xy 218.287635 135.44886) (xy 218.287635 135.43513) (xy 218.287635 135.4214) (xy 218.287635 135.40766)
			(xy 218.287635 135.39393) (xy 218.287635 135.3802) (xy 218.287635 135.36647) (xy 218.287635 135.35274)
			(xy 218.287635 135.339) (xy 218.287635 135.32527) (xy 218.287635 135.31154) (xy 218.287635 135.29781)
			(xy 218.287635 135.28408) (xy 218.287635 135.27034) (xy 218.287635 135.25661) (xy 218.287635 135.24288)
			(xy 218.287635 135.22915) (xy 218.287635 135.21542) (xy 218.287635 135.20169) (xy 218.287635 135.18795)
			(xy 218.287635 135.17422) (xy 218.287635 135.16049) (xy 218.287635 135.14676) (xy 218.287635 135.13303)
			(xy 218.287635 135.1193) (xy 218.287635 135.10556) (xy 218.287635 135.09183) (xy 218.287635 135.0781)
			(xy 218.287635 135.06437) (xy 218.287635 135.05064) (xy 218.287635 135.03691) (xy 218.287635 135.02317)
			(xy 218.287635 135.00944) (xy 218.287635 134.99571) (xy 218.287635 134.98198) (xy 218.287635 134.96825)
			(xy 218.287635 134.95452) (xy 218.287635 134.94078) (xy 218.287635 134.92705) (xy 218.287635 134.91332)
			(xy 218.287635 134.89959) (xy 218.287635 134.88586) (xy 218.287635 134.87213) (xy 218.287635 134.85839)
			(xy 218.287635 134.84466) (xy 218.287635 134.83093) (xy 218.287635 134.8172) (xy 218.287635 134.80347)
			(xy 218.287635 134.78973) (xy 218.287635 134.776) (xy 218.287635 134.76227) (xy 218.287635 134.74854)
			(xy 218.287635 134.73481) (xy 218.287635 134.72107) (xy 218.287635 134.70734) (xy 218.287635 134.69361)
			(xy 218.287635 134.67988) (xy 218.287635 134.66615) (xy 218.287635 134.65242) (xy 218.287635 134.63868)
			(xy 218.287635 134.62495) (xy 218.287635 134.61122) (xy 218.287635 134.59749) (xy 218.287635 134.58376)
			(xy 218.287635 134.57003) (xy 218.617195 134.57003) (xy 218.617195 134.58376) (xy 218.617195 134.59749)
			(xy 218.617195 134.61122) (xy 218.617195 134.62495) (xy 218.617195 134.63868) (xy 218.617195 134.65242)
			(xy 218.617195 134.66615) (xy 218.617195 134.67988) (xy 218.617195 134.69361) (xy 218.617195 134.70734)
			(xy 218.617195 134.72107) (xy 218.617195 134.73481) (xy 218.617195 134.74854) (xy 218.617195 134.76227)
			(xy 218.617195 134.776) (xy 218.617195 134.78973) (xy 218.617195 134.80347) (xy 218.617195 134.8172)
			(xy 218.617195 134.83093) (xy 218.617195 134.84466) (xy 218.617195 134.85839) (xy 218.617195 134.87213)
			(xy 218.617195 134.88586) (xy 218.617195 134.89959) (xy 218.617195 134.91332) (xy 218.617195 134.92705)
			(xy 218.617195 134.94078) (xy 218.617195 134.95452) (xy 218.617195 134.96825) (xy 218.617195 134.98198)
			(xy 218.617195 134.99571) (xy 218.617195 135.00944) (xy 218.617195 135.02317) (xy 218.617195 135.03691)
			(xy 218.617195 135.05064) (xy 218.617195 135.06437) (xy 218.617195 135.0781) (xy 218.617195 135.09183)
			(xy 218.617195 135.10556) (xy 218.617195 135.1193) (xy 218.617195 135.13303) (xy 218.617195 135.14676)
			(xy 218.617195 135.16049) (xy 218.617195 135.17422) (xy 218.617195 135.18795) (xy 218.617195 135.20169)
			(xy 218.617195 135.21542) (xy 218.617195 135.22915) (xy 218.617195 135.24288) (xy 218.617195 135.25661)
			(xy 218.617195 135.27034) (xy 218.617195 135.28408) (xy 218.617195 135.29781) (xy 218.617195 135.31154)
			(xy 218.617195 135.32527) (xy 218.617195 135.339) (xy 218.617195 135.35274) (xy 218.617195 135.36647)
			(xy 218.617195 135.3802) (xy 218.617195 135.39393) (xy 218.617195 135.40766) (xy 218.617195 135.4214)
			(xy 218.617195 135.43513) (xy 218.617195 135.44886) (xy 218.617195 135.46259) (xy 218.617195 135.47632)
			(xy 218.617195 135.49005) (xy 218.617195 135.50379) (xy 218.617195 135.51752) (xy 218.617195 135.53125)
			(xy 218.617195 135.54498) (xy 218.617195 135.55871) (xy 218.617195 135.57244) (xy 218.617195 135.58618)
			(xy 218.617195 135.59991) (xy 218.617195 135.61364) (xy 218.617195 135.62737) (xy 218.617195 135.6411)
			(xy 218.617195 135.65483) (xy 218.617195 135.66857) (xy 218.617195 135.6823) (xy 218.617195 135.69603)
			(xy 218.617195 135.70976) (xy 218.617195 135.72349) (xy 218.617195 135.73722) (xy 218.617195 135.75096)
			(xy 218.617195 135.76469) (xy 218.617195 135.77842) (xy 218.617195 135.79215) (xy 218.617195 135.80588)
			(xy 218.617195 135.81961) (xy 218.617195 135.83335) (xy 218.617195 135.84708) (xy 218.617195 135.86081)
			(xy 218.617195 135.87454) (xy 218.617195 135.88827) (xy 218.617195 135.90201) (xy 218.617195 135.91574)
			(xy 218.617195 135.92947) (xy 218.617195 135.9432) (xy 218.617195 135.95693) (xy 218.617195 135.97067)
			(xy 218.617195 135.9844) (xy 218.617195 135.99813) (xy 218.617195 136.01186) (xy 218.617195 136.02559)
			(xy 218.617195 136.03932) (xy 218.617195 136.05306) (xy 218.617195 136.06679) (xy 218.617195 136.08052)
			(xy 218.617195 136.09425) (xy 218.617195 136.10798) (xy 218.617195 136.12171) (xy 218.617195 136.13545)
			(xy 218.617195 136.14918) (xy 218.617195 136.16291) (xy 218.617195 136.17664) (xy 218.617195 136.19037)
			(xy 218.617195 136.2041) (xy 218.617195 136.21784) (xy 218.617195 136.23157) (xy 218.617195 136.2453)
			(xy 218.617195 136.25903) (xy 218.617195 136.27276) (xy 218.617195 136.28649) (xy 218.617195 136.30023)
			(xy 218.617195 136.31396) (xy 218.617195 136.32769) (xy 218.617195 136.34142) (xy 218.617195 136.35515)
			(xy 218.617195 136.36889) (xy 218.617195 136.38262) (xy 218.617195 136.39635) (xy 218.617195 136.41008)
			(xy 218.617195 136.42381) (xy 218.617195 136.43755) (xy 218.617195 136.45128) (xy 218.617195 136.46501)
			(xy 218.617195 136.47874) (xy 218.630925 136.47874) (xy 218.630925 136.49247) (xy 218.630925 136.5062)
			(xy 218.630925 136.51994) (xy 218.630925 136.53367) (xy 218.630925 136.5474) (xy 218.644655 136.5474)
			(xy 218.644655 136.56113) (xy 218.644655 136.57486) (xy 218.658395 136.57486) (xy 218.658395 136.58859)
			(xy 218.658395 136.60233) (xy 218.672125 136.60233) (xy 218.672125 136.61606) (xy 218.685855 136.61606)
			(xy 218.685855 136.62979) (xy 218.699585 136.62979) (xy 218.699585 136.64352) (xy 218.713315 136.64352)
			(xy 218.713315 136.65725) (xy 218.727055 136.65725) (xy 218.727055 136.67098) (xy 218.740785 136.67098)
			(xy 218.740785 136.68472) (xy 218.754515 136.68472) (xy 218.754515 136.69845) (xy 218.768245 136.69845)
			(xy 218.768245 136.71218) (xy 218.781975 136.71218) (xy 218.781975 136.72591) (xy 218.795705 136.72591)
			(xy 218.795705 136.73964) (xy 218.809445 136.73964) (xy 218.809445 136.75337) (xy 218.823175 136.75337)
			(xy 218.823175 136.76711) (xy 218.836905 136.76711) (xy 218.836905 136.78084) (xy 218.850635 136.78084)
			(xy 218.850635 136.79457) (xy 218.864365 136.79457) (xy 218.864365 136.8083) (xy 218.878095 136.8083)
			(xy 218.878095 136.82203) (xy 218.891835 136.82203) (xy 218.891835 136.83576) (xy 218.905565 136.83576)
			(xy 218.905565 136.8495) (xy 218.919295 136.8495) (xy 218.919295 136.86323) (xy 218.933025 136.86323)
			(xy 218.933025 136.87696) (xy 218.946755 136.87696) (xy 218.946755 136.89069) (xy 218.960485 136.89069)
			(xy 218.960485 136.90442) (xy 218.974225 136.90442) (xy 218.974225 136.91816) (xy 218.987955 136.91816)
			(xy 218.987955 136.93189) (xy 219.001685 136.93189) (xy 219.001685 136.94562) (xy 219.015415 136.94562)
			(xy 219.015415 136.95935) (xy 219.029145 136.95935) (xy 219.029145 136.97308) (xy 219.042875 136.97308)
			(xy 219.042875 136.98682) (xy 219.070345 136.98682) (xy 219.070345 137.00055) (xy 219.125265 137.00055)
			(xy 219.125265 137.01428) (xy 220.869205 137.01428) (xy 220.869205 137.00055) (xy 220.882935 137.00055)
			(xy 220.882935 136.98682) (xy 220.896665 136.98682) (xy 220.896665 136.97308) (xy 220.896665 136.95935)
			(xy 220.910395 136.95935) (xy 220.910395 136.94562) (xy 220.910395 136.93189) (xy 220.910395 136.91816)
			(xy 220.910395 136.90442) (xy 220.910395 136.89069) (xy 220.910395 136.87696) (xy 220.910395 136.86323)
			(xy 220.910395 136.8495) (xy 220.910395 136.83576) (xy 220.910395 136.82203) (xy 220.910395 136.8083)
			(xy 220.910395 136.79457) (xy 220.910395 136.78084) (xy 220.910395 136.76711) (xy 220.910395 136.75337)
			(xy 220.910395 136.73964) (xy 220.910395 136.72591) (xy 220.910395 136.71218) (xy 220.910395 136.69845)
			(xy 220.910395 136.68472) (xy 220.910395 136.67098) (xy 220.910395 136.65725) (xy 220.910395 136.64352)
			(xy 220.910395 136.62979) (xy 220.910395 136.61606) (xy 220.910395 136.60233) (xy 220.910395 136.58859)
			(xy 220.910395 136.57486) (xy 220.910395 136.56113) (xy 220.910395 136.5474) (xy 220.910395 136.53367)
			(xy 220.910395 136.51994) (xy 220.910395 136.5062) (xy 220.910395 136.49247) (xy 220.910395 136.47874)
			(xy 220.910395 136.46501) (xy 220.910395 136.45128) (xy 220.910395 136.43755) (xy 220.910395 136.42381)
			(xy 220.910395 136.41008) (xy 220.910395 136.39635) (xy 220.910395 136.38262) (xy 220.910395 136.36889)
			(xy 220.896665 136.36889) (xy 220.896665 136.35515) (xy 220.896665 136.34142) (xy 220.882935 136.34142)
			(xy 220.882935 136.32769) (xy 220.855475 136.32769) (xy 220.855475 136.31396) (xy 219.386175 136.31396)
			(xy 219.386175 136.30023) (xy 219.372445 136.30023) (xy 219.372445 136.28649) (xy 219.372445 136.27276)
			(xy 219.372445 136.25903) (xy 219.372445 136.2453) (xy 219.372445 136.23157) (xy 219.372445 136.21784)
			(xy 219.372445 136.2041) (xy 219.372445 136.19037) (xy 219.372445 136.17664) (xy 219.372445 136.16291)
			(xy 219.372445 136.14918) (xy 219.372445 136.13545) (xy 219.372445 136.12171) (xy 219.372445 136.10798)
			(xy 219.372445 136.09425) (xy 219.372445 136.08052) (xy 219.372445 136.06679) (xy 219.372445 136.05306)
			(xy 219.372445 136.03932) (xy 219.372445 136.02559) (xy 219.372445 136.01186) (xy 219.372445 135.99813)
			(xy 219.372445 135.9844) (xy 219.372445 135.97067) (xy 219.372445 135.95693) (xy 219.372445 135.9432)
			(xy 219.372445 135.92947) (xy 219.372445 135.91574) (xy 219.372445 135.90201) (xy 219.372445 135.88827)
			(xy 219.372445 135.87454) (xy 219.372445 135.86081) (xy 219.372445 135.84708) (xy 219.372445 135.83335)
			(xy 219.386175 135.83335) (xy 219.386175 135.81961) (xy 220.649495 135.81961) (xy 220.649495 135.80588)
			(xy 220.676955 135.80588) (xy 220.676955 135.79215) (xy 220.676955 135.77842) (xy 220.690685 135.77842)
			(xy 220.690685 135.76469) (xy 220.690685 135.75096) (xy 220.690685 135.73722) (xy 220.690685 135.72349)
			(xy 220.690685 135.70976) (xy 220.690685 135.69603) (xy 220.690685 135.6823) (xy 220.690685 135.66857)
			(xy 220.690685 135.65483) (xy 220.690685 135.6411) (xy 220.690685 135.62737) (xy 220.690685 135.61364)
			(xy 220.690685 135.59991) (xy 220.690685 135.58618) (xy 220.690685 135.57244) (xy 220.690685 135.55871)
			(xy 220.690685 135.54498) (xy 220.690685 135.53125) (xy 220.690685 135.51752) (xy 220.690685 135.50379)
			(xy 220.690685 135.49005) (xy 220.690685 135.47632) (xy 220.690685 135.46259) (xy 220.690685 135.44886)
			(xy 220.690685 135.43513) (xy 220.690685 135.4214) (xy 220.690685 135.40766) (xy 220.690685 135.39393)
			(xy 220.690685 135.3802) (xy 220.690685 135.36647) (xy 220.690685 135.35274) (xy 220.690685 135.339)
			(xy 220.690685 135.32527) (xy 220.690685 135.31154) (xy 220.690685 135.29781) (xy 220.690685 135.28408)
			(xy 220.690685 135.27034) (xy 220.676955 135.27034) (xy 220.676955 135.25661) (xy 220.676955 135.24288)
			(xy 220.649495 135.24288) (xy 220.649495 135.22915) (xy 219.386175 135.22915) (xy 219.386175 135.21542)
			(xy 219.372445 135.21542) (xy 219.372445 135.20169) (xy 219.372445 135.18795) (xy 219.372445 135.17422)
			(xy 219.372445 135.16049) (xy 219.372445 135.14676) (xy 219.372445 135.13303) (xy 219.372445 135.1193)
			(xy 219.372445 135.10556) (xy 219.372445 135.09183) (xy 219.372445 135.0781) (xy 219.372445 135.06437)
			(xy 219.372445 135.05064) (xy 219.372445 135.03691) (xy 219.372445 135.02317) (xy 219.372445 135.00944)
			(xy 219.372445 134.99571) (xy 219.372445 134.98198) (xy 219.372445 134.96825) (xy 219.372445 134.95452)
			(xy 219.372445 134.94078) (xy 219.372445 134.92705) (xy 219.372445 134.91332) (xy 219.372445 134.89959)
			(xy 219.372445 134.88586) (xy 219.372445 134.87213) (xy 219.372445 134.85839) (xy 219.372445 134.84466)
			(xy 219.372445 134.83093) (xy 219.372445 134.8172) (xy 219.372445 134.80347) (xy 219.372445 134.78973)
			(xy 219.372445 134.776) (xy 219.372445 134.76227) (xy 219.372445 134.74854) (xy 219.372445 134.73481)
			(xy 219.386175 134.73481) (xy 219.386175 134.72107) (xy 220.869205 134.72107) (xy 220.869205 134.70734)
			(xy 220.882935 134.70734) (xy 220.882935 134.69361) (xy 220.896665 134.69361) (xy 220.896665 134.67988)
			(xy 220.910395 134.67988) (xy 220.910395 134.66615) (xy 220.910395 134.65242) (xy 220.910395 134.63868)
			(xy 220.910395 134.62495) (xy 220.910395 134.61122) (xy 220.910395 134.59749) (xy 220.910395 134.58376)
			(xy 220.910395 134.57003) (xy 220.910395 134.55629) (xy 220.910395 134.54256) (xy 220.910395 134.52883)
			(xy 220.910395 134.5151) (xy 220.910395 134.50137) (xy 220.910395 134.48764) (xy 220.910395 134.4739)
			(xy 220.910395 134.46017) (xy 220.910395 134.44644) (xy 220.910395 134.43271) (xy 220.910395 134.41898)
			(xy 220.910395 134.40525) (xy 220.910395 134.39151) (xy 220.910395 134.37778) (xy 220.910395 134.36405)
			(xy 220.910395 134.35032) (xy 220.910395 134.33659) (xy 220.910395 134.32286) (xy 220.910395 134.30912)
			(xy 220.910395 134.29539) (xy 220.910395 134.28166) (xy 220.910395 134.26793) (xy 220.910395 134.2542)
			(xy 220.910395 134.24046) (xy 220.910395 134.22673) (xy 220.910395 134.213) (xy 220.910395 134.19927)
			(xy 220.910395 134.18554) (xy 220.910395 134.1718) (xy 220.910395 134.15807) (xy 220.910395 134.14434)
			(xy 220.910395 134.13061) (xy 220.910395 134.11688) (xy 220.910395 134.10315) (xy 220.910395 134.08941)
			(xy 220.896665 134.08941) (xy 220.896665 134.07568) (xy 220.896665 134.06195) (xy 220.882935 134.06195)
			(xy 220.882935 134.04822) (xy 220.869205 134.04822) (xy 220.869205 134.03449) (xy 220.841745 134.03449)
			(xy 220.841745 134.02076) (xy 220.800545 134.02076) (xy 220.800545 134.03449) (xy 220.786815 134.03449)
			(xy 220.786815 134.02076) (xy 219.180195 134.02076) (xy 219.180195 134.03449) (xy 219.111535 134.03449)
			(xy 219.111535 134.04822) (xy 219.070345 134.04822) (xy 219.070345 134.06195) (xy 219.042875 134.06195)
			(xy 219.042875 134.07568) (xy 219.029145 134.07568) (xy 219.029145 134.08941) (xy 219.015415 134.08941)
			(xy 219.015415 134.10315) (xy 219.001685 134.10315) (xy 219.001685 134.11688) (xy 218.987955 134.11688)
			(xy 218.987955 134.13061) (xy 218.974225 134.13061) (xy 218.974225 134.14434) (xy 218.960485 134.14434)
			(xy 218.960485 134.15807) (xy 218.946755 134.15807) (xy 218.946755 134.1718) (xy 218.933025 134.1718)
			(xy 218.933025 134.18554) (xy 218.919295 134.18554) (xy 218.919295 134.19927) (xy 218.905565 134.19927)
			(xy 218.905565 134.213) (xy 218.891835 134.213) (xy 218.891835 134.22673) (xy 218.878095 134.22673)
			(xy 218.878095 134.24046) (xy 218.864365 134.24046) (xy 218.864365 134.2542) (xy 218.850635 134.2542)
			(xy 218.850635 134.26793) (xy 218.836905 134.26793) (xy 218.836905 134.28166) (xy 218.823175 134.28166)
			(xy 218.823175 134.29539) (xy 218.809445 134.29539) (xy 218.809445 134.30912) (xy 218.795705 134.30912)
			(xy 218.795705 134.32286) (xy 218.781975 134.32286) (xy 218.781975 134.33659) (xy 218.768245 134.33659)
			(xy 218.768245 134.35032) (xy 218.754515 134.35032) (xy 218.754515 134.36405) (xy 218.740785 134.36405)
			(xy 218.740785 134.37778) (xy 218.727055 134.37778) (xy 218.727055 134.39151) (xy 218.713315 134.39151)
			(xy 218.713315 134.40525) (xy 218.699585 134.40525) (xy 218.699585 134.41898) (xy 218.685855 134.41898)
			(xy 218.685855 134.43271) (xy 218.672125 134.43271) (xy 218.672125 134.44644) (xy 218.658395 134.44644)
			(xy 218.658395 134.46017) (xy 218.644655 134.46017) (xy 218.644655 134.4739) (xy 218.644655 134.48764)
			(xy 218.644655 134.50137) (xy 218.630925 134.50137) (xy 218.630925 134.5151) (xy 218.630925 134.52883)
			(xy 218.630925 134.54256) (xy 218.630925 134.55629) (xy 218.630925 134.57003) (xy 218.617195 134.57003)
			(xy 218.287635 134.57003) (xy 218.287635 134.55629) (xy 218.287635 134.54256) (xy 218.287635 134.52883)
			(xy 218.287635 134.5151) (xy 218.287635 134.50137) (xy 218.287635 134.48764) (xy 218.287635 134.4739)
			(xy 218.287635 134.46017) (xy 218.287635 134.44644) (xy 218.287635 134.43271) (xy 218.287635 134.41898)
			(xy 218.287635 134.40525) (xy 218.287635 134.39151) (xy 218.287635 134.37778) (xy 218.287635 134.36405)
			(xy 218.287635 134.35032) (xy 218.287635 134.33659) (xy 218.287635 134.32286) (xy 218.287635 134.30912)
			(xy 218.287635 134.29539) (xy 218.287635 134.28166) (xy 218.287635 134.26793) (xy 218.287635 134.2542)
			(xy 218.287635 134.24046) (xy 218.287635 134.22673) (xy 218.287635 134.213) (xy 218.287635 134.19927)
			(xy 218.287635 134.18554) (xy 218.287635 134.1718) (xy 218.287635 134.15807) (xy 218.287635 134.14434)
			(xy 218.287635 134.13061) (xy 218.287635 134.11688) (xy 218.287635 134.10315) (xy 218.287635 134.08941)
			(xy 218.287635 134.07568) (xy 218.287635 134.06195) (xy 218.287635 134.04822) (xy 218.287635 134.03449)
			(xy 218.287635 134.02076) (xy 218.287635 134.00702) (xy 218.287635 133.99329) (xy 218.287635 133.97956)
			(xy 218.287635 133.96583) (xy 218.287635 133.9521) (xy 218.287635 133.93837) (xy 218.287635 133.92463)
			(xy 218.287635 133.9109) (xy 218.287635 133.89717) (xy 218.287635 133.88344) (xy 218.287635 133.86971)
			(xy 218.287635 133.85598) (xy 218.287635 133.84224) (xy 218.287635 133.82851) (xy 218.287635 133.81478)
			(xy 218.287635 133.80105) (xy 218.287635 133.78732) (xy 218.287635 133.77359) (xy 218.287635 133.75985)
			(xy 218.287635 133.74612) (xy 218.287635 133.73239) (xy 218.287635 133.71866) (xy 218.287635 133.70493)
			(xy 218.287635 133.69119) (xy 218.287635 133.67746) (xy 218.287635 133.66373) (xy 218.287635 133.65)
			(xy 218.287635 133.63627) (xy 218.287635 133.62253) (xy 218.287635 133.6088) (xy 218.287635 133.59507)
			(xy 218.287635 133.58134) (xy 218.287635 133.56761) (xy 218.287635 133.55388) (xy 218.287635 133.54014)
			(xy 218.287635 133.52641) (xy 218.287635 133.51268) (xy 218.287635 133.49895) (xy 218.287635 133.48522)
			(xy 218.287635 133.47149) (xy 218.287635 133.45775) (xy 218.287635 133.44402) (xy 218.287635 133.43029)
			(xy 218.287635 133.41656) (xy 218.287635 133.40283) (xy 218.287635 133.3891) (xy 218.287635 133.37536)
			(xy 218.287635 133.36163) (xy 218.287635 133.3479) (xy 218.287635 133.33417) (xy 218.287635 133.32044)
			(xy 218.287635 133.30671) (xy 218.287635 133.29297) (xy 218.287635 133.27924) (xy 218.287635 133.26551)
			(xy 218.287635 133.25178) (xy 218.287635 133.23805) (xy 218.287635 133.22431) (xy 218.287635 133.21058)
			(xy 218.287635 133.19685) (xy 218.287635 133.18312) (xy 218.287635 133.16939) (xy 218.287635 133.15565)
			(xy 218.287635 133.14192) (xy 218.287635 133.12819) (xy 218.287635 133.11446) (xy 218.287635 133.10073)
			(xy 218.287635 133.087) (xy 218.287635 133.07326) (xy 218.287635 133.05953) (xy 218.287635 133.0458)
			(xy 218.287635 133.03207) (xy 218.287635 133.01834) (xy 218.287635 133.00461) (xy 218.287635 132.99087)
			(xy 218.287635 132.97714) (xy 218.287635 132.96341) (xy 218.287635 132.94968) (xy 218.287635 132.93595)
			(xy 218.287635 132.92222) (xy 218.287635 132.90848) (xy 218.287635 132.89475) (xy 218.287635 132.88102)
			(xy 218.273905 132.88102) (xy 218.273905 132.86729) (xy 218.273905 132.85356) (xy 218.273905 132.83983)
			(xy 218.273905 132.82609) (xy 218.260175 132.82609) (xy 218.260175 132.81236) (xy 218.260175 132.79863)
			(xy 218.246445 132.79863) (xy 218.246445 132.7849) (xy 218.232705 132.7849) (xy 218.232705 132.77117)
			(xy 218.218975 132.77117) (xy 218.218975 132.75744) (xy 218.205245 132.75744) (xy 218.205245 132.7437)
			(xy 218.191515 132.7437) (xy 218.191515 132.72997) (xy 218.177785 132.72997) (xy 218.177785 132.71624)
			(xy 218.164045 132.71624) (xy 218.164045 132.70251) (xy 218.150315 132.70251) (xy 218.150315 132.68878)
			(xy 218.136585 132.68878) (xy 218.136585 132.67504) (xy 218.122855 132.67504) (xy 218.122855 132.66131)
			(xy 218.109125 132.66131) (xy 218.109125 132.64758) (xy 218.095385 132.64758) (xy 218.095385 132.63385)
			(xy 218.081655 132.63385) (xy 218.081655 132.62012) (xy 218.067925 132.62012) (xy 218.067925 132.60638)
			(xy 218.054195 132.60638) (xy 218.054195 132.59265) (xy 218.040465 132.59265) (xy 218.040465 132.57892)
			(xy 218.026735 132.57892) (xy 218.026735 132.56519) (xy 218.012995 132.56519) (xy 218.012995 132.55146)
			(xy 217.999265 132.55146) (xy 217.999265 132.53773) (xy 217.985535 132.53773) (xy 217.985535 132.52399)
			(xy 217.971805 132.52399) (xy 217.971805 132.51026) (xy 217.958075 132.51026) (xy 217.958075 132.49653)
			(xy 217.944345 132.49653) (xy 217.944345 132.4828) (xy 217.930605 132.4828) (xy 217.930605 132.46907)
			(xy 217.916875 132.46907) (xy 217.916875 132.45534) (xy 217.903145 132.45534) (xy 217.903145 132.4416)
			(xy 217.889415 132.4416) (xy 217.889415 132.42787) (xy 217.875685 132.42787) (xy 217.875685 132.41414)
			(xy 217.848215 132.41414) (xy 217.848215 132.40041) (xy 217.793295 132.40041) (xy 217.793295 132.38668)
			(xy 217.546115 132.38668) (xy 217.546115 132.40041) (xy 217.546115 132.41414) (xy 217.546115 132.42787)
			(xy 217.546115 132.4416) (xy 217.546115 132.45534) (xy 217.546115 132.46907) (xy 217.546115 132.4828)
			(xy 217.546115 132.49653) (xy 217.546115 132.51026) (xy 217.546115 132.52399) (xy 217.546115 132.53773)
			(xy 217.546115 132.55146) (xy 217.546115 132.56519) (xy 217.546115 132.57892) (xy 217.546115 132.59265)
			(xy 217.546115 132.60638) (xy 217.546115 132.62012) (xy 217.546115 132.63385) (xy 217.546115 132.64758)
			(xy 217.546115 132.66131) (xy 217.546115 132.67504) (xy 217.546115 132.68878) (xy 217.546115 132.70251)
			(xy 217.546115 132.71624) (xy 217.546115 132.72997) (xy 217.546115 132.7437) (xy 217.546115 132.75744)
			(xy 217.546115 132.77117) (xy 217.546115 132.7849) (xy 217.546115 132.79863) (xy 217.546115 132.81236)
			(xy 217.546115 132.82609) (xy 217.546115 132.83983) (xy 217.546115 132.85356) (xy 217.546115 132.86729)
			(xy 217.546115 132.88102) (xy 217.546115 132.89475) (xy 217.546115 132.90848) (xy 217.546115 132.92222)
			(xy 217.546115 132.93595) (xy 217.546115 132.94968) (xy 217.546115 132.96341) (xy 217.546115 132.97714)
			(xy 217.546115 132.99087) (xy 217.546115 133.00461) (xy 217.546115 133.01834) (xy 217.546115 133.03207)
			(xy 217.546115 133.0458) (xy 217.546115 133.05953) (xy 217.546115 133.07326) (xy 217.546115 133.087)
			(xy 217.546115 133.10073) (xy 217.546115 133.11446) (xy 217.546115 133.12819) (xy 217.546115 133.14192)
			(xy 217.546115 133.15565) (xy 217.546115 133.16939) (xy 217.546115 133.18312) (xy 217.546115 133.19685)
			(xy 217.546115 133.21058) (xy 217.546115 133.22431) (xy 217.546115 133.23805) (xy 217.546115 133.25178)
			(xy 217.546115 133.26551) (xy 217.546115 133.27924) (xy 217.546115 133.29297) (xy 217.546115 133.30671)
			(xy 217.546115 133.32044) (xy 217.546115 133.33417) (xy 217.546115 133.3479) (xy 217.546115 133.36163)
			(xy 217.546115 133.37536) (xy 217.546115 133.3891) (xy 217.546115 133.40283) (xy 217.546115 133.41656)
			(xy 217.546115 133.43029) (xy 217.546115 133.44402) (xy 217.546115 133.45775) (xy 217.546115 133.47149)
			(xy 217.546115 133.48522) (xy 217.546115 133.49895) (xy 217.546115 133.51268) (xy 217.546115 133.52641)
			(xy 217.546115 133.54014) (xy 217.546115 133.55388) (xy 217.546115 133.56761) (xy 217.546115 133.58134)
			(xy 217.546115 133.59507) (xy 217.546115 133.6088) (xy 217.546115 133.62253) (xy 217.546115 133.63627)
			(xy 217.546115 133.65) (xy 217.546115 133.66373) (xy 217.546115 133.67746) (xy 217.546115 133.69119)
			(xy 217.546115 133.70493) (xy 217.546115 133.71866) (xy 217.546115 133.73239) (xy 217.546115 133.74612)
			(xy 217.546115 133.75985) (xy 217.546115 133.77359) (xy 217.546115 133.78732) (xy 217.546115 133.80105)
			(xy 217.546115 133.81478) (xy 217.546115 133.82851) (xy 217.546115 133.84224) (xy 217.546115 133.85598)
			(xy 217.546115 133.86971) (xy 217.546115 133.88344) (xy 217.546115 133.89717) (xy 217.546115 133.9109)
			(xy 217.546115 133.92463) (xy 217.546115 133.93837) (xy 217.546115 133.9521) (xy 217.546115 133.96583)
			(xy 217.546115 133.97956) (xy 217.546115 133.99329) (xy 217.546115 134.00702) (xy 217.546115 134.02076)
			(xy 217.546115 134.03449) (xy 217.546115 134.04822) (xy 217.546115 134.06195) (xy 217.546115 134.07568)
			(xy 217.546115 134.08941) (xy 217.546115 134.10315) (xy 217.546115 134.11688) (xy 217.546115 134.13061)
			(xy 217.546115 134.14434) (xy 217.546115 134.15807) (xy 217.546115 134.1718) (xy 217.546115 134.18554)
			(xy 217.546115 134.19927) (xy 217.546115 134.213) (xy 217.546115 134.22673) (xy 217.546115 134.24046)
			(xy 217.546115 134.2542) (xy 217.546115 134.26793) (xy 217.546115 134.28166) (xy 217.546115 134.29539)
			(xy 217.546115 134.30912) (xy 217.546115 134.32286) (xy 217.546115 134.33659) (xy 217.546115 134.35032)
			(xy 217.546115 134.36405) (xy 217.546115 134.37778) (xy 217.546115 134.39151) (xy 217.546115 134.40525)
			(xy 217.546115 134.41898) (xy 217.546115 134.43271) (xy 217.546115 134.44644) (xy 217.546115 134.46017)
			(xy 217.546115 134.4739) (xy 217.546115 134.48764) (xy 217.546115 134.50137) (xy 217.546115 134.5151)
			(xy 217.546115 134.52883) (xy 217.546115 134.54256) (xy 217.546115 134.55629) (xy 217.546115 134.57003)
			(xy 217.546115 134.58376) (xy 217.546115 134.59749) (xy 217.546115 134.61122) (xy 217.546115 134.62495)
			(xy 217.546115 134.63868) (xy 217.546115 134.65242) (xy 217.546115 134.66615) (xy 217.546115 134.67988)
			(xy 217.546115 134.69361) (xy 217.546115 134.70734) (xy 217.546115 134.72107) (xy 217.546115 134.73481)
			(xy 217.546115 134.74854) (xy 217.546115 134.76227) (xy 217.546115 134.776) (xy 217.546115 134.78973)
			(xy 217.546115 134.80347) (xy 217.546115 134.8172) (xy 217.546115 134.83093) (xy 217.546115 134.84466)
			(xy 217.546115 134.85839) (xy 217.546115 134.87213) (xy 217.546115 134.88586) (xy 217.546115 134.89959)
			(xy 217.546115 134.91332) (xy 217.546115 134.92705) (xy 217.546115 134.94078) (xy 217.546115 134.95452)
			(xy 217.546115 134.96825) (xy 217.546115 134.98198) (xy 217.546115 134.99571) (xy 217.546115 135.00944)
			(xy 217.546115 135.02317) (xy 217.546115 135.03691) (xy 217.546115 135.05064) (xy 217.546115 135.06437)
			(xy 217.546115 135.0781) (xy 217.546115 135.09183) (xy 217.546115 135.10556) (xy 217.546115 135.1193)
			(xy 217.546115 135.13303) (xy 217.546115 135.14676) (xy 217.546115 135.16049) (xy 217.546115 135.17422)
			(xy 217.546115 135.18795) (xy 217.546115 135.20169) (xy 217.546115 135.21542) (xy 217.546115 135.22915)
			(xy 217.546115 135.24288) (xy 217.546115 135.25661) (xy 217.546115 135.27034) (xy 217.546115 135.28408)
			(xy 217.546115 135.29781) (xy 217.546115 135.31154) (xy 217.546115 135.32527) (xy 217.546115 135.339)
			(xy 217.546115 135.35274) (xy 217.546115 135.36647) (xy 217.546115 135.3802) (xy 217.546115 135.39393)
			(xy 217.546115 135.40766) (xy 217.546115 135.4214) (xy 217.546115 135.43513) (xy 217.546115 135.44886)
			(xy 217.546115 135.46259) (xy 217.546115 135.47632) (xy 217.546115 135.49005) (xy 217.546115 135.50379)
			(xy 217.546115 135.51752) (xy 217.546115 135.53125) (xy 217.546115 135.54498) (xy 217.546115 135.55871)
			(xy 217.546115 135.57244) (xy 217.546115 135.58618) (xy 217.546115 135.59991) (xy 217.546115 135.61364)
			(xy 217.546115 135.62737) (xy 217.546115 135.6411) (xy 217.546115 135.65483) (xy 217.546115 135.66857)
			(xy 217.546115 135.6823) (xy 217.546115 135.69603) (xy 217.546115 135.70976) (xy 217.546115 135.72349)
			(xy 217.546115 135.73722) (xy 217.546115 135.75096) (xy 217.546115 135.76469) (xy 217.546115 135.77842)
			(xy 217.546115 135.79215) (xy 217.546115 135.80588) (xy 217.546115 135.81961) (xy 217.546115 135.83335)
			(xy 217.546115 135.84708) (xy 217.546115 135.86081) (xy 217.546115 135.87454) (xy 217.546115 135.88827)
			(xy 217.546115 135.90201) (xy 217.546115 135.91574) (xy 217.546115 135.92947) (xy 217.546115 135.9432)
			(xy 217.546115 135.95693) (xy 217.546115 135.97067) (xy 217.546115 135.9844) (xy 217.546115 135.99813)
			(xy 217.546115 136.01186) (xy 217.546115 136.02559) (xy 217.546115 136.03932) (xy 217.546115 136.05306)
			(xy 217.546115 136.06679) (xy 217.546115 136.08052) (xy 217.546115 136.09425) (xy 217.546115 136.10798)
			(xy 217.546115 136.12171) (xy 217.546115 136.13545) (xy 217.546115 136.14918) (xy 217.546115 136.16291)
			(xy 217.546115 136.17664) (xy 217.546115 136.19037) (xy 217.546115 136.2041) (xy 217.546115 136.21784)
			(xy 217.546115 136.23157) (xy 217.546115 136.2453) (xy 217.546115 136.25903) (xy 217.546115 136.27276)
			(xy 217.546115 136.28649) (xy 217.546115 136.30023) (xy 217.546115 136.31396) (xy 217.546115 136.32769)
			(xy 217.546115 136.34142) (xy 217.546115 136.35515) (xy 217.546115 136.36889) (xy 217.546115 136.38262)
			(xy 217.546115 136.39635) (xy 217.546115 136.41008) (xy 217.546115 136.42381) (xy 217.546115 136.43755)
			(xy 217.546115 136.45128) (xy 217.546115 136.46501) (xy 217.546115 136.47874) (xy 217.546115 136.49247)
			(xy 217.546115 136.5062) (xy 217.546115 136.51994) (xy 217.546115 136.53367) (xy 217.546115 136.5474)
			(xy 217.546115 136.56113) (xy 217.546115 136.57486) (xy 217.546115 136.58859) (xy 217.546115 136.60233)
			(xy 217.546115 136.61606) (xy 217.546115 136.62979) (xy 217.546115 136.64352) (xy 217.546115 136.65725)
			(xy 217.546115 136.67098) (xy 217.546115 136.68472) (xy 217.546115 136.69845) (xy 217.546115 136.71218)
			(xy 217.546115 136.72591) (xy 217.546115 136.73964) (xy 217.546115 136.75337) (xy 217.546115 136.76711)
			(xy 217.546115 136.78084) (xy 217.546115 136.79457) (xy 217.546115 136.8083) (xy 217.546115 136.82203)
			(xy 217.546115 136.83576) (xy 217.546115 136.8495) (xy 217.546115 136.86323) (xy 217.546115 136.87696)
			(xy 217.546115 136.89069) (xy 217.546115 136.90442) (xy 217.546115 136.91816) (xy 217.546115 136.93189)
			(xy 217.532385 136.93189) (xy 217.532385 136.94562) (xy 217.518655 136.94562) (xy 217.518655 136.95935)
			(xy 217.504925 136.95935) (xy 217.504925 136.97308) (xy 217.491195 136.97308) (xy 217.491195 136.98682)
			(xy 217.477465 136.98682) (xy 217.477465 137.00055) (xy 217.463725 137.00055) (xy 217.463725 137.01428)
			(xy 217.449995 137.01428) (xy 217.449995 137.02801) (xy 217.436265 137.02801) (xy 217.436265 137.04174)
			(xy 217.422535 137.04174) (xy 217.422535 137.05547) (xy 217.408805 137.05547) (xy 217.408805 137.06921)
			(xy 217.395075 137.06921) (xy 217.395075 137.08294) (xy 217.381335 137.08294) (xy 217.381335 137.09667)
			(xy 217.367605 137.09667) (xy 217.367605 137.1104) (xy 217.353875 137.1104) (xy 217.353875 137.12413)
			(xy 217.340145 137.12413) (xy 217.340145 137.13786) (xy 217.326415 137.13786) (xy 217.326415 137.1516)
			(xy 217.312685 137.1516) (xy 217.312685 137.16533) (xy 217.285215 137.16533) (xy 217.285215 137.17906)
			(xy 217.271485 137.17906) (xy 217.271485 137.19279) (xy 217.257755 137.19279) (xy 217.257755 137.20652)
			(xy 217.244025 137.20652) (xy 217.244025 137.22025) (xy 217.230295 137.22025) (xy 217.230295 137.23399)
			(xy 217.216555 137.23399) (xy 217.216555 137.24772) (xy 217.202825 137.24772) (xy 217.202825 137.26145)
			(xy 217.189095 137.26145) (xy 217.189095 137.27518) (xy 217.175365 137.27518) (xy 217.175365 137.28891)
			(xy 217.161635 137.28891) (xy 217.161635 137.30264) (xy 217.147905 137.30264) (xy 217.147905 137.31638)
			(xy 217.134165 137.31638) (xy 217.134165 137.33011) (xy 217.120435 137.33011) (xy 217.120435 137.34384)
			(xy 217.106705 137.34384) (xy 217.106705 137.35757) (xy 217.092975 137.35757) (xy 217.092975 137.3713)
			(xy 217.079245 137.3713) (xy 217.079245 137.38503) (xy 217.065505 137.38503) (xy 217.065505 137.39877)
			(xy 217.051775 137.39877) (xy 217.051775 137.4125) (xy 217.038045 137.4125) (xy 217.038045 137.42623)
			(xy 217.024315 137.42623) (xy 217.024315 137.43996) (xy 217.010585 137.43996) (xy 217.010585 137.45369)
			(xy 216.996845 137.45369) (xy 216.996845 137.46743) (xy 216.983115 137.46743) (xy 216.983115 137.48116)
			(xy 216.969385 137.48116) (xy 216.969385 137.49489) (xy 216.955655 137.49489) (xy 216.955655 137.50862)
			(xy 216.941925 137.50862) (xy 216.941925 137.52235) (xy 216.928195 137.52235) (xy 216.928195 137.53609)
			(xy 216.914455 137.53609) (xy 216.914455 137.54982) (xy 216.900725 137.54982) (xy 216.900725 137.56355)
			(xy 216.886995 137.56355) (xy 216.886995 137.57728) (xy 216.873265 137.57728) (xy 216.873265 137.59101)
			(xy 216.859535 137.59101) (xy 216.859535 137.60474) (xy 216.845805 137.60474) (xy 216.845805 137.61848)
			(xy 216.832065 137.61848) (xy 216.832065 137.63221) (xy 216.818335 137.63221) (xy 216.818335 137.64594)
			(xy 216.804605 137.64594) (xy 216.804605 137.65967) (xy 216.790875 137.65967) (xy 216.790875 137.6734)
			(xy 216.777145 137.6734) (xy 216.777145 137.68713) (xy 216.763415 137.68713) (xy 216.763415 137.70087)
			(xy 216.749675 137.70087) (xy 216.749675 137.7146) (xy 216.735945 137.7146) (xy 216.735945 137.72833)
			(xy 216.722215 137.72833) (xy 216.722215 137.74206) (xy 216.708485 137.74206) (xy 216.708485 137.75579)
			(xy 216.694755 137.75579) (xy 216.694755 137.76952) (xy 216.681025 137.76952) (xy 216.681025 137.78326)
			(xy 216.667285 137.78326) (xy 216.667285 137.79699) (xy 216.653555 137.79699) (xy 216.653555 137.81072)
			(xy 216.639825 137.81072) (xy 216.639825 137.82445) (xy 216.626095 137.82445) (xy 216.626095 137.83818)
			(xy 216.612365 137.83818) (xy 216.612365 137.85191) (xy 216.598625 137.85191) (xy 216.598625 137.86565)
			(xy 216.584895 137.86565) (xy 216.584895 137.87938) (xy 216.571165 137.87938) (xy 216.571165 137.89311)
			(xy 216.557435 137.89311) (xy 216.557435 137.90684) (xy 216.543705 137.90684) (xy 216.543705 137.92057)
			(xy 216.529965 137.92057) (xy 216.529965 137.9343) (xy 216.516235 137.9343) (xy 216.516235 137.94804)
			(xy 216.502505 137.94804) (xy 216.502505 137.96177) (xy 216.488775 137.96177) (xy 216.488775 137.9755)
			(xy 216.475045 137.9755) (xy 216.475045 137.98923) (xy 216.461315 137.98923) (xy 216.461315 138.00296)
			(xy 216.447575 138.00296) (xy 216.447575 138.0167) (xy 216.433845 138.0167) (xy 216.433845 138.03043)
			(xy 216.420115 138.03043) (xy 216.420115 138.04416) (xy 216.406385 138.04416) (xy 216.406385 138.05789)
			(xy 216.392655 138.05789) (xy 216.392655 138.07162) (xy 216.378925 138.07162) (xy 216.378925 138.08536)
			(xy 216.351455 138.08536) (xy 216.351455 138.09909) (xy 216.337725 138.09909) (xy 216.337725 138.11282)
			(xy 216.323995 138.11282) (xy 216.323995 138.12655) (xy 216.310265 138.12655) (xy 216.310265 138.14028)
			(xy 216.296535 138.14028) (xy 216.296535 138.15401) (xy 216.282795 138.15401) (xy 216.282795 138.16775)
			(xy 216.269065 138.16775) (xy 216.269065 138.18148) (xy 216.255335 138.18148) (xy 216.255335 138.19521)
			(xy 216.241605 138.19521) (xy 216.241605 138.20894) (xy 216.227875 138.20894) (xy 216.227875 138.22267)
			(xy 216.214145 138.22267) (xy 216.214145 138.2364) (xy 216.200405 138.2364) (xy 216.200405 138.25014)
			(xy 216.186675 138.25014) (xy 216.186675 138.26387) (xy 216.172945 138.26387) (xy 216.172945 138.2776)
			(xy 216.159215 138.2776) (xy 216.159215 138.29133) (xy 216.145485 138.29133) (xy 216.145485 138.30506)
			(xy 216.131755 138.30506) (xy 216.131755 138.31879) (xy 216.131755 138.33253) (xy 216.118015 138.33253)
			(xy 216.118015 138.34626) (xy 216.104285 138.34626) (xy 216.104285 138.35999) (xy 216.104285 138.37372)
			(xy 216.090555 138.37372) (xy 216.090555 138.38745) (xy 216.090555 138.40118) (xy 216.076825 138.40118)
			(xy 214.882155 138.40118) (xy 214.882155 138.38745) (xy 214.882155 138.37372) (xy 214.882155 138.35999)
			(xy 214.882155 138.34626) (xy 214.882155 138.33253) (xy 214.882155 138.31879) (xy 214.882155 138.30506)
			(xy 214.882155 138.29133) (xy 214.882155 138.2776) (xy 214.882155 138.26387) (xy 214.882155 138.25014)
			(xy 214.882155 138.2364) (xy 214.882155 138.22267) (xy 214.882155 138.20894) (xy 214.882155 138.19521)
			(xy 214.882155 138.18148) (xy 214.882155 138.16775) (xy 214.882155 138.15401) (xy 214.882155 138.14028)
			(xy 214.882155 138.12655) (xy 214.882155 138.11282) (xy 214.882155 138.09909) (xy 214.882155 138.08536)
			(xy 214.882155 138.07162) (xy 214.882155 138.05789) (xy 214.882155 138.04416) (xy 214.882155 138.03043)
			(xy 214.895895 138.03043) (xy 214.895895 138.0167) (xy 214.909625 138.0167) (xy 214.909625 138.00296)
			(xy 216.269065 138.00296) (xy 216.269065 137.98923) (xy 216.282795 137.98923) (xy 216.282795 138.00296)
			(xy 216.337725 138.00296) (xy 216.337725 137.98923) (xy 216.378925 137.98923) (xy 216.378925 137.9755)
			(xy 216.392655 137.9755) (xy 216.392655 137.96177) (xy 216.406385 137.96177) (xy 216.406385 137.94804)
			(xy 216.406385 137.9343) (xy 216.406385 137.92057) (xy 216.406385 137.90684) (xy 216.406385 137.89311)
			(xy 216.406385 137.87938) (xy 216.406385 137.86565) (xy 216.406385 137.85191) (xy 216.406385 137.83818)
			(xy 216.406385 137.82445) (xy 216.406385 137.81072) (xy 216.406385 137.79699) (xy 216.406385 137.78326)
			(xy 216.406385 137.76952) (xy 216.406385 137.75579) (xy 216.406385 137.74206) (xy 216.406385 137.72833)
			(xy 216.406385 137.7146) (xy 216.406385 137.70087) (xy 216.406385 137.68713) (xy 216.406385 137.6734)
			(xy 216.406385 137.65967) (xy 216.406385 137.64594) (xy 216.406385 137.63221) (xy 216.406385 137.61848)
			(xy 216.406385 137.60474) (xy 216.406385 137.59101) (xy 216.406385 137.57728) (xy 216.406385 137.56355)
			(xy 216.406385 137.54982) (xy 216.406385 137.53609) (xy 216.406385 137.52235) (xy 216.406385 137.50862)
			(xy 216.406385 137.49489) (xy 216.406385 137.48116) (xy 216.406385 137.46743) (xy 216.406385 137.45369)
			(xy 216.406385 137.43996) (xy 216.406385 137.42623) (xy 216.406385 137.4125) (xy 216.406385 137.39877)
			(xy 216.406385 137.38503) (xy 216.406385 137.3713) (xy 216.406385 137.35757) (xy 216.406385 137.34384)
			(xy 216.406385 137.33011) (xy 216.406385 137.31638) (xy 216.406385 137.30264) (xy 216.392655 137.30264)
			(xy 216.392655 137.28891) (xy 216.378925 137.28891) (xy 216.378925 137.27518) (xy 216.337725 137.27518)
			(xy 216.337725 137.26145) (xy 216.310265 137.26145) (xy 216.310265 137.27518) (xy 216.296535 137.27518)
			(xy 216.296535 137.26145) (xy 214.648725 137.26145) (xy 214.648725 137.27518) (xy 214.607525 137.27518)
			(xy 214.607525 137.28891) (xy 214.566335 137.28891) (xy 214.566335 137.30264) (xy 214.538865 137.30264)
			(xy 214.538865 137.31638) (xy 214.525135 137.31638) (xy 214.525135 137.33011) (xy 214.511405 137.33011)
			(xy 214.511405 137.34384) (xy 214.497675 137.34384) (xy 214.497675 137.35757) (xy 214.483935 137.35757)
			(xy 214.483935 137.3713) (xy 214.470205 137.3713) (xy 214.470205 137.38503) (xy 214.456475 137.38503)
			(xy 214.456475 137.39877) (xy 214.442745 137.39877) (xy 214.442745 137.4125) (xy 214.429015 137.4125)
			(xy 214.429015 137.42623) (xy 214.415275 137.42623) (xy 214.415275 137.43996) (xy 214.401545 137.43996)
			(xy 214.401545 137.45369) (xy 214.387815 137.45369) (xy 214.387815 137.46743) (xy 214.374085 137.46743)
			(xy 214.374085 137.48116) (xy 214.360355 137.48116) (xy 214.360355 137.49489) (xy 214.346625 137.49489)
			(xy 214.346625 137.50862) (xy 214.332885 137.50862) (xy 214.332885 137.52235) (xy 214.319155 137.52235)
			(xy 214.319155 137.53609) (xy 214.305425 137.53609) (xy 214.305425 137.54982) (xy 214.291695 137.54982)
			(xy 214.291695 137.56355) (xy 214.277965 137.56355) (xy 214.277965 137.57728) (xy 214.264235 137.57728)
			(xy 214.264235 137.59101) (xy 214.250495 137.59101) (xy 214.250495 137.60474) (xy 214.236765 137.60474)
			(xy 214.236765 137.61848) (xy 214.223035 137.61848) (xy 214.223035 137.63221) (xy 214.209305 137.63221)
			(xy 214.209305 137.64594) (xy 214.195575 137.64594) (xy 214.195575 137.65967) (xy 214.181845 137.65967)
			(xy 214.181845 137.6734) (xy 214.168105 137.6734) (xy 214.168105 137.68713) (xy 214.154375 137.68713)
			(xy 214.154375 137.70087) (xy 214.154375 137.7146) (xy 214.140645 137.7146) (xy 214.140645 137.72833)
			(xy 214.140645 137.74206) (xy 214.140645 137.75579) (xy 214.140645 137.76952) (xy 214.126915 137.76952)
			(xy 212.904785 137.76952) (xy 212.904785 137.75579) (xy 212.904785 137.74206) (xy 212.904785 137.72833)
			(xy 212.904785 137.7146) (xy 212.891055 137.7146) (xy 212.891055 137.70087) (xy 212.891055 137.68713)
			(xy 212.891055 137.6734) (xy 212.891055 137.65967) (xy 212.891055 137.64594) (xy 212.891055 137.63221)
			(xy 212.891055 137.61848) (xy 212.891055 137.60474) (xy 212.891055 137.59101) (xy 212.891055 137.57728)
			(xy 212.877325 137.57728) (xy 212.877325 137.56355) (xy 212.877325 137.54982) (xy 212.877325 137.53609)
			(xy 212.877325 137.52235) (xy 212.877325 137.50862) (xy 212.877325 137.49489) (xy 212.877325 137.48116)
			(xy 212.877325 137.46743) (xy 212.877325 137.45369) (xy 212.877325 137.43996) (xy 212.877325 137.42623)
			(xy 212.877325 137.4125) (xy 212.877325 137.39877) (xy 212.877325 137.38503) (xy 212.877325 137.3713)
			(xy 212.877325 137.35757) (xy 212.863595 137.35757) (xy 212.863595 137.34384) (xy 212.863595 137.33011)
			(xy 212.863595 137.31638) (xy 212.863595 137.30264) (xy 212.863595 137.28891) (xy 212.863595 137.27518)
			(xy 212.698815 137.27518) (xy 212.698815 137.28891) (xy 210.858755 137.28891) (xy 210.858755 137.27518)
			(xy 210.858755 137.26145) (xy 210.858755 137.24772) (xy 210.858755 137.23399) (xy 210.858755 137.22025)
			(xy 210.858755 137.20652) (xy 210.858755 137.19279) (xy 210.858755 137.17906) (xy 210.858755 137.16533)
			(xy 210.858755 137.1516) (xy 210.858755 137.13786) (xy 210.858755 137.12413) (xy 210.858755 137.1104)
			(xy 210.858755 137.09667) (xy 210.858755 137.08294) (xy 210.858755 137.06921) (xy 210.858755 137.05547)
			(xy 210.858755 137.04174) (xy 210.858755 137.02801) (xy 210.858755 137.01428) (xy 210.858755 137.00055)
			(xy 210.858755 136.98682) (xy 210.858755 136.97308) (xy 210.858755 136.95935) (xy 210.858755 136.94562)
			(xy 210.858755 136.93189) (xy 210.858755 136.91816) (xy 210.858755 136.90442) (xy 210.858755 136.89069)
			(xy 210.858755 136.87696) (xy 210.858755 136.86323) (xy 210.858755 136.8495) (xy 210.858755 136.83576)
			(xy 210.858755 136.82203) (xy 210.858755 136.8083) (xy 210.858755 136.79457) (xy 210.858755 136.78084)
			(xy 210.858755 136.76711) (xy 210.858755 136.75337) (xy 210.858755 136.73964) (xy 210.858755 136.72591)
			(xy 210.858755 136.71218) (xy 210.858755 136.69845) (xy 210.858755 136.68472) (xy 210.858755 136.67098)
			(xy 210.858755 136.65725) (xy 210.858755 136.64352) (xy 210.858755 136.62979) (xy 210.858755 136.61606)
			(xy 210.858755 136.60233) (xy 210.858755 136.58859) (xy 210.858755 136.57486) (xy 210.858755 136.56113)
			(xy 210.858755 136.5474) (xy 210.858755 136.53367) (xy 210.858755 136.51994) (xy 210.858755 136.5062)
			(xy 210.858755 136.49247) (xy 210.858755 136.47874) (xy 210.858755 136.46501) (xy 210.858755 136.45128)
			(xy 210.858755 136.43755) (xy 210.858755 136.42381) (xy 210.858755 136.41008) (xy 210.858755 136.39635)
			(xy 210.858755 136.38262) (xy 210.858755 136.36889) (xy 210.858755 136.35515) (xy 210.858755 136.34142)
			(xy 210.858755 136.32769) (xy 210.858755 136.31396) (xy 210.858755 136.30023) (xy 210.858755 136.28649)
			(xy 210.858755 136.27276) (xy 210.858755 136.25903) (xy 210.858755 136.2453) (xy 210.858755 136.23157)
			(xy 210.858755 136.21784) (xy 210.858755 136.2041) (xy 210.858755 136.19037) (xy 210.858755 136.17664)
			(xy 210.858755 136.16291) (xy 209.526775 136.16291) (xy 209.526775 136.14918) (xy 209.526775 136.13545)
			(xy 209.526775 136.12171) (xy 209.526775 136.10798) (xy 209.526775 136.09425) (xy 209.526775 136.08052)
			(xy 209.526775 136.06679) (xy 209.526775 136.05306) (xy 209.526775 136.03932) (xy 209.526775 136.02559)
			(xy 209.526775 136.01186) (xy 209.526775 135.99813) (xy 209.526775 135.9844) (xy 209.526775 135.97067)
			(xy 209.526775 135.95693) (xy 209.526775 135.9432) (xy 209.526775 135.92947) (xy 209.526775 135.91574)
			(xy 209.526775 135.90201) (xy 209.526775 135.88827) (xy 209.526775 135.87454) (xy 209.526775 135.86081)
			(xy 209.526775 135.84708) (xy 209.526775 135.83335) (xy 209.526775 135.81961) (xy 209.526775 135.80588)
			(xy 209.526775 135.79215) (xy 209.526775 135.77842) (xy 209.526775 135.76469) (xy 209.526775 135.75096)
			(xy 209.526775 135.73722) (xy 209.526775 135.72349) (xy 209.526775 135.70976) (xy 209.526775 135.69603)
			(xy 209.526775 135.6823) (xy 209.526775 135.66857) (xy 209.526775 135.65483) (xy 209.526775 135.6411)
			(xy 209.526775 135.62737) (xy 209.526775 135.61364) (xy 209.526775 135.59991) (xy 209.526775 135.58618)
			(xy 209.526775 135.57244) (xy 209.526775 135.55871) (xy 209.526775 135.54498) (xy 209.526775 135.53125)
			(xy 209.526775 135.51752) (xy 209.526775 135.50379) (xy 209.526775 135.49005) (xy 209.526775 135.47632)
			(xy 209.526775 135.46259) (xy 209.526775 135.44886) (xy 209.526775 135.43513) (xy 209.526775 135.4214)
			(xy 209.526775 135.40766) (xy 209.526775 135.39393) (xy 209.526775 135.3802) (xy 209.526775 135.36647)
			(xy 209.526775 135.35274) (xy 209.526775 135.339) (xy 209.526775 135.32527) (xy 209.526775 135.31154)
			(xy 209.526775 135.29781) (xy 209.526775 135.28408) (xy 209.526775 135.27034) (xy 209.526775 135.25661)
			(xy 209.526775 135.24288) (xy 209.526775 135.22915) (xy 209.526775 135.21542) (xy 209.526775 135.20169)
			(xy 209.526775 135.18795) (xy 209.526775 135.17422) (xy 209.526775 135.16049) (xy 209.526775 135.14676)
			(xy 209.526775 135.13303) (xy 209.526775 135.1193) (xy 209.526775 135.10556) (xy 209.526775 135.09183)
			(xy 209.526775 135.0781) (xy 209.526775 135.06437) (xy 209.526775 135.05064) (xy 209.526775 135.03691)
			(xy 209.526775 135.02317) (xy 209.526775 135.00944) (xy 209.526775 134.99571) (xy 209.526775 134.98198)
			(xy 209.526775 134.96825) (xy 209.526775 134.95452) (xy 209.526775 134.94078) (xy 209.526775 134.92705)
			(xy 209.526775 134.91332) (xy 209.526775 134.89959) (xy 209.526775 134.88586) (xy 209.526775 134.87213)
			(xy 209.526775 134.85839) (xy 209.526775 134.84466) (xy 209.526775 134.83093) (xy 209.526775 134.8172)
			(xy 209.526775 134.80347) (xy 209.526775 134.78973) (xy 209.526775 134.776) (xy 209.526775 134.76227)
			(xy 209.526775 134.74854) (xy 209.526775 134.73481) (xy 209.526775 134.72107) (xy 209.526775 134.70734)
			(xy 209.526775 134.69361) (xy 209.526775 134.67988) (xy 209.526775 134.66615) (xy 209.526775 134.65242)
			(xy 209.526775 134.63868) (xy 209.526775 134.62495) (xy 209.526775 134.61122) (xy 209.526775 134.59749)
			(xy 209.526775 134.58376) (xy 209.526775 134.57003) (xy 209.526775 134.55629) (xy 209.526775 134.54256)
			(xy 209.526775 134.52883) (xy 209.526775 134.5151) (xy 209.526775 134.50137) (xy 209.526775 134.48764)
			(xy 209.526775 134.4739) (xy 209.526775 134.46017) (xy 209.526775 134.44644) (xy 209.526775 134.43271)
			(xy 209.526775 134.41898) (xy 209.526775 134.40525) (xy 209.526775 134.39151) (xy 209.526775 134.37778)
			(xy 209.526775 134.36405) (xy 209.526775 134.35032) (xy 209.526775 134.33659) (xy 209.526775 134.32286)
			(xy 209.526775 134.30912) (xy 209.526775 134.29539) (xy 209.526775 134.28166) (xy 209.526775 134.26793)
			(xy 209.526775 134.2542) (xy 209.526775 134.24046) (xy 209.526775 134.22673) (xy 209.526775 134.213)
			(xy 209.526775 134.19927) (xy 209.526775 134.18554) (xy 209.526775 134.1718) (xy 209.526775 134.15807)
			(xy 209.526775 134.14434) (xy 209.526775 134.13061) (xy 209.526775 134.11688) (xy 209.526775 134.10315)
			(xy 209.526775 134.08941) (xy 209.526775 134.07568) (xy 211.586535 134.07568) (xy 211.586535 134.08941)
			(xy 211.586535 134.10315) (xy 211.586535 134.11688) (xy 211.586535 134.13061) (xy 211.586535 134.14434)
			(xy 211.586535 134.15807) (xy 211.586535 134.1718) (xy 211.586535 134.18554) (xy 211.586535 134.19927)
			(xy 211.586535 134.213) (xy 211.586535 134.22673) (xy 211.586535 134.24046) (xy 211.586535 134.2542)
			(xy 211.586535 134.26793) (xy 211.586535 134.28166) (xy 211.586535 134.29539) (xy 211.586535 134.30912)
			(xy 211.586535 134.32286) (xy 211.586535 134.33659) (xy 211.586535 134.35032) (xy 211.586535 134.36405)
			(xy 211.586535 134.37778) (xy 211.586535 134.39151) (xy 211.586535 134.40525) (xy 211.586535 134.41898)
			(xy 211.586535 134.43271) (xy 211.586535 134.44644) (xy 211.586535 134.46017) (xy 211.586535 134.4739)
			(xy 211.586535 134.48764) (xy 211.586535 134.50137) (xy 211.586535 134.5151) (xy 211.586535 134.52883)
			(xy 211.586535 134.54256) (xy 211.586535 134.55629) (xy 211.586535 134.57003) (xy 211.586535 134.58376)
			(xy 211.586535 134.59749) (xy 211.586535 134.61122) (xy 211.586535 134.62495) (xy 211.586535 134.63868)
			(xy 211.586535 134.65242) (xy 211.586535 134.66615) (xy 211.586535 134.67988) (xy 211.586535 134.69361)
			(xy 211.586535 134.70734) (xy 211.600275 134.70734) (xy 211.600275 134.72107) (xy 211.614005 134.72107)
			(xy 211.614005 134.73481) (xy 211.627735 134.73481) (xy 211.627735 134.74854) (xy 211.655195 134.74854)
			(xy 211.655195 134.76227) (xy 212.314325 134.76227) (xy 212.314325 134.776) (xy 212.328055 134.776)
			(xy 212.328055 134.78973) (xy 212.341785 134.78973) (xy 212.341785 134.80347) (xy 212.341785 134.8172)
			(xy 212.355515 134.8172) (xy 212.355515 134.83093) (xy 212.355515 134.84466) (xy 212.355515 134.85839)
			(xy 212.355515 134.87213) (xy 212.355515 134.88586) (xy 212.355515 134.89959) (xy 212.355515 134.91332)
			(xy 212.355515 134.92705) (xy 212.355515 134.94078) (xy 212.355515 134.95452) (xy 212.355515 134.96825)
			(xy 212.355515 134.98198) (xy 212.355515 134.99571) (xy 212.355515 135.00944) (xy 212.355515 135.02317)
			(xy 212.355515 135.03691) (xy 212.355515 135.05064) (xy 212.355515 135.06437) (xy 212.355515 135.0781)
			(xy 212.355515 135.09183) (xy 212.355515 135.10556) (xy 212.355515 135.1193) (xy 212.355515 135.13303)
			(xy 212.355515 135.14676) (xy 212.355515 135.16049) (xy 212.355515 135.17422) (xy 212.355515 135.18795)
			(xy 212.355515 135.20169) (xy 212.355515 135.21542) (xy 212.355515 135.22915) (xy 212.355515 135.24288)
			(xy 212.355515 135.25661) (xy 212.355515 135.27034) (xy 212.355515 135.28408) (xy 212.355515 135.29781)
			(xy 212.355515 135.31154) (xy 212.355515 135.32527) (xy 212.355515 135.339) (xy 212.355515 135.35274)
			(xy 212.355515 135.36647) (xy 212.355515 135.3802) (xy 212.355515 135.39393) (xy 212.355515 135.40766)
			(xy 212.355515 135.4214) (xy 212.355515 135.43513) (xy 212.355515 135.44886) (xy 212.355515 135.46259)
			(xy 212.355515 135.47632) (xy 212.355515 135.49005) (xy 212.355515 135.50379) (xy 212.355515 135.51752)
			(xy 212.355515 135.53125) (xy 212.355515 135.54498) (xy 212.355515 135.55871) (xy 212.355515 135.57244)
			(xy 212.355515 135.58618) (xy 212.355515 135.59991) (xy 212.355515 135.61364) (xy 212.355515 135.62737)
			(xy 212.355515 135.6411) (xy 212.355515 135.65483) (xy 212.355515 135.66857) (xy 212.355515 135.6823)
			(xy 212.355515 135.69603) (xy 212.355515 135.70976) (xy 212.355515 135.72349) (xy 212.355515 135.73722)
			(xy 212.355515 135.75096) (xy 212.355515 135.76469) (xy 212.355515 135.77842) (xy 212.355515 135.79215)
			(xy 212.355515 135.80588) (xy 212.355515 135.81961) (xy 212.355515 135.83335) (xy 212.355515 135.84708)
			(xy 212.355515 135.86081) (xy 212.355515 135.87454) (xy 212.355515 135.88827) (xy 212.355515 135.90201)
			(xy 212.355515 135.91574) (xy 212.355515 135.92947) (xy 212.355515 135.9432) (xy 212.355515 135.95693)
			(xy 212.355515 135.97067) (xy 212.355515 135.9844) (xy 212.355515 135.99813) (xy 212.355515 136.01186)
			(xy 212.355515 136.02559) (xy 212.355515 136.03932) (xy 212.355515 136.05306) (xy 212.355515 136.06679)
			(xy 212.355515 136.08052) (xy 212.355515 136.09425) (xy 212.355515 136.10798) (xy 212.355515 136.12171)
			(xy 212.355515 136.13545) (xy 212.355515 136.14918) (xy 212.355515 136.16291) (xy 212.355515 136.17664)
			(xy 212.355515 136.19037) (xy 212.355515 136.2041) (xy 212.355515 136.21784) (xy 212.355515 136.23157)
			(xy 212.355515 136.2453) (xy 212.355515 136.25903) (xy 212.355515 136.27276) (xy 212.355515 136.28649)
			(xy 212.355515 136.30023) (xy 212.355515 136.31396) (xy 212.355515 136.32769) (xy 212.355515 136.34142)
			(xy 212.355515 136.35515) (xy 212.355515 136.36889) (xy 212.355515 136.38262) (xy 212.355515 136.39635)
			(xy 212.355515 136.41008) (xy 212.355515 136.42381) (xy 212.355515 136.43755) (xy 212.355515 136.45128)
			(xy 212.355515 136.46501) (xy 212.355515 136.47874) (xy 212.355515 136.49247) (xy 212.355515 136.5062)
			(xy 212.355515 136.51994) (xy 212.355515 136.53367) (xy 212.355515 136.5474) (xy 212.355515 136.56113)
			(xy 212.355515 136.57486) (xy 212.355515 136.58859) (xy 212.355515 136.60233) (xy 212.355515 136.61606)
			(xy 212.355515 136.62979) (xy 212.355515 136.64352) (xy 212.355515 136.65725) (xy 212.355515 136.67098)
			(xy 212.355515 136.68472) (xy 212.355515 136.69845) (xy 212.355515 136.71218) (xy 212.355515 136.72591)
			(xy 212.355515 136.73964) (xy 212.355515 136.75337) (xy 212.355515 136.76711) (xy 212.355515 136.78084)
			(xy 212.355515 136.79457) (xy 212.355515 136.8083) (xy 212.355515 136.82203) (xy 212.355515 136.83576)
			(xy 212.355515 136.8495) (xy 212.355515 136.86323) (xy 212.355515 136.87696) (xy 212.355515 136.89069)
			(xy 212.355515 136.90442) (xy 212.355515 136.91816) (xy 212.355515 136.93189) (xy 212.355515 136.94562)
			(xy 212.355515 136.95935) (xy 212.355515 136.97308) (xy 212.369255 136.97308) (xy 212.369255 136.98682)
			(xy 212.382985 136.98682) (xy 212.382985 137.00055) (xy 212.396715 137.00055) (xy 212.396715 137.01428)
			(xy 213.069565 137.01428) (xy 213.069565 137.00055) (xy 213.083305 137.00055) (xy 213.083305 136.98682)
			(xy 213.097035 136.98682) (xy 213.097035 136.97308) (xy 213.097035 136.95935) (xy 213.097035 136.94562)
			(xy 213.110765 136.94562) (xy 213.110765 136.93189) (xy 213.110765 136.91816) (xy 213.110765 136.90442)
			(xy 213.110765 136.89069) (xy 213.110765 136.87696) (xy 213.110765 136.86323) (xy 213.110765 136.8495)
			(xy 213.110765 136.83576) (xy 213.110765 136.82203) (xy 213.110765 136.8083) (xy 213.110765 136.79457)
			(xy 213.110765 136.78084) (xy 213.110765 136.76711) (xy 213.110765 136.75337) (xy 213.110765 136.73964)
			(xy 213.110765 136.72591) (xy 213.110765 136.71218) (xy 213.110765 136.69845) (xy 213.110765 136.68472)
			(xy 213.110765 136.67098) (xy 213.110765 136.65725) (xy 213.110765 136.64352) (xy 213.110765 136.62979)
			(xy 213.110765 136.61606) (xy 213.110765 136.60233) (xy 213.110765 136.58859) (xy 213.110765 136.57486)
			(xy 213.110765 136.56113) (xy 213.110765 136.5474) (xy 213.110765 136.53367) (xy 213.110765 136.51994)
			(xy 213.110765 136.5062) (xy 213.110765 136.49247) (xy 213.110765 136.47874) (xy 213.110765 136.46501)
			(xy 213.110765 136.45128) (xy 213.110765 136.43755) (xy 213.110765 136.42381) (xy 213.110765 136.41008)
			(xy 213.110765 136.39635) (xy 213.110765 136.38262) (xy 213.110765 136.36889) (xy 213.110765 136.35515)
			(xy 213.110765 136.34142) (xy 213.110765 136.32769) (xy 213.110765 136.31396) (xy 213.110765 136.30023)
			(xy 213.110765 136.28649) (xy 213.110765 136.27276) (xy 213.110765 136.25903) (xy 213.110765 136.2453)
			(xy 213.110765 136.23157) (xy 213.110765 136.21784) (xy 213.110765 136.2041) (xy 213.110765 136.19037)
			(xy 213.110765 136.17664) (xy 213.110765 136.16291) (xy 213.110765 136.14918) (xy 213.110765 136.13545)
			(xy 213.110765 136.12171) (xy 213.110765 136.10798) (xy 213.110765 136.09425) (xy 213.110765 136.08052)
			(xy 213.110765 136.06679) (xy 213.110765 136.05306) (xy 213.110765 136.03932) (xy 213.110765 136.02559)
			(xy 213.110765 136.01186) (xy 213.110765 135.99813) (xy 213.110765 135.9844) (xy 213.110765 135.97067)
			(xy 213.110765 135.95693) (xy 213.110765 135.9432) (xy 213.110765 135.92947) (xy 213.110765 135.91574)
			(xy 213.110765 135.90201) (xy 213.110765 135.88827) (xy 213.110765 135.87454) (xy 213.110765 135.86081)
			(xy 213.110765 135.84708) (xy 213.110765 135.83335) (xy 213.110765 135.81961) (xy 213.110765 135.80588)
			(xy 213.110765 135.79215) (xy 213.110765 135.77842) (xy 213.110765 135.76469) (xy 213.110765 135.75096)
			(xy 213.110765 135.73722) (xy 213.110765 135.72349) (xy 213.110765 135.70976) (xy 213.110765 135.69603)
			(xy 213.110765 135.6823) (xy 213.110765 135.66857) (xy 213.110765 135.65483) (xy 213.110765 135.6411)
			(xy 213.110765 135.62737) (xy 213.110765 135.61364) (xy 213.110765 135.59991) (xy 213.110765 135.58618)
			(xy 213.110765 135.57244) (xy 213.110765 135.55871) (xy 213.110765 135.54498) (xy 213.110765 135.53125)
			(xy 213.110765 135.51752) (xy 213.110765 135.50379) (xy 213.110765 135.49005) (xy 213.110765 135.47632)
			(xy 213.110765 135.46259) (xy 213.110765 135.44886) (xy 213.110765 135.43513) (xy 213.110765 135.4214)
			(xy 213.110765 135.40766) (xy 213.110765 135.39393) (xy 213.110765 135.3802) (xy 213.110765 135.36647)
			(xy 213.110765 135.35274) (xy 213.110765 135.339) (xy 213.110765 135.32527) (xy 213.110765 135.31154)
			(xy 213.110765 135.29781) (xy 213.110765 135.28408) (xy 213.110765 135.27034) (xy 213.110765 135.25661)
			(xy 213.110765 135.24288) (xy 213.110765 135.22915) (xy 213.110765 135.21542) (xy 213.110765 135.20169)
			(xy 213.110765 135.18795) (xy 213.110765 135.17422) (xy 213.110765 135.16049) (xy 213.110765 135.14676)
			(xy 213.110765 135.13303) (xy 213.110765 135.1193) (xy 213.110765 135.10556) (xy 213.110765 135.09183)
			(xy 213.110765 135.0781) (xy 213.110765 135.06437) (xy 213.110765 135.05064) (xy 213.110765 135.03691)
			(xy 213.110765 135.02317) (xy 213.110765 135.00944) (xy 213.110765 134.99571) (xy 213.110765 134.98198)
			(xy 213.110765 134.96825) (xy 213.110765 134.95452) (xy 213.110765 134.94078) (xy 213.110765 134.92705)
			(xy 213.110765 134.91332) (xy 213.110765 134.89959) (xy 213.110765 134.88586) (xy 213.110765 134.87213)
			(xy 213.110765 134.85839) (xy 213.110765 134.84466) (xy 213.110765 134.83093) (xy 213.110765 134.8172)
			(xy 213.110765 134.80347) (xy 213.110765 134.78973) (xy 213.124495 134.78973) (xy 213.124495 134.776)
			(xy 213.138225 134.776) (xy 213.138225 134.76227) (xy 213.797355 134.76227) (xy 213.797355 134.74854)
			(xy 213.838545 134.74854) (xy 213.838545 134.73481) (xy 213.852275 134.73481) (xy 213.852275 134.72107)
			(xy 213.866005 134.72107) (xy 213.866005 134.70734) (xy 213.866005 134.69361) (xy 213.866005 134.67988)
			(xy 213.879745 134.67988) (xy 213.879745 134.66615) (xy 213.879745 134.65242) (xy 213.879745 134.63868)
			(xy 213.879745 134.62495) (xy 213.879745 134.61122) (xy 213.879745 134.59749) (xy 213.879745 134.58376)
			(xy 213.879745 134.57003) (xy 213.879745 134.55629) (xy 213.879745 134.54256) (xy 213.879745 134.52883)
			(xy 213.879745 134.5151) (xy 213.879745 134.50137) (xy 213.879745 134.48764) (xy 213.879745 134.4739)
			(xy 213.879745 134.46017) (xy 213.879745 134.44644) (xy 213.879745 134.43271) (xy 213.879745 134.41898)
			(xy 213.879745 134.40525) (xy 213.879745 134.39151) (xy 213.879745 134.37778) (xy 213.879745 134.36405)
			(xy 213.879745 134.35032) (xy 213.879745 134.33659) (xy 213.879745 134.32286) (xy 213.879745 134.30912)
			(xy 213.879745 134.29539) (xy 213.879745 134.28166) (xy 213.879745 134.26793) (xy 213.879745 134.2542)
			(xy 213.879745 134.24046) (xy 213.879745 134.22673) (xy 213.879745 134.213) (xy 213.879745 134.19927)
			(xy 213.879745 134.18554) (xy 213.879745 134.1718) (xy 213.879745 134.15807) (xy 213.879745 134.14434)
			(xy 213.879745 134.13061) (xy 213.879745 134.11688) (xy 213.879745 134.10315) (xy 213.866005 134.10315)
			(xy 213.866005 134.08941) (xy 214.044525 134.08941) (xy 214.044525 134.10315) (xy 214.044525 134.11688)
			(xy 214.044525 134.13061) (xy 214.044525 134.14434) (xy 214.044525 134.15807) (xy 214.044525 134.1718)
			(xy 214.044525 134.18554) (xy 214.044525 134.19927) (xy 214.044525 134.213) (xy 214.044525 134.22673)
			(xy 214.044525 134.24046) (xy 214.044525 134.2542) (xy 214.044525 134.26793) (xy 214.044525 134.28166)
			(xy 214.044525 134.29539) (xy 214.044525 134.30912) (xy 214.044525 134.32286) (xy 214.044525 134.33659)
			(xy 214.044525 134.35032) (xy 214.044525 134.36405) (xy 214.044525 134.37778) (xy 214.044525 134.39151)
			(xy 214.044525 134.40525) (xy 214.044525 134.41898) (xy 214.044525 134.43271) (xy 214.044525 134.44644)
			(xy 214.044525 134.46017) (xy 214.044525 134.4739) (xy 214.044525 134.48764) (xy 214.044525 134.50137)
			(xy 214.044525 134.5151) (xy 214.044525 134.52883) (xy 214.044525 134.54256) (xy 214.044525 134.55629)
			(xy 214.044525 134.57003) (xy 214.044525 134.58376) (xy 214.044525 134.59749) (xy 214.044525 134.61122)
			(xy 214.044525 134.62495) (xy 214.044525 134.63868) (xy 214.044525 134.65242) (xy 214.044525 134.66615)
			(xy 214.044525 134.67988) (xy 214.044525 134.69361) (xy 214.044525 134.70734) (xy 214.044525 134.72107)
			(xy 214.044525 134.73481) (xy 214.044525 134.74854) (xy 214.044525 134.76227) (xy 214.044525 134.776)
			(xy 214.044525 134.78973) (xy 214.044525 134.80347) (xy 214.044525 134.8172) (xy 214.044525 134.83093)
			(xy 214.044525 134.84466) (xy 214.044525 134.85839) (xy 214.044525 134.87213) (xy 214.044525 134.88586)
			(xy 214.044525 134.89959) (xy 214.044525 134.91332) (xy 214.044525 134.92705) (xy 214.044525 134.94078)
			(xy 214.044525 134.95452) (xy 214.044525 134.96825) (xy 214.044525 134.98198) (xy 214.044525 134.99571)
			(xy 214.044525 135.00944) (xy 214.044525 135.02317) (xy 214.044525 135.03691) (xy 214.044525 135.05064)
			(xy 214.044525 135.06437) (xy 214.044525 135.0781) (xy 214.044525 135.09183) (xy 214.044525 135.10556)
			(xy 214.044525 135.1193) (xy 214.044525 135.13303) (xy 214.044525 135.14676) (xy 214.044525 135.16049)
			(xy 214.044525 135.17422) (xy 214.044525 135.18795) (xy 214.044525 135.20169) (xy 214.044525 135.21542)
			(xy 214.044525 135.22915) (xy 214.044525 135.24288) (xy 214.044525 135.25661) (xy 214.044525 135.27034)
			(xy 214.044525 135.28408) (xy 214.044525 135.29781) (xy 214.044525 135.31154) (xy 214.044525 135.32527)
			(xy 214.044525 135.339) (xy 214.044525 135.35274) (xy 214.044525 135.36647) (xy 214.044525 135.3802)
			(xy 214.044525 135.39393) (xy 214.044525 135.40766) (xy 214.044525 135.4214) (xy 214.044525 135.43513)
			(xy 214.044525 135.44886) (xy 214.044525 135.46259) (xy 214.044525 135.47632) (xy 214.044525 135.49005)
			(xy 214.044525 135.50379) (xy 214.044525 135.51752) (xy 214.044525 135.53125) (xy 214.044525 135.54498)
			(xy 214.044525 135.55871) (xy 214.044525 135.57244) (xy 214.044525 135.58618) (xy 214.044525 135.59991)
			(xy 214.044525 135.61364) (xy 214.044525 135.62737) (xy 214.044525 135.6411) (xy 214.044525 135.65483)
			(xy 214.044525 135.66857) (xy 214.044525 135.6823) (xy 214.044525 135.69603) (xy 214.044525 135.70976)
			(xy 214.044525 135.72349) (xy 214.044525 135.73722) (xy 214.044525 135.75096) (xy 214.044525 135.76469)
			(xy 214.044525 135.77842) (xy 214.044525 135.79215) (xy 214.044525 135.80588) (xy 214.044525 135.81961)
			(xy 214.044525 135.83335) (xy 214.044525 135.84708) (xy 214.044525 135.86081) (xy 214.044525 135.87454)
			(xy 214.044525 135.88827) (xy 214.044525 135.90201) (xy 214.044525 135.91574) (xy 214.044525 135.92947)
			(xy 214.044525 135.9432) (xy 214.044525 135.95693) (xy 214.044525 135.97067) (xy 214.044525 135.9844)
			(xy 214.044525 135.99813) (xy 214.044525 136.01186) (xy 214.044525 136.02559) (xy 214.044525 136.03932)
			(xy 214.044525 136.05306) (xy 214.044525 136.06679) (xy 214.044525 136.08052) (xy 214.044525 136.09425)
			(xy 214.044525 136.10798) (xy 214.044525 136.12171) (xy 214.044525 136.13545) (xy 214.044525 136.14918)
			(xy 214.044525 136.16291) (xy 214.044525 136.17664) (xy 214.044525 136.19037) (xy 214.044525 136.2041)
			(xy 214.044525 136.21784) (xy 214.044525 136.23157) (xy 214.044525 136.2453) (xy 214.044525 136.25903)
			(xy 214.044525 136.27276) (xy 214.044525 136.28649) (xy 214.044525 136.30023) (xy 214.044525 136.31396)
			(xy 214.044525 136.32769) (xy 214.044525 136.34142) (xy 214.044525 136.35515) (xy 214.044525 136.36889)
			(xy 214.044525 136.38262) (xy 214.044525 136.39635) (xy 214.044525 136.41008) (xy 214.044525 136.42381)
			(xy 214.044525 136.43755) (xy 214.044525 136.45128) (xy 214.044525 136.46501) (xy 214.044525 136.47874)
			(xy 214.044525 136.49247) (xy 214.044525 136.5062) (xy 214.044525 136.51994) (xy 214.044525 136.53367)
			(xy 214.044525 136.5474) (xy 214.044525 136.56113) (xy 214.044525 136.57486) (xy 214.044525 136.58859)
			(xy 214.044525 136.60233) (xy 214.044525 136.61606) (xy 214.044525 136.62979) (xy 214.044525 136.64352)
			(xy 214.044525 136.65725) (xy 214.044525 136.67098) (xy 214.044525 136.68472) (xy 214.044525 136.69845)
			(xy 214.044525 136.71218) (xy 214.044525 136.72591) (xy 214.044525 136.73964) (xy 214.044525 136.75337)
			(xy 214.044525 136.76711) (xy 214.044525 136.78084) (xy 214.044525 136.79457) (xy 214.044525 136.8083)
			(xy 214.044525 136.82203) (xy 214.044525 136.83576) (xy 214.044525 136.8495) (xy 214.044525 136.86323)
			(xy 214.044525 136.87696) (xy 214.044525 136.89069) (xy 214.044525 136.90442) (xy 214.044525 136.91816)
			(xy 214.044525 136.93189) (xy 214.044525 136.94562) (xy 214.044525 136.95935) (xy 214.058255 136.95935)
			(xy 214.058255 136.97308) (xy 214.058255 136.98682) (xy 214.071985 136.98682) (xy 214.071985 137.00055)
			(xy 214.085715 137.00055) (xy 214.085715 137.01428) (xy 214.772305 137.01428) (xy 214.772305 137.00055)
			(xy 214.786035 137.00055) (xy 214.786035 136.98682) (xy 214.799765 136.98682) (xy 214.799765 136.97308)
			(xy 214.799765 136.95935) (xy 214.799765 136.94562) (xy 214.799765 136.93189) (xy 214.799765 136.91816)
			(xy 214.799765 136.90442) (xy 214.799765 136.89069) (xy 214.799765 136.87696) (xy 214.799765 136.86323)
			(xy 214.799765 136.8495) (xy 214.799765 136.83576) (xy 214.799765 136.82203) (xy 214.799765 136.8083)
			(xy 214.799765 136.79457) (xy 214.799765 136.78084) (xy 214.799765 136.76711) (xy 214.799765 136.75337)
			(xy 214.799765 136.73964) (xy 214.799765 136.72591) (xy 214.799765 136.71218) (xy 214.799765 136.69845)
			(xy 214.799765 136.68472) (xy 214.799765 136.67098) (xy 214.799765 136.65725) (xy 214.799765 136.64352)
			(xy 214.799765 136.62979) (xy 214.799765 136.61606) (xy 214.799765 136.60233) (xy 214.799765 136.58859)
			(xy 214.799765 136.57486) (xy 214.799765 136.56113) (xy 214.799765 136.5474) (xy 214.799765 136.53367)
			(xy 214.799765 136.51994) (xy 214.799765 136.5062) (xy 214.799765 136.49247) (xy 214.799765 136.47874)
			(xy 214.799765 136.46501) (xy 214.799765 136.45128) (xy 214.799765 136.43755) (xy 214.799765 136.42381)
			(xy 214.799765 136.41008) (xy 214.799765 136.39635) (xy 214.799765 136.38262) (xy 214.799765 136.36889)
			(xy 214.799765 136.35515) (xy 214.799765 136.34142) (xy 214.799765 136.32769) (xy 214.799765 136.31396)
			(xy 214.799765 136.30023) (xy 214.799765 136.28649) (xy 214.799765 136.27276) (xy 214.799765 136.25903)
			(xy 214.799765 136.2453) (xy 214.799765 136.23157) (xy 214.799765 136.21784) (xy 214.799765 136.2041)
			(xy 214.799765 136.19037) (xy 214.799765 136.17664) (xy 214.799765 136.16291) (xy 214.799765 136.14918)
			(xy 214.799765 136.13545) (xy 214.799765 136.12171) (xy 214.799765 136.10798) (xy 214.799765 136.09425)
			(xy 214.799765 136.08052) (xy 214.799765 136.06679) (xy 214.799765 136.05306) (xy 214.799765 136.03932)
			(xy 214.799765 136.02559) (xy 214.799765 136.01186) (xy 214.799765 135.99813) (xy 214.799765 135.9844)
			(xy 214.799765 135.97067) (xy 214.799765 135.95693) (xy 214.799765 135.9432) (xy 214.799765 135.92947)
			(xy 214.799765 135.91574) (xy 214.799765 135.90201) (xy 214.799765 135.88827) (xy 214.799765 135.87454)
			(xy 214.799765 135.86081) (xy 214.799765 135.84708) (xy 214.799765 135.83335) (xy 214.799765 135.81961)
			(xy 214.799765 135.80588) (xy 214.799765 135.79215) (xy 214.799765 135.77842) (xy 214.799765 135.76469)
			(xy 214.799765 135.75096) (xy 214.799765 135.73722) (xy 214.799765 135.72349) (xy 214.799765 135.70976)
			(xy 214.799765 135.69603) (xy 214.799765 135.6823) (xy 214.799765 135.66857) (xy 214.799765 135.65483)
			(xy 214.799765 135.6411) (xy 214.799765 135.62737) (xy 214.799765 135.61364) (xy 214.799765 135.59991)
			(xy 214.799765 135.58618) (xy 214.799765 135.57244) (xy 214.799765 135.55871) (xy 214.799765 135.54498)
			(xy 214.799765 135.53125) (xy 214.799765 135.51752) (xy 214.799765 135.50379) (xy 214.799765 135.49005)
			(xy 214.799765 135.47632) (xy 214.799765 135.46259) (xy 214.799765 135.44886) (xy 214.799765 135.43513)
			(xy 214.799765 135.4214) (xy 214.799765 135.40766) (xy 214.799765 135.39393) (xy 214.799765 135.3802)
			(xy 214.799765 135.36647) (xy 214.799765 135.35274) (xy 214.799765 135.339) (xy 214.799765 135.32527)
			(xy 214.799765 135.31154) (xy 214.799765 135.29781) (xy 214.799765 135.28408) (xy 214.799765 135.27034)
			(xy 214.799765 135.25661) (xy 214.799765 135.24288) (xy 214.799765 135.22915) (xy 214.799765 135.21542)
			(xy 214.799765 135.20169) (xy 214.799765 135.18795) (xy 214.799765 135.17422) (xy 214.799765 135.16049)
			(xy 214.799765 135.14676) (xy 214.799765 135.13303) (xy 214.799765 135.1193) (xy 214.799765 135.10556)
			(xy 214.799765 135.09183) (xy 214.799765 135.0781) (xy 214.799765 135.06437) (xy 214.799765 135.05064)
			(xy 214.799765 135.03691) (xy 214.799765 135.02317) (xy 214.799765 135.00944) (xy 214.799765 134.99571)
			(xy 214.799765 134.98198) (xy 214.799765 134.96825) (xy 214.799765 134.95452) (xy 214.799765 134.94078)
			(xy 214.799765 134.92705) (xy 214.799765 134.91332) (xy 214.799765 134.89959) (xy 214.799765 134.88586)
			(xy 214.799765 134.87213) (xy 214.799765 134.85839) (xy 214.799765 134.84466) (xy 214.799765 134.83093)
			(xy 214.799765 134.8172) (xy 214.799765 134.80347) (xy 214.799765 134.78973) (xy 214.799765 134.776)
			(xy 214.799765 134.76227) (xy 214.799765 134.74854) (xy 214.799765 134.73481) (xy 214.799765 134.72107)
			(xy 214.799765 134.70734) (xy 214.799765 134.69361) (xy 214.799765 134.67988) (xy 214.799765 134.66615)
			(xy 214.799765 134.65242) (xy 214.799765 134.63868) (xy 214.799765 134.62495) (xy 214.799765 134.61122)
			(xy 214.799765 134.59749) (xy 214.799765 134.58376) (xy 214.799765 134.57003) (xy 214.799765 134.55629)
			(xy 214.799765 134.54256) (xy 214.799765 134.52883) (xy 214.799765 134.5151) (xy 214.799765 134.50137)
			(xy 214.799765 134.48764) (xy 214.799765 134.4739) (xy 214.799765 134.46017) (xy 214.799765 134.44644)
			(xy 214.799765 134.43271) (xy 214.799765 134.41898) (xy 214.799765 134.40525) (xy 214.799765 134.39151)
			(xy 214.799765 134.37778) (xy 214.799765 134.36405) (xy 214.799765 134.35032) (xy 214.799765 134.33659)
			(xy 214.799765 134.32286) (xy 214.799765 134.30912) (xy 214.799765 134.29539) (xy 214.799765 134.28166)
			(xy 214.799765 134.26793) (xy 214.799765 134.2542) (xy 214.799765 134.24046) (xy 214.799765 134.22673)
			(xy 214.799765 134.213) (xy 214.799765 134.19927) (xy 214.799765 134.18554) (xy 214.799765 134.1718)
			(xy 214.799765 134.15807) (xy 214.799765 134.14434) (xy 214.799765 134.13061) (xy 214.799765 134.11688)
			(xy 214.799765 134.10315) (xy 214.799765 134.08941) (xy 214.799765 134.07568) (xy 215.143065 134.07568)
			(xy 215.143065 134.08941) (xy 215.143065 134.10315) (xy 215.143065 134.11688) (xy 215.143065 134.13061)
			(xy 215.143065 134.14434) (xy 215.143065 134.15807) (xy 215.143065 134.1718) (xy 215.143065 134.18554)
			(xy 215.143065 134.19927) (xy 215.143065 134.213) (xy 215.143065 134.22673) (xy 215.143065 134.24046)
			(xy 215.143065 134.2542) (xy 215.143065 134.26793) (xy 215.143065 134.28166) (xy 215.143065 134.29539)
			(xy 215.143065 134.30912) (xy 215.143065 134.32286) (xy 215.143065 134.33659) (xy 215.143065 134.35032)
			(xy 215.143065 134.36405) (xy 215.143065 134.37778) (xy 215.143065 134.39151) (xy 215.143065 134.40525)
			(xy 215.143065 134.41898) (xy 215.143065 134.43271) (xy 215.143065 134.44644) (xy 215.143065 134.46017)
			(xy 215.143065 134.4739) (xy 215.143065 134.48764) (xy 215.143065 134.50137) (xy 215.143065 134.5151)
			(xy 215.143065 134.52883) (xy 215.143065 134.54256) (xy 215.143065 134.55629) (xy 215.143065 134.57003)
			(xy 215.143065 134.58376) (xy 215.143065 134.59749) (xy 215.143065 134.61122) (xy 215.143065 134.62495)
			(xy 215.143065 134.63868) (xy 215.143065 134.65242) (xy 215.143065 134.66615) (xy 215.143065 134.67988)
			(xy 215.143065 134.69361) (xy 215.143065 134.70734) (xy 215.143065 134.72107) (xy 215.143065 134.73481)
			(xy 215.143065 134.74854) (xy 215.143065 134.76227) (xy 215.143065 134.776) (xy 215.143065 134.78973)
			(xy 215.143065 134.80347) (xy 215.143065 134.8172) (xy 215.143065 134.83093) (xy 215.143065 134.84466)
			(xy 215.143065 134.85839) (xy 215.143065 134.87213) (xy 215.143065 134.88586) (xy 215.143065 134.89959)
			(xy 215.143065 134.91332) (xy 215.143065 134.92705) (xy 215.143065 134.94078) (xy 215.143065 134.95452)
			(xy 215.143065 134.96825) (xy 215.143065 134.98198) (xy 215.143065 134.99571) (xy 215.143065 135.00944)
			(xy 215.143065 135.02317) (xy 215.143065 135.03691) (xy 215.143065 135.05064) (xy 215.143065 135.06437)
			(xy 215.143065 135.0781) (xy 215.143065 135.09183) (xy 215.143065 135.10556) (xy 215.143065 135.1193)
			(xy 215.143065 135.13303) (xy 215.143065 135.14676) (xy 215.143065 135.16049) (xy 215.143065 135.17422)
			(xy 215.143065 135.18795) (xy 215.143065 135.20169) (xy 215.143065 135.21542) (xy 215.143065 135.22915)
			(xy 215.143065 135.24288) (xy 215.143065 135.25661) (xy 215.143065 135.27034) (xy 215.143065 135.28408)
			(xy 215.143065 135.29781) (xy 215.143065 135.31154) (xy 215.143065 135.32527) (xy 215.143065 135.339)
			(xy 215.143065 135.35274) (xy 215.143065 135.36647) (xy 215.143065 135.3802) (xy 215.143065 135.39393)
			(xy 215.143065 135.40766) (xy 215.143065 135.4214) (xy 215.143065 135.43513) (xy 215.143065 135.44886)
			(xy 215.143065 135.46259) (xy 215.143065 135.47632) (xy 215.143065 135.49005) (xy 215.143065 135.50379)
			(xy 215.143065 135.51752) (xy 215.143065 135.53125) (xy 215.143065 135.54498) (xy 215.143065 135.55871)
			(xy 215.143065 135.57244) (xy 215.143065 135.58618) (xy 215.143065 135.59991) (xy 215.143065 135.61364)
			(xy 215.143065 135.62737) (xy 215.143065 135.6411) (xy 215.143065 135.65483) (xy 215.143065 135.66857)
			(xy 215.143065 135.6823) (xy 215.143065 135.69603) (xy 215.143065 135.70976) (xy 215.143065 135.72349)
			(xy 215.143065 135.73722) (xy 215.143065 135.75096) (xy 215.143065 135.76469) (xy 215.143065 135.77842)
			(xy 215.143065 135.79215) (xy 215.143065 135.80588) (xy 215.143065 135.81961) (xy 215.143065 135.83335)
			(xy 215.143065 135.84708) (xy 215.143065 135.86081) (xy 215.143065 135.87454) (xy 215.143065 135.88827)
			(xy 215.143065 135.90201) (xy 215.143065 135.91574) (xy 215.143065 135.92947) (xy 215.143065 135.9432)
			(xy 215.143065 135.95693) (xy 215.143065 135.97067) (xy 215.143065 135.9844) (xy 215.143065 135.99813)
			(xy 215.143065 136.01186) (xy 215.143065 136.02559) (xy 215.143065 136.03932) (xy 215.143065 136.05306)
			(xy 215.143065 136.06679) (xy 215.143065 136.08052) (xy 215.143065 136.09425) (xy 215.143065 136.10798)
			(xy 215.143065 136.12171) (xy 215.143065 136.13545) (xy 215.143065 136.14918) (xy 215.143065 136.16291)
			(xy 215.143065 136.17664) (xy 215.143065 136.19037) (xy 215.143065 136.2041) (xy 215.143065 136.21784)
			(xy 215.143065 136.23157) (xy 215.143065 136.2453) (xy 215.143065 136.25903) (xy 215.143065 136.27276)
			(xy 215.143065 136.28649) (xy 215.143065 136.30023) (xy 215.143065 136.31396) (xy 215.143065 136.32769)
			(xy 215.143065 136.34142) (xy 215.143065 136.35515) (xy 215.143065 136.36889) (xy 215.143065 136.38262)
			(xy 215.143065 136.39635) (xy 215.143065 136.41008) (xy 215.143065 136.42381) (xy 215.143065 136.43755)
			(xy 215.143065 136.45128) (xy 215.143065 136.46501) (xy 215.143065 136.47874) (xy 215.143065 136.49247)
			(xy 215.143065 136.5062) (xy 215.143065 136.51994) (xy 215.143065 136.53367) (xy 215.143065 136.5474)
			(xy 215.143065 136.56113) (xy 215.143065 136.57486) (xy 215.143065 136.58859) (xy 215.143065 136.60233)
			(xy 215.143065 136.61606) (xy 215.143065 136.62979) (xy 215.143065 136.64352) (xy 215.143065 136.65725)
			(xy 215.143065 136.67098) (xy 215.143065 136.68472) (xy 215.143065 136.69845) (xy 215.143065 136.71218)
			(xy 215.143065 136.72591) (xy 215.143065 136.73964) (xy 215.143065 136.75337) (xy 215.143065 136.76711)
			(xy 215.143065 136.78084) (xy 215.143065 136.79457) (xy 215.143065 136.8083) (xy 215.143065 136.82203)
			(xy 215.143065 136.83576) (xy 215.143065 136.8495) (xy 215.143065 136.86323) (xy 215.143065 136.87696)
			(xy 215.143065 136.89069) (xy 215.143065 136.90442) (xy 215.143065 136.91816) (xy 215.143065 136.93189)
			(xy 215.143065 136.94562) (xy 215.143065 136.95935) (xy 215.143065 136.97308) (xy 215.156795 136.97308)
			(xy 215.156795 136.98682) (xy 215.156795 137.00055) (xy 215.184255 137.00055) (xy 215.184255 137.01428)
			(xy 215.857115 137.01428) (xy 215.857115 137.00055) (xy 215.870845 137.00055) (xy 215.870845 136.98682)
			(xy 215.884575 136.98682) (xy 215.884575 136.97308) (xy 215.884575 136.95935) (xy 215.898305 136.95935)
			(xy 215.898305 136.94562) (xy 215.898305 136.93189) (xy 215.898305 136.91816) (xy 215.898305 136.90442)
			(xy 215.898305 136.89069) (xy 215.898305 136.87696) (xy 215.898305 136.86323) (xy 215.898305 136.8495)
			(xy 215.898305 136.83576) (xy 215.898305 136.82203) (xy 215.898305 136.8083) (xy 215.898305 136.79457)
			(xy 215.898305 136.78084) (xy 215.898305 136.76711) (xy 215.898305 136.75337) (xy 215.898305 136.73964)
			(xy 215.898305 136.72591) (xy 215.898305 136.71218) (xy 215.898305 136.69845) (xy 215.898305 136.68472)
			(xy 215.898305 136.67098) (xy 215.898305 136.65725) (xy 215.898305 136.64352) (xy 215.898305 136.62979)
			(xy 215.898305 136.61606) (xy 215.898305 136.60233) (xy 215.898305 136.58859) (xy 215.898305 136.57486)
			(xy 215.898305 136.56113) (xy 215.898305 136.5474) (xy 215.898305 136.53367) (xy 215.898305 136.51994)
			(xy 215.898305 136.5062) (xy 215.898305 136.49247) (xy 215.898305 136.47874) (xy 215.898305 136.46501)
			(xy 215.898305 136.45128) (xy 215.898305 136.43755) (xy 215.898305 136.42381) (xy 215.898305 136.41008)
			(xy 215.898305 136.39635) (xy 215.898305 136.38262) (xy 215.898305 136.36889) (xy 215.898305 136.35515)
			(xy 215.898305 136.34142) (xy 215.898305 136.32769) (xy 215.898305 136.31396) (xy 215.898305 136.30023)
			(xy 215.898305 136.28649) (xy 215.898305 136.27276) (xy 215.898305 136.25903) (xy 215.898305 136.2453)
			(xy 215.898305 136.23157) (xy 215.898305 136.21784) (xy 215.898305 136.2041) (xy 215.898305 136.19037)
			(xy 215.898305 136.17664) (xy 215.898305 136.16291) (xy 215.898305 136.14918) (xy 215.898305 136.13545)
			(xy 215.898305 136.12171) (xy 215.898305 136.10798) (xy 215.898305 136.09425) (xy 215.898305 136.08052)
			(xy 215.898305 136.06679) (xy 215.898305 136.05306) (xy 215.898305 136.03932) (xy 215.898305 136.02559)
			(xy 215.898305 136.01186) (xy 215.898305 135.99813) (xy 215.898305 135.9844) (xy 215.898305 135.97067)
			(xy 215.898305 135.95693) (xy 215.898305 135.9432) (xy 215.898305 135.92947) (xy 215.898305 135.91574)
			(xy 215.898305 135.90201) (xy 215.898305 135.88827) (xy 215.898305 135.87454) (xy 215.898305 135.86081)
			(xy 215.898305 135.84708) (xy 215.898305 135.83335) (xy 215.898305 135.81961) (xy 215.898305 135.80588)
			(xy 215.898305 135.79215) (xy 215.898305 135.77842) (xy 215.898305 135.76469) (xy 215.898305 135.75096)
			(xy 215.898305 135.73722) (xy 215.898305 135.72349) (xy 215.898305 135.70976) (xy 215.898305 135.69603)
			(xy 215.898305 135.6823) (xy 215.898305 135.66857) (xy 215.898305 135.65483) (xy 215.898305 135.6411)
			(xy 215.898305 135.62737) (xy 215.898305 135.61364) (xy 215.898305 135.59991) (xy 215.898305 135.58618)
			(xy 215.898305 135.57244) (xy 215.898305 135.55871) (xy 215.898305 135.54498) (xy 215.898305 135.53125)
			(xy 215.898305 135.51752) (xy 215.898305 135.50379) (xy 215.898305 135.49005) (xy 215.898305 135.47632)
			(xy 215.898305 135.46259) (xy 215.898305 135.44886) (xy 215.898305 135.43513) (xy 215.898305 135.4214)
			(xy 215.898305 135.40766) (xy 215.898305 135.39393) (xy 215.898305 135.3802) (xy 215.898305 135.36647)
			(xy 215.898305 135.35274) (xy 215.898305 135.339) (xy 215.898305 135.32527) (xy 215.898305 135.31154)
			(xy 215.898305 135.29781) (xy 215.898305 135.28408) (xy 215.898305 135.27034) (xy 215.898305 135.25661)
			(xy 215.898305 135.24288) (xy 215.898305 135.22915) (xy 215.898305 135.21542) (xy 215.898305 135.20169)
			(xy 215.898305 135.18795) (xy 215.898305 135.17422) (xy 215.898305 135.16049) (xy 215.898305 135.14676)
			(xy 215.898305 135.13303) (xy 215.898305 135.1193) (xy 215.898305 135.10556) (xy 215.898305 135.09183)
			(xy 215.898305 135.0781) (xy 215.898305 135.06437) (xy 215.898305 135.05064) (xy 215.898305 135.03691)
			(xy 215.898305 135.02317) (xy 215.898305 135.00944) (xy 215.898305 134.99571) (xy 215.898305 134.98198)
			(xy 215.898305 134.96825) (xy 215.898305 134.95452) (xy 215.898305 134.94078) (xy 215.898305 134.92705)
			(xy 215.898305 134.91332) (xy 215.898305 134.89959) (xy 215.898305 134.88586) (xy 215.898305 134.87213)
			(xy 215.898305 134.85839) (xy 215.898305 134.84466) (xy 215.898305 134.83093) (xy 215.898305 134.8172)
			(xy 215.898305 134.80347) (xy 215.898305 134.78973) (xy 215.898305 134.776) (xy 215.898305 134.76227)
			(xy 216.365185 134.76227) (xy 216.365185 134.776) (xy 216.365185 134.78973) (xy 216.365185 134.80347)
			(xy 216.365185 134.8172) (xy 216.365185 134.83093) (xy 216.365185 134.84466) (xy 216.365185 134.85839)
			(xy 216.365185 134.87213) (xy 216.365185 134.88586) (xy 216.365185 134.89959) (xy 216.365185 134.91332)
			(xy 216.365185 134.92705) (xy 216.365185 134.94078) (xy 216.365185 134.95452) (xy 216.365185 134.96825)
			(xy 216.365185 134.98198) (xy 216.365185 134.99571) (xy 216.365185 135.00944) (xy 216.365185 135.02317)
			(xy 216.365185 135.03691) (xy 216.365185 135.05064) (xy 216.365185 135.06437) (xy 216.365185 135.0781)
			(xy 216.365185 135.09183) (xy 216.365185 135.10556) (xy 216.365185 135.1193) (xy 216.365185 135.13303)
			(xy 216.365185 135.14676) (xy 216.365185 135.16049) (xy 216.365185 135.17422) (xy 216.365185 135.18795)
			(xy 216.365185 135.20169) (xy 216.365185 135.21542) (xy 216.365185 135.22915) (xy 216.365185 135.24288)
			(xy 216.365185 135.25661) (xy 216.365185 135.27034) (xy 216.365185 135.28408) (xy 216.365185 135.29781)
			(xy 216.365185 135.31154) (xy 216.365185 135.32527) (xy 216.365185 135.339) (xy 216.365185 135.35274)
			(xy 216.365185 135.36647) (xy 216.365185 135.3802) (xy 216.365185 135.39393) (xy 216.365185 135.40766)
			(xy 216.365185 135.4214) (xy 216.365185 135.43513) (xy 216.365185 135.44886) (xy 216.365185 135.46259)
			(xy 216.365185 135.47632) (xy 216.365185 135.49005) (xy 216.365185 135.50379) (xy 216.365185 135.51752)
			(xy 216.365185 135.53125) (xy 216.365185 135.54498) (xy 216.365185 135.55871) (xy 216.365185 135.57244)
			(xy 216.365185 135.58618) (xy 216.365185 135.59991) (xy 216.365185 135.61364) (xy 216.365185 135.62737)
			(xy 216.365185 135.6411) (xy 216.365185 135.65483) (xy 216.365185 135.66857) (xy 216.365185 135.6823)
			(xy 216.365185 135.69603) (xy 216.365185 135.70976) (xy 216.365185 135.72349) (xy 216.365185 135.73722)
			(xy 216.365185 135.75096) (xy 216.365185 135.76469) (xy 216.365185 135.77842) (xy 216.365185 135.79215)
			(xy 216.365185 135.80588) (xy 216.365185 135.81961) (xy 216.365185 135.83335) (xy 216.365185 135.84708)
			(xy 216.365185 135.86081) (xy 216.365185 135.87454) (xy 216.365185 135.88827) (xy 216.365185 135.90201)
			(xy 216.365185 135.91574) (xy 216.365185 135.92947) (xy 216.365185 135.9432) (xy 216.365185 135.95693)
			(xy 216.365185 135.97067) (xy 216.365185 135.9844) (xy 216.365185 135.99813) (xy 216.365185 136.01186)
			(xy 216.365185 136.02559) (xy 216.365185 136.03932) (xy 216.365185 136.05306) (xy 216.365185 136.06679)
			(xy 216.365185 136.08052) (xy 216.365185 136.09425) (xy 216.365185 136.10798) (xy 216.365185 136.12171)
			(xy 216.365185 136.13545) (xy 216.365185 136.14918) (xy 216.365185 136.16291) (xy 216.365185 136.17664)
			(xy 216.365185 136.19037) (xy 216.365185 136.2041) (xy 216.365185 136.21784) (xy 216.365185 136.23157)
			(xy 216.365185 136.2453) (xy 216.365185 136.25903) (xy 216.365185 136.27276) (xy 216.365185 136.28649)
			(xy 216.365185 136.30023) (xy 216.365185 136.31396) (xy 216.365185 136.32769) (xy 216.365185 136.34142)
			(xy 216.365185 136.35515) (xy 216.365185 136.36889) (xy 216.365185 136.38262) (xy 216.365185 136.39635)
			(xy 216.365185 136.41008) (xy 216.365185 136.42381) (xy 216.365185 136.43755) (xy 216.365185 136.45128)
			(xy 216.365185 136.46501) (xy 216.365185 136.47874) (xy 216.365185 136.49247) (xy 216.365185 136.5062)
			(xy 216.365185 136.51994) (xy 216.365185 136.53367) (xy 216.365185 136.5474) (xy 216.365185 136.56113)
			(xy 216.365185 136.57486) (xy 216.365185 136.58859) (xy 216.365185 136.60233) (xy 216.365185 136.61606)
			(xy 216.365185 136.62979) (xy 216.365185 136.64352) (xy 216.365185 136.65725) (xy 216.365185 136.67098)
			(xy 216.365185 136.68472) (xy 216.365185 136.69845) (xy 216.365185 136.71218) (xy 216.365185 136.72591)
			(xy 216.365185 136.73964) (xy 216.365185 136.75337) (xy 216.365185 136.76711) (xy 216.365185 136.78084)
			(xy 216.365185 136.79457) (xy 216.365185 136.8083) (xy 216.365185 136.82203) (xy 216.365185 136.83576)
			(xy 216.365185 136.8495) (xy 216.365185 136.86323) (xy 216.365185 136.87696) (xy 216.365185 136.89069)
			(xy 216.365185 136.90442) (xy 216.365185 136.91816) (xy 216.365185 136.93189) (xy 216.365185 136.94562)
			(xy 216.365185 136.95935) (xy 216.378925 136.95935) (xy 216.378925 136.97308) (xy 216.378925 136.98682)
			(xy 216.392655 136.98682) (xy 216.392655 137.00055) (xy 216.420115 137.00055) (xy 216.420115 137.01428)
			(xy 217.024315 137.01428) (xy 217.024315 137.00055) (xy 217.038045 137.00055) (xy 217.038045 136.98682)
			(xy 217.051775 136.98682) (xy 217.051775 136.97308) (xy 217.065505 136.97308) (xy 217.065505 136.95935)
			(xy 217.065505 136.94562) (xy 217.065505 136.93189) (xy 217.065505 136.91816) (xy 217.065505 136.90442)
			(xy 217.065505 136.89069) (xy 217.065505 136.87696) (xy 217.065505 136.86323) (xy 217.065505 136.8495)
			(xy 217.065505 136.83576) (xy 217.065505 136.82203) (xy 217.065505 136.8083) (xy 217.065505 136.79457)
			(xy 217.065505 136.78084) (xy 217.065505 136.76711) (xy 217.065505 136.75337) (xy 217.065505 136.73964)
			(xy 217.065505 136.72591) (xy 217.065505 136.71218) (xy 217.065505 136.69845) (xy 217.065505 136.68472)
			(xy 217.065505 136.67098) (xy 217.065505 136.65725) (xy 217.065505 136.64352) (xy 217.065505 136.62979)
			(xy 217.065505 136.61606) (xy 217.065505 136.60233) (xy 217.065505 136.58859) (xy 217.065505 136.57486)
			(xy 217.065505 136.56113) (xy 217.065505 136.5474) (xy 217.065505 136.53367) (xy 217.065505 136.51994)
			(xy 217.065505 136.5062) (xy 217.065505 136.49247) (xy 217.065505 136.47874) (xy 217.065505 136.46501)
			(xy 217.065505 136.45128) (xy 217.065505 136.43755) (xy 217.065505 136.42381) (xy 217.065505 136.41008)
			(xy 217.065505 136.39635) (xy 217.065505 136.38262) (xy 217.065505 136.36889) (xy 217.065505 136.35515)
			(xy 217.065505 136.34142) (xy 217.065505 136.32769) (xy 217.065505 136.31396) (xy 217.065505 136.30023)
			(xy 217.065505 136.28649) (xy 217.065505 136.27276) (xy 217.065505 136.25903) (xy 217.065505 136.2453)
			(xy 217.065505 136.23157) (xy 217.065505 136.21784) (xy 217.065505 136.2041) (xy 217.065505 136.19037)
			(xy 217.065505 136.17664) (xy 217.065505 136.16291) (xy 217.065505 136.14918) (xy 217.065505 136.13545)
			(xy 217.065505 136.12171) (xy 217.065505 136.10798) (xy 217.065505 136.09425) (xy 217.065505 136.08052)
			(xy 217.065505 136.06679) (xy 217.065505 136.05306) (xy 217.065505 136.03932) (xy 217.065505 136.02559)
			(xy 217.065505 136.01186) (xy 217.065505 135.99813) (xy 217.065505 135.9844) (xy 217.065505 135.97067)
			(xy 217.065505 135.95693) (xy 217.065505 135.9432) (xy 217.065505 135.92947) (xy 217.065505 135.91574)
			(xy 217.065505 135.90201) (xy 217.065505 135.88827) (xy 217.065505 135.87454) (xy 217.065505 135.86081)
			(xy 217.065505 135.84708) (xy 217.065505 135.83335) (xy 217.065505 135.81961) (xy 217.065505 135.80588)
			(xy 217.065505 135.79215) (xy 217.065505 135.77842) (xy 217.065505 135.76469) (xy 217.065505 135.75096)
			(xy 217.065505 135.73722) (xy 217.065505 135.72349) (xy 217.065505 135.70976) (xy 217.065505 135.69603)
			(xy 217.065505 135.6823) (xy 217.065505 135.66857) (xy 217.065505 135.65483) (xy 217.065505 135.6411)
			(xy 217.065505 135.62737) (xy 217.065505 135.61364) (xy 217.065505 135.59991) (xy 217.065505 135.58618)
			(xy 217.065505 135.57244) (xy 217.065505 135.55871) (xy 217.065505 135.54498) (xy 217.065505 135.53125)
			(xy 217.065505 135.51752) (xy 217.065505 135.50379) (xy 217.065505 135.49005) (xy 217.065505 135.47632)
			(xy 217.065505 135.46259) (xy 217.065505 135.44886) (xy 217.065505 135.43513) (xy 217.065505 135.4214)
			(xy 217.065505 135.40766) (xy 217.065505 135.39393) (xy 217.065505 135.3802) (xy 217.065505 135.36647)
			(xy 217.065505 135.35274) (xy 217.065505 135.339) (xy 217.065505 135.32527) (xy 217.065505 135.31154)
			(xy 217.065505 135.29781) (xy 217.065505 135.28408) (xy 217.065505 135.27034) (xy 217.065505 135.25661)
			(xy 217.065505 135.24288) (xy 217.065505 135.22915) (xy 217.065505 135.21542) (xy 217.065505 135.20169)
			(xy 217.065505 135.18795) (xy 217.065505 135.17422) (xy 217.065505 135.16049) (xy 217.065505 135.14676)
			(xy 217.065505 135.13303) (xy 217.065505 135.1193) (xy 217.065505 135.10556) (xy 217.065505 135.09183)
			(xy 217.065505 135.0781) (xy 217.065505 135.06437) (xy 217.065505 135.05064) (xy 217.065505 135.03691)
			(xy 217.065505 135.02317) (xy 217.065505 135.00944) (xy 217.065505 134.99571) (xy 217.065505 134.98198)
			(xy 217.065505 134.96825) (xy 217.065505 134.95452) (xy 217.065505 134.94078) (xy 217.065505 134.92705)
			(xy 217.065505 134.91332) (xy 217.065505 134.89959) (xy 217.065505 134.88586) (xy 217.065505 134.87213)
			(xy 217.065505 134.85839) (xy 217.065505 134.84466) (xy 217.065505 134.83093) (xy 217.065505 134.8172)
			(xy 217.065505 134.80347) (xy 217.065505 134.78973) (xy 217.065505 134.776) (xy 217.065505 134.76227)
			(xy 217.257755 134.76227) (xy 217.257755 134.74854) (xy 217.271485 134.74854) (xy 217.271485 134.76227)
			(xy 217.312685 134.76227) (xy 217.312685 134.74854) (xy 217.312685 134.73481) (xy 217.312685 134.72107)
			(xy 217.312685 134.70734) (xy 217.312685 134.69361) (xy 217.312685 134.67988) (xy 217.312685 134.66615)
			(xy 217.312685 134.65242) (xy 217.312685 134.63868) (xy 217.312685 134.62495) (xy 217.312685 134.61122)
			(xy 217.312685 134.59749) (xy 217.312685 134.58376) (xy 217.312685 134.57003) (xy 217.312685 134.55629)
			(xy 217.312685 134.54256) (xy 217.312685 134.52883) (xy 217.312685 134.5151) (xy 217.312685 134.50137)
			(xy 217.312685 134.48764) (xy 217.312685 134.4739) (xy 217.312685 134.46017) (xy 217.312685 134.44644)
			(xy 217.312685 134.43271) (xy 217.312685 134.41898) (xy 217.312685 134.40525) (xy 217.312685 134.39151)
			(xy 217.312685 134.37778) (xy 217.312685 134.36405) (xy 217.312685 134.35032) (xy 217.312685 134.33659)
			(xy 217.312685 134.32286) (xy 217.312685 134.30912) (xy 217.312685 134.29539) (xy 217.312685 134.28166)
			(xy 217.312685 134.26793) (xy 217.312685 134.2542) (xy 217.312685 134.24046) (xy 217.312685 134.22673)
			(xy 217.312685 134.213) (xy 217.312685 134.19927) (xy 217.312685 134.18554) (xy 217.312685 134.1718)
			(xy 217.312685 134.15807) (xy 217.312685 134.14434) (xy 217.312685 134.13061) (xy 217.312685 134.11688)
			(xy 217.312685 134.10315) (xy 217.312685 134.08941) (xy 217.312685 134.07568) (xy 217.312685 134.06195)
			(xy 217.312685 134.04822) (xy 217.312685 134.03449) (xy 217.312685 134.02076) (xy 215.211725 134.02076)
			(xy 215.211725 134.03449) (xy 215.170525 134.03449) (xy 215.170525 134.04822) (xy 215.156795 134.04822)
			(xy 215.156795 134.06195) (xy 215.156795 134.07568) (xy 215.143065 134.07568) (xy 214.799765 134.07568)
			(xy 214.799765 134.06195) (xy 214.786035 134.06195) (xy 214.786035 134.04822) (xy 214.772305 134.04822)
			(xy 214.772305 134.03449) (xy 214.744845 134.03449) (xy 214.744845 134.02076) (xy 214.113185 134.02076)
			(xy 214.113185 134.03449) (xy 214.071985 134.03449) (xy 214.071985 134.04822) (xy 214.071985 134.06195)
			(xy 214.058255 134.06195) (xy 214.058255 134.07568) (xy 214.058255 134.08941) (xy 214.044525 134.08941)
			(xy 213.866005 134.08941) (xy 213.866005 134.07568) (xy 213.866005 134.06195) (xy 213.852275 134.06195)
			(xy 213.852275 134.04822) (xy 213.838545 134.04822) (xy 213.838545 134.03449) (xy 213.811085 134.03449)
			(xy 213.811085 134.02076) (xy 213.783615 134.02076) (xy 213.783615 134.03449) (xy 213.769885 134.03449)
			(xy 213.769885 134.02076) (xy 211.655195 134.02076) (xy 211.655195 134.03449) (xy 211.614005 134.03449)
			(xy 211.614005 134.04822) (xy 211.600275 134.04822) (xy 211.600275 134.06195) (xy 211.600275 134.07568)
			(xy 211.586535 134.07568) (xy 209.526775 134.07568) (xy 209.526775 134.06195) (xy 209.526775 134.04822)
			(xy 209.526775 134.03449) (xy 209.526775 134.02076) (xy 209.526775 134.00702) (xy 209.526775 133.99329)
			(xy 209.526775 133.97956) (xy 209.526775 133.96583) (xy 209.526775 133.9521) (xy 209.526775 133.93837)
			(xy 209.526775 133.92463) (xy 209.526775 133.9109) (xy 209.526775 133.89717) (xy 209.526775 133.88344)
			(xy 209.526775 133.86971) (xy 209.526775 133.85598) (xy 209.526775 133.84224) (xy 209.526775 133.82851)
			(xy 209.526775 133.81478) (xy 209.526775 133.80105) (xy 209.526775 133.78732) (xy 213.866005 133.78732)
			(xy 213.866005 133.80105) (xy 214.085715 133.80105) (xy 214.085715 133.78732) (xy 214.099455 133.78732)
			(xy 214.099455 133.77359) (xy 214.113185 133.77359) (xy 214.113185 133.75985) (xy 214.113185 133.74612)
			(xy 214.126915 133.74612) (xy 214.126915 133.73239) (xy 214.140645 133.73239) (xy 214.140645 133.71866)
			(xy 214.154375 133.71866) (xy 214.154375 133.70493) (xy 214.168105 133.70493) (xy 214.168105 133.69119)
			(xy 214.181845 133.69119) (xy 214.181845 133.67746) (xy 214.195575 133.67746) (xy 214.195575 133.66373)
			(xy 214.209305 133.66373) (xy 214.209305 133.65) (xy 214.223035 133.65) (xy 214.223035 133.63627)
			(xy 214.223035 133.62253) (xy 214.236765 133.62253) (xy 214.236765 133.6088) (xy 214.250495 133.6088)
			(xy 214.250495 133.59507) (xy 214.264235 133.59507) (xy 214.264235 133.58134) (xy 214.277965 133.58134)
			(xy 214.277965 133.56761) (xy 214.291695 133.56761) (xy 214.291695 133.55388) (xy 214.305425 133.55388)
			(xy 214.305425 133.54014) (xy 214.319155 133.54014) (xy 214.319155 133.52641) (xy 214.332885 133.52641)
			(xy 214.332885 133.51268) (xy 214.346625 133.51268) (xy 214.346625 133.49895) (xy 214.360355 133.49895)
			(xy 214.360355 133.48522) (xy 214.374085 133.48522) (xy 214.374085 133.47149) (xy 214.387815 133.47149)
			(xy 214.387815 133.45775) (xy 214.401545 133.45775) (xy 214.401545 133.44402) (xy 214.415275 133.44402)
			(xy 214.415275 133.43029) (xy 214.429015 133.43029) (xy 214.429015 133.41656) (xy 214.442745 133.41656)
			(xy 214.442745 133.40283) (xy 214.456475 133.40283) (xy 214.456475 133.3891) (xy 214.470205 133.3891)
			(xy 214.470205 133.37536) (xy 214.483935 133.37536) (xy 214.483935 133.36163) (xy 214.497675 133.36163)
			(xy 214.497675 133.3479) (xy 214.525135 133.3479) (xy 214.525135 133.33417) (xy 214.538865 133.33417)
			(xy 214.538865 133.32044) (xy 214.552595 133.32044) (xy 214.552595 133.30671) (xy 214.566335 133.30671)
			(xy 214.566335 133.29297) (xy 214.580065 133.29297) (xy 214.580065 133.27924) (xy 214.593795 133.27924)
			(xy 214.593795 133.26551) (xy 214.607525 133.26551) (xy 214.607525 133.25178) (xy 214.621255 133.25178)
			(xy 214.621255 133.23805) (xy 214.634985 133.23805) (xy 214.634985 133.22431) (xy 214.662455 133.22431)
			(xy 214.662455 133.21058) (xy 214.676185 133.21058) (xy 214.676185 133.19685) (xy 214.689915 133.19685)
			(xy 214.689915 133.18312) (xy 214.703645 133.18312) (xy 214.703645 133.16939) (xy 214.717375 133.16939)
			(xy 214.717375 133.15565) (xy 214.744845 133.15565) (xy 214.744845 133.14192) (xy 214.758575 133.14192)
			(xy 214.758575 133.12819) (xy 214.772305 133.12819) (xy 214.772305 133.11446) (xy 214.786035 133.11446)
			(xy 214.786035 133.10073) (xy 214.813505 133.10073) (xy 214.813505 133.087) (xy 214.827235 133.087)
			(xy 214.827235 133.07326) (xy 214.840965 133.07326) (xy 214.840965 133.05953) (xy 214.854695 133.05953)
			(xy 214.854695 133.0458) (xy 214.882155 133.0458) (xy 214.882155 133.03207) (xy 214.895895 133.03207)
			(xy 214.895895 133.01834) (xy 214.909625 133.01834) (xy 214.909625 133.00461) (xy 214.937085 133.00461)
			(xy 214.937085 132.99087) (xy 214.950815 132.99087) (xy 214.950815 132.97714) (xy 214.964555 132.97714)
			(xy 214.964555 132.96341) (xy 214.992015 132.96341) (xy 214.992015 132.94968) (xy 215.005745 132.94968)
			(xy 215.005745 132.93595) (xy 215.019475 132.93595) (xy 215.019475 132.92222) (xy 215.046945 132.92222)
			(xy 215.046945 132.90848) (xy 215.060675 132.90848) (xy 215.060675 132.89475) (xy 215.088135 132.89475)
			(xy 215.088135 132.88102) (xy 215.101865 132.88102) (xy 215.101865 132.86729) (xy 215.129335 132.86729)
			(xy 215.129335 132.85356) (xy 215.143065 132.85356) (xy 215.143065 132.83983) (xy 215.170525 132.83983)
			(xy 215.170525 132.82609) (xy 215.184255 132.82609) (xy 215.184255 132.81236) (xy 215.211725 132.81236)
			(xy 215.211725 132.79863) (xy 215.225455 132.79863) (xy 215.225455 132.7849) (xy 215.252915 132.7849)
			(xy 215.252915 132.77117) (xy 215.266645 132.77117) (xy 215.266645 132.75744) (xy 215.294115 132.75744)
			(xy 215.294115 132.7437) (xy 215.321575 132.7437) (xy 215.321575 132.72997) (xy 215.335305 132.72997)
			(xy 215.335305 132.71624) (xy 215.362775 132.71624) (xy 215.362775 132.70251) (xy 215.390235 132.70251)
			(xy 215.390235 132.68878) (xy 215.403965 132.68878) (xy 215.403965 132.67504) (xy 215.431425 132.67504)
			(xy 215.431425 132.66131) (xy 215.458895 132.66131) (xy 215.458895 132.64758) (xy 215.472625 132.64758)
			(xy 215.472625 132.63385) (xy 215.500085 132.63385) (xy 215.500085 132.62012) (xy 215.527555 132.62012)
			(xy 215.527555 132.60638) (xy 215.555015 132.60638) (xy 215.555015 132.59265) (xy 215.582485 132.59265)
			(xy 215.582485 132.57892) (xy 215.609945 132.57892) (xy 215.609945 132.56519) (xy 215.637405 132.56519)
			(xy 215.637405 132.55146) (xy 215.651135 132.55146) (xy 215.651135 132.53773) (xy 215.678605 132.53773)
			(xy 215.678605 132.52399) (xy 215.706065 132.52399) (xy 215.706065 132.51026) (xy 215.733525 132.51026)
			(xy 215.733525 132.49653) (xy 215.760995 132.49653) (xy 215.760995 132.4828) (xy 215.802185 132.4828)
			(xy 215.802185 132.46907) (xy 215.829655 132.46907) (xy 215.829655 132.45534) (xy 215.857115 132.45534)
			(xy 215.857115 132.4416) (xy 215.884575 132.4416) (xy 215.884575 132.42787) (xy 215.912045 132.42787)
			(xy 215.912045 132.41414) (xy 215.939505 132.41414) (xy 215.939505 132.40041) (xy 215.980695 132.40041)
			(xy 215.980695 132.38668) (xy 216.008165 132.38668) (xy 216.008165 132.37295) (xy 216.035625 132.37295)
			(xy 216.035625 132.35921) (xy 216.076825 132.35921) (xy 216.076825 132.34548) (xy 216.104285 132.34548)
			(xy 216.104285 132.33175) (xy 216.145485 132.33175) (xy 216.145485 132.31802) (xy 216.186675 132.31802)
			(xy 216.186675 132.30429) (xy 216.214145 132.30429) (xy 216.214145 132.29056) (xy 216.255335 132.29056)
			(xy 216.255335 132.27682) (xy 216.296535 132.27682) (xy 216.296535 132.26309) (xy 216.337725 132.26309)
			(xy 216.337725 132.24936) (xy 216.365185 132.24936) (xy 216.365185 132.23563) (xy 216.420115 132.23563)
			(xy 216.420115 132.2219) (xy 216.461315 132.2219) (xy 216.461315 132.20817) (xy 216.502505 132.20817)
			(xy 216.502505 132.19443) (xy 216.543705 132.19443) (xy 216.543705 132.1807) (xy 216.598625 132.1807)
			(xy 216.598625 132.16697) (xy 216.639825 132.16697) (xy 216.639825 132.15324) (xy 216.694755 132.15324)
			(xy 216.694755 132.13951) (xy 216.749675 132.13951) (xy 216.749675 132.12577) (xy 216.804605 132.12577)
			(xy 216.804605 132.11204) (xy 216.859535 132.11204) (xy 216.859535 132.09831) (xy 216.928195 132.09831)
			(xy 216.928195 132.08458) (xy 216.996845 132.08458) (xy 216.996845 132.07085) (xy 217.051775 132.07085)
			(xy 217.051775 132.05711) (xy 217.147905 132.05711) (xy 217.147905 132.04338) (xy 217.230295 132.04338)
			(xy 217.230295 132.02965) (xy 217.326415 132.02965) (xy 217.326415 132.01592) (xy 217.436265 132.01592)
			(xy 217.436265 132.00219) (xy 217.587315 132.00219) (xy 217.587315 131.98846) (xy 217.834485 131.98846)
			(xy 217.834485 131.97472) (xy 218.177785 131.97472) (xy 218.177785 131.98846) (xy 218.191515 131.98846)
			(xy 218.191515 131.97472) (xy 218.205245 131.97472) (xy 218.205245 131.98846) (xy 218.424955 131.98846)
			(xy 218.424955 132.00219) (xy 218.575995 132.00219) (xy 218.575995 132.01592) (xy 218.699585 132.01592)
			(xy 218.699585 132.02965) (xy 218.781975 132.02965) (xy 218.781975 132.04338) (xy 218.864365 132.04338)
			(xy 218.864365 132.05711) (xy 218.946755 132.05711) (xy 218.946755 132.07085) (xy 219.015415 132.07085)
			(xy 219.015415 132.08458) (xy 219.084075 132.08458) (xy 219.084075 132.09831) (xy 219.152735 132.09831)
			(xy 219.152735 132.11204) (xy 219.207665 132.11204) (xy 219.207665 132.12577) (xy 219.262585 132.12577)
			(xy 219.262585 132.13951) (xy 219.317515 132.13951) (xy 219.317515 132.15324) (xy 219.372445 132.15324)
			(xy 219.372445 132.16697) (xy 219.413635 132.16697) (xy 219.413635 132.1807) (xy 219.468565 132.1807)
			(xy 219.468565 132.19443) (xy 219.509755 132.19443) (xy 219.509755 132.20817) (xy 219.550955 132.20817)
			(xy 219.550955 132.2219) (xy 219.592145 132.2219) (xy 219.592145 132.23563) (xy 219.633345 132.23563)
			(xy 219.633345 132.24936) (xy 219.674545 132.24936) (xy 219.674545 132.26309) (xy 219.715735 132.26309)
			(xy 219.715735 132.27682) (xy 219.756935 132.27682) (xy 219.756935 132.29056) (xy 219.798125 132.29056)
			(xy 219.798125 132.30429) (xy 219.825595 132.30429) (xy 219.825595 132.31802) (xy 219.866785 132.31802)
			(xy 219.866785 132.33175) (xy 219.894245 132.33175) (xy 219.894245 132.34548) (xy 219.935445 132.34548)
			(xy 219.935445 132.35921) (xy 219.962905 132.35921) (xy 219.962905 132.37295) (xy 220.004105 132.37295)
			(xy 220.004105 132.38668) (xy 220.031565 132.38668) (xy 220.031565 132.40041) (xy 220.059025 132.40041)
			(xy 220.059025 132.41414) (xy 220.100225 132.41414) (xy 220.100225 132.42787) (xy 220.127685 132.42787)
			(xy 220.127685 132.4416) (xy 220.155155 132.4416) (xy 220.155155 132.45534) (xy 220.182615 132.45534)
			(xy 220.182615 132.46907) (xy 220.210075 132.46907) (xy 220.210075 132.4828) (xy 220.251275 132.4828)
			(xy 220.251275 132.49653) (xy 220.278735 132.49653) (xy 220.278735 132.51026) (xy 220.292475 132.51026)
			(xy 220.292475 132.52399) (xy 220.319935 132.52399) (xy 220.319935 132.53773) (xy 220.347395 132.53773)
			(xy 220.347395 132.55146) (xy 220.374865 132.55146) (xy 220.374865 132.56519) (xy 220.402325 132.56519)
			(xy 220.402325 132.57892) (xy 220.429785 132.57892) (xy 220.429785 132.59265) (xy 220.457255 132.59265)
			(xy 220.457255 132.60638) (xy 220.484715 132.60638) (xy 220.484715 132.62012) (xy 220.512175 132.62012)
			(xy 220.512175 132.63385) (xy 220.525905 132.63385) (xy 220.525905 132.64758) (xy 220.553375 132.64758)
			(xy 220.553375 132.66131) (xy 220.580835 132.66131) (xy 220.580835 132.67504) (xy 220.608295 132.67504)
			(xy 220.608295 132.68878) (xy 220.622035 132.68878) (xy 220.622035 132.70251) (xy 220.649495 132.70251)
			(xy 220.649495 132.71624) (xy 220.676955 132.71624) (xy 220.676955 132.72997) (xy 220.690685 132.72997)
			(xy 220.690685 132.7437) (xy 220.718155 132.7437) (xy 220.718155 132.75744) (xy 220.745615 132.75744)
			(xy 220.745615 132.77117) (xy 220.759345 132.77117) (xy 220.759345 132.7849) (xy 220.786815 132.7849)
			(xy 220.786815 132.79863) (xy 220.800545 132.79863) (xy 220.800545 132.81236) (xy 220.828005 132.81236)
			(xy 220.828005 132.82609) (xy 220.841745 132.82609) (xy 220.841745 132.83983) (xy 220.869205 132.83983)
			(xy 220.869205 132.85356) (xy 220.882935 132.85356) (xy 220.882935 132.86729) (xy 220.910395 132.86729)
			(xy 220.910395 132.88102) (xy 220.924135 132.88102) (xy 220.924135 132.89475) (xy 220.951595 132.89475)
			(xy 220.951595 132.90848) (xy 220.965325 132.90848) (xy 220.965325 132.92222) (xy 220.979055 132.92222)
			(xy 220.979055 132.93595) (xy 221.006525 132.93595) (xy 221.006525 132.94968) (xy 221.020255 132.94968)
			(xy 221.020255 132.96341) (xy 221.047715 132.96341) (xy 221.047715 132.97714) (xy 221.061445 132.97714)
			(xy 221.061445 132.99087) (xy 221.075175 132.99087) (xy 221.075175 133.00461) (xy 221.102645 133.00461)
			(xy 221.102645 133.01834) (xy 221.116375 133.01834) (xy 221.116375 133.03207) (xy 221.130105 133.03207)
			(xy 221.130105 133.0458) (xy 221.157565 133.0458) (xy 221.157565 133.05953) (xy 221.171305 133.05953)
			(xy 221.171305 133.07326) (xy 221.185035 133.07326) (xy 221.185035 133.087) (xy 221.198765 133.087)
			(xy 221.198765 133.10073) (xy 221.226225 133.10073) (xy 221.226225 133.11446) (xy 221.239955 133.11446)
			(xy 221.239955 133.12819) (xy 221.253695 133.12819) (xy 221.253695 133.14192) (xy 221.267425 133.14192)
			(xy 221.267425 133.15565) (xy 221.294885 133.15565) (xy 221.294885 133.16939) (xy 221.308615 133.16939)
			(xy 221.308615 133.18312) (xy 221.322355 133.18312) (xy 221.322355 133.19685) (xy 221.336085 133.19685)
			(xy 221.336085 133.21058) (xy 221.349815 133.21058) (xy 221.349815 133.22431) (xy 221.363545 133.22431)
			(xy 221.363545 133.23805) (xy 221.391015 133.23805) (xy 221.391015 133.25178) (xy 221.404745 133.25178)
			(xy 221.404745 133.26551) (xy 221.418475 133.26551) (xy 221.418475 133.27924) (xy 221.432205 133.27924)
			(xy 221.432205 133.29297) (xy 221.445935 133.29297) (xy 221.445935 133.30671) (xy 221.459665 133.30671)
			(xy 221.459665 133.32044) (xy 221.473405 133.32044) (xy 221.473405 133.33417) (xy 221.487135 133.33417)
			(xy 221.487135 133.3479) (xy 221.500865 133.3479) (xy 221.500865 133.36163) (xy 221.528325 133.36163)
			(xy 221.528325 133.37536) (xy 221.542055 133.37536) (xy 221.542055 133.3891) (xy 221.555795 133.3891)
			(xy 221.555795 133.40283) (xy 221.569525 133.40283) (xy 221.569525 133.41656) (xy 221.583255 133.41656)
			(xy 221.583255 133.43029) (xy 221.596985 133.43029) (xy 221.596985 133.44402) (xy 221.610715 133.44402)
			(xy 221.610715 133.45775) (xy 221.624445 133.45775) (xy 221.624445 133.47149) (xy 221.638185 133.47149)
			(xy 221.638185 133.48522) (xy 221.651915 133.48522) (xy 221.651915 133.49895) (xy 221.665645 133.49895)
			(xy 221.665645 133.51268) (xy 221.679375 133.51268) (xy 221.679375 133.52641) (xy 221.693105 133.52641)
			(xy 221.693105 133.54014) (xy 221.706835 133.54014) (xy 221.706835 133.55388) (xy 221.720575 133.55388)
			(xy 221.720575 133.56761) (xy 221.734305 133.56761) (xy 221.734305 133.58134) (xy 221.748035 133.58134)
			(xy 221.748035 133.59507) (xy 221.761765 133.59507) (xy 221.761765 133.6088) (xy 221.761765 133.62253)
			(xy 221.775495 133.62253) (xy 221.775495 133.63627) (xy 221.789235 133.63627) (xy 221.789235 133.65)
			(xy 221.802965 133.65) (xy 221.802965 133.66373) (xy 221.816695 133.66373) (xy 221.816695 133.67746)
			(xy 221.830425 133.67746) (xy 221.830425 133.69119) (xy 221.844155 133.69119) (xy 221.844155 133.70493)
			(xy 221.857895 133.70493) (xy 221.857895 133.71866) (xy 221.871625 133.71866) (xy 221.871625 133.73239)
			(xy 221.885355 133.73239) (xy 221.885355 133.74612) (xy 221.885355 133.75985) (xy 221.899085 133.75985)
			(xy 221.899085 133.77359) (xy 221.912815 133.77359) (xy 221.912815 133.78732) (xy 221.926545 133.78732)
			(xy 221.926545 133.80105) (xy 221.940285 133.80105) (xy 221.940285 133.81478) (xy 221.954015 133.81478)
			(xy 221.954015 133.82851) (xy 221.967745 133.82851) (xy 221.967745 133.84224) (xy 221.967745 133.85598)
			(xy 221.981475 133.85598) (xy 221.981475 133.86971) (xy 221.995205 133.86971) (xy 221.995205 133.88344)
			(xy 222.008935 133.88344) (xy 222.008935 133.89717) (xy 222.022675 133.89717) (xy 222.022675 133.9109)
			(xy 222.022675 133.92463) (xy 222.036405 133.92463) (xy 222.036405 133.93837) (xy 222.050135 133.93837)
			(xy 222.050135 133.9521) (xy 222.063865 133.9521) (xy 222.063865 133.96583) (xy 222.077595 133.96583)
			(xy 222.077595 133.97956) (xy 222.077595 133.99329) (xy 222.091325 133.99329) (xy 222.091325 134.00702)
			(xy 222.105065 134.00702) (xy 222.105065 134.02076) (xy 222.118795 134.02076) (xy 222.118795 134.03449)
			(xy 222.118795 134.04822) (xy 222.132525 134.04822) (xy 222.132525 134.06195) (xy 222.146255 134.06195)
			(xy 222.146255 134.07568) (xy 222.159985 134.07568) (xy 222.159985 134.08941) (xy 222.159985 134.10315)
			(xy 222.173715 134.10315) (xy 222.173715 134.11688) (xy 222.187455 134.11688) (xy 222.187455 134.13061)
			(xy 222.187455 134.14434) (xy 222.201185 134.14434) (xy 222.201185 134.15807) (xy 222.214915 134.15807)
			(xy 222.214915 134.1718) (xy 222.228645 134.1718) (xy 222.228645 134.18554) (xy 222.228645 134.19927)
			(xy 222.242375 134.19927) (xy 222.242375 134.213) (xy 222.256105 134.213) (xy 222.256105 134.22673)
			(xy 222.256105 134.24046) (xy 222.269845 134.24046) (xy 222.269845 134.2542) (xy 222.283575 134.2542)
			(xy 222.283575 134.26793) (xy 222.283575 134.28166) (xy 222.297305 134.28166) (xy 222.297305 134.29539)
			(xy 222.311035 134.29539) (xy 222.311035 134.30912) (xy 222.311035 134.32286) (xy 222.324765 134.32286)
			(xy 222.324765 134.33659) (xy 222.338505 134.33659) (xy 222.338505 134.35032) (xy 222.338505 134.36405)
			(xy 222.352235 134.36405) (xy 222.352235 134.37778) (xy 222.365965 134.37778) (xy 222.365965 134.39151)
			(xy 222.365965 134.40525) (xy 222.379695 134.40525) (xy 222.379695 134.41898) (xy 222.379695 134.43271)
			(xy 222.393425 134.43271) (xy 222.393425 134.44644) (xy 222.407165 134.44644) (xy 222.407165 134.46017)
			(xy 222.407165 134.4739) (xy 222.420895 134.4739) (xy 222.420895 134.48764) (xy 222.420895 134.50137)
			(xy 222.434625 134.50137) (xy 222.434625 134.5151) (xy 222.448355 134.5151) (xy 222.448355 134.52883)
			(xy 222.448355 134.54256) (xy 222.462085 134.54256) (xy 222.462085 134.55629) (xy 222.462085 134.57003)
			(xy 222.475815 134.57003) (xy 222.475815 134.58376) (xy 222.475815 134.59749) (xy 222.489555 134.59749)
			(xy 222.489555 134.61122) (xy 222.503285 134.61122) (xy 222.503285 134.62495) (xy 222.503285 134.63868)
			(xy 222.517015 134.63868) (xy 222.517015 134.65242) (xy 222.517015 134.66615) (xy 222.530745 134.66615)
			(xy 222.530745 134.67988) (xy 222.530745 134.69361) (xy 222.544475 134.69361) (xy 222.544475 134.70734)
			(xy 222.544475 134.72107) (xy 222.558205 134.72107) (xy 222.558205 134.73481) (xy 222.558205 134.74854)
			(xy 222.571945 134.74854) (xy 222.571945 134.76227) (xy 222.585675 134.76227) (xy 222.585675 134.776)
			(xy 222.585675 134.78973) (xy 222.599405 134.78973) (xy 222.599405 134.80347) (xy 222.599405 134.8172)
			(xy 222.613135 134.8172) (xy 222.613135 134.83093) (xy 222.613135 134.84466) (xy 222.626865 134.84466)
			(xy 222.626865 134.85839) (xy 222.626865 134.87213) (xy 222.640595 134.87213) (xy 222.640595 134.88586)
			(xy 222.640595 134.89959) (xy 222.640595 134.91332) (xy 222.654335 134.91332) (xy 222.654335 134.92705)
			(xy 222.654335 134.94078) (xy 222.668065 134.94078) (xy 222.668065 134.95452) (xy 222.668065 134.96825)
			(xy 222.681795 134.96825) (xy 222.681795 134.98198) (xy 222.681795 134.99571) (xy 222.695525 134.99571)
			(xy 222.695525 135.00944) (xy 222.695525 135.02317) (xy 222.709255 135.02317) (xy 222.709255 135.03691)
			(xy 222.709255 135.05064) (xy 222.722985 135.05064) (xy 222.722985 135.06437) (xy 222.722985 135.0781)
			(xy 222.722985 135.09183) (xy 222.736725 135.09183) (xy 222.736725 135.10556) (xy 222.736725 135.1193)
			(xy 222.750455 135.1193) (xy 222.750455 135.13303) (xy 222.750455 135.14676) (xy 222.764185 135.14676)
			(xy 222.764185 135.16049) (xy 222.764185 135.17422) (xy 222.764185 135.18795) (xy 222.777915 135.18795)
			(xy 222.777915 135.20169) (xy 222.777915 135.21542) (xy 222.791645 135.21542) (xy 222.791645 135.22915)
			(xy 222.791645 135.24288) (xy 222.791645 135.25661) (xy 222.805375 135.25661) (xy 222.805375 135.27034)
			(xy 222.805375 135.28408) (xy 222.819115 135.28408) (xy 222.819115 135.29781) (xy 222.819115 135.31154)
			(xy 222.819115 135.32527) (xy 222.832845 135.32527) (xy 222.832845 135.339) (xy 222.832845 135.35274)
			(xy 222.832845 135.36647) (xy 222.846575 135.36647) (xy 222.846575 135.3802) (xy 222.846575 135.39393)
			(xy 222.846575 135.40766) (xy 222.860305 135.40766) (xy 222.860305 135.4214) (xy 222.860305 135.43513)
			(xy 222.874035 135.43513) (xy 222.874035 135.44886) (xy 222.874035 135.46259) (xy 222.874035 135.47632)
			(xy 222.887775 135.47632) (xy 222.887775 135.49005) (xy 222.887775 135.50379) (xy 222.887775 135.51752)
			(xy 222.901505 135.51752) (xy 222.901505 135.53125) (xy 222.901505 135.54498) (xy 222.901505 135.55871)
			(xy 222.901505 135.57244) (xy 222.915235 135.57244) (xy 222.915235 135.58618) (xy 222.915235 135.59991)
			(xy 222.915235 135.61364) (xy 222.928965 135.61364) (xy 222.928965 135.62737) (xy 222.928965 135.6411)
			(xy 222.928965 135.65483) (xy 222.942695 135.65483) (xy 222.942695 135.66857) (xy 222.942695 135.6823)
			(xy 222.942695 135.69603) (xy 222.942695 135.70976) (xy 222.956435 135.70976) (xy 222.956435 135.72349)
			(xy 222.956435 135.73722) (xy 222.956435 135.75096) (xy 222.970165 135.75096) (xy 222.970165 135.76469)
			(xy 222.970165 135.77842) (xy 222.970165 135.79215) (xy 222.970165 135.80588) (xy 222.983895 135.80588)
			(xy 222.983895 135.81961) (xy 222.983895 135.83335) (xy 222.983895 135.84708) (xy 222.983895 135.86081)
			(xy 222.997625 135.86081) (xy 222.997625 135.87454) (xy 222.997625 135.88827) (xy 222.997625 135.90201)
			(xy 222.997625 135.91574) (xy 223.011355 135.91574) (xy 223.011355 135.92947) (xy 223.011355 135.9432)
			(xy 223.011355 135.95693) (xy 223.011355 135.97067) (xy 223.025085 135.97067) (xy 223.025085 135.9844)
			(xy 223.025085 135.99813) (xy 223.025085 136.01186) (xy 223.025085 136.02559) (xy 223.025085 136.03932)
			(xy 223.038825 136.03932) (xy 223.038825 136.05306) (xy 223.038825 136.06679) (xy 223.038825 136.08052)
			(xy 223.038825 136.09425) (xy 223.052555 136.09425) (xy 223.052555 136.10798) (xy 223.052555 136.12171)
			(xy 223.052555 136.13545) (xy 223.052555 136.14918) (xy 223.052555 136.16291) (xy 223.052555 136.17664)
			(xy 223.066285 136.17664) (xy 223.066285 136.19037) (xy 223.066285 136.2041) (xy 223.066285 136.21784)
			(xy 223.066285 136.23157) (xy 223.066285 136.2453) (xy 223.080015 136.2453) (xy 223.080015 136.25903)
			(xy 223.080015 136.27276) (xy 223.080015 136.28649) (xy 223.080015 136.30023) (xy 223.080015 136.31396)
			(xy 223.080015 136.32769) (xy 223.093745 136.32769) (xy 223.093745 136.34142) (xy 223.093745 136.35515)
			(xy 223.093745 136.36889) (xy 223.093745 136.38262) (xy 223.093745 136.39635) (xy 223.093745 136.41008)
			(xy 223.093745 136.42381) (xy 223.107475 136.42381) (xy 223.107475 136.43755) (xy 223.107475 136.45128)
			(xy 223.107475 136.46501) (xy 223.107475 136.47874) (xy 223.107475 136.49247) (xy 223.107475 136.5062)
			(xy 223.107475 136.51994) (xy 223.107475 136.53367) (xy 223.107475 136.5474) (xy 223.121215 136.5474)
			(xy 223.121215 136.56113) (xy 223.121215 136.57486) (xy 223.121215 136.58859) (xy 223.121215 136.60233)
			(xy 223.121215 136.61606) (xy 223.121215 136.62979) (xy 223.121215 136.64352) (xy 223.121215 136.65725)
			(xy 223.121215 136.67098) (xy 223.134945 136.67098) (xy 223.134945 136.68472) (xy 223.134945 136.69845)
			(xy 223.134945 136.71218) (xy 223.134945 136.72591) (xy 223.134945 136.73964) (xy 223.134945 136.75337)
			(xy 223.134945 136.76711) (xy 223.134945 136.78084) (xy 223.134945 136.79457) (xy 223.134945 136.8083)
			(xy 223.134945 136.82203) (xy 223.134945 136.83576) (xy 223.134945 136.8495) (xy 223.134945 136.86323)
			(xy 223.134945 136.87696) (xy 223.134945 136.89069) (xy 223.134945 136.90442) (xy 223.148675 136.90442)
			(xy 223.148675 136.91816) (xy 223.148675 136.93189) (xy 223.148675 136.94562) (xy 223.148675 136.95935)
			(xy 223.148675 136.97308) (xy 223.148675 136.98682) (xy 223.148675 137.00055) (xy 223.148675 137.01428)
			(xy 223.148675 137.02801) (xy 223.148675 137.04174) (xy 223.148675 137.05547) (xy 223.313455 137.05547)
			(xy 223.313455 137.04174) (xy 223.313455 137.02801) (xy 223.313455 137.01428) (xy 223.313455 137.00055)
			(xy 223.313455 136.98682) (xy 223.313455 136.97308) (xy 223.313455 136.95935) (xy 223.313455 136.94562)
			(xy 223.313455 136.93189) (xy 223.313455 136.91816) (xy 223.313455 136.90442) (xy 223.313455 136.89069)
			(xy 223.299725 136.89069) (xy 223.299725 136.87696) (xy 223.313455 136.87696) (xy 223.313455 136.86323)
			(xy 223.313455 136.8495) (xy 223.313455 136.83576) (xy 223.299725 136.83576) (xy 223.299725 136.82203)
			(xy 223.299725 136.8083) (xy 223.299725 136.79457) (xy 223.299725 136.78084) (xy 223.299725 136.76711)
			(xy 223.299725 136.75337) (xy 223.299725 136.73964) (xy 223.299725 136.72591) (xy 223.299725 136.71218)
			(xy 223.299725 136.69845) (xy 223.299725 136.68472) (xy 223.299725 136.67098) (xy 223.299725 136.65725)
			(xy 223.299725 136.64352) (xy 223.285995 136.64352) (xy 223.285995 136.62979) (xy 223.285995 136.61606)
			(xy 223.285995 136.60233) (xy 223.285995 136.58859) (xy 223.285995 136.57486) (xy 223.285995 136.56113)
			(xy 223.285995 136.5474) (xy 223.285995 136.53367) (xy 223.285995 136.51994) (xy 223.285995 136.5062)
			(xy 223.272255 136.5062) (xy 223.272255 136.49247) (xy 223.272255 136.47874) (xy 223.272255 136.46501)
			(xy 223.272255 136.45128) (xy 223.272255 136.43755) (xy 223.272255 136.42381) (xy 223.272255 136.41008)
			(xy 223.272255 136.39635) (xy 223.258525 136.39635) (xy 223.258525 136.38262) (xy 223.258525 136.36889)
			(xy 223.258525 136.35515) (xy 223.258525 136.34142) (xy 223.258525 136.32769) (xy 223.258525 136.31396)
			(xy 223.258525 136.30023) (xy 223.244795 136.30023) (xy 223.244795 136.28649) (xy 223.244795 136.27276)
			(xy 223.244795 136.25903) (xy 223.244795 136.2453) (xy 223.244795 136.23157) (xy 223.244795 136.21784)
			(xy 223.231065 136.21784) (xy 223.231065 136.2041) (xy 223.231065 136.19037) (xy 223.231065 136.17664)
			(xy 223.231065 136.16291) (xy 223.231065 136.14918) (xy 223.217335 136.14918) (xy 223.217335 136.13545)
			(xy 223.217335 136.12171) (xy 223.217335 136.10798) (xy 223.217335 136.09425) (xy 223.217335 136.08052)
			(xy 223.203605 136.08052) (xy 223.203605 136.06679) (xy 223.203605 136.05306) (xy 223.203605 136.03932)
			(xy 223.203605 136.02559) (xy 223.203605 136.01186) (xy 223.189865 136.01186) (xy 223.189865 135.99813)
			(xy 223.189865 135.9844) (xy 223.189865 135.97067) (xy 223.189865 135.95693) (xy 223.189865 135.9432)
			(xy 223.176135 135.9432) (xy 223.176135 135.92947) (xy 223.176135 135.91574) (xy 223.176135 135.90201)
			(xy 223.176135 135.88827) (xy 223.162405 135.88827) (xy 223.162405 135.87454) (xy 223.162405 135.86081)
			(xy 223.162405 135.84708) (xy 223.162405 135.83335) (xy 223.148675 135.83335) (xy 223.148675 135.81961)
			(xy 223.148675 135.80588) (xy 223.148675 135.79215) (xy 223.148675 135.77842) (xy 223.134945 135.77842)
			(xy 223.134945 135.76469) (xy 223.134945 135.75096) (xy 223.134945 135.73722) (xy 223.134945 135.72349)
			(xy 223.121215 135.72349) (xy 223.121215 135.70976) (xy 223.121215 135.69603) (xy 223.121215 135.6823)
			(xy 223.107475 135.6823) (xy 223.107475 135.66857) (xy 223.107475 135.65483) (xy 223.107475 135.6411)
			(xy 223.107475 135.62737) (xy 223.093745 135.62737) (xy 223.093745 135.61364) (xy 223.093745 135.59991)
			(xy 223.093745 135.58618) (xy 223.080015 135.58618) (xy 223.080015 135.57244) (xy 223.080015 135.55871)
			(xy 223.080015 135.54498) (xy 223.080015 135.53125) (xy 223.066285 135.53125) (xy 223.066285 135.51752)
			(xy 223.066285 135.50379) (xy 223.066285 135.49005) (xy 223.052555 135.49005) (xy 223.052555 135.47632)
			(xy 223.052555 135.46259) (xy 223.052555 135.44886) (xy 223.038825 135.44886) (xy 223.038825 135.43513)
			(xy 223.038825 135.4214) (xy 223.038825 135.40766) (xy 223.025085 135.40766) (xy 223.025085 135.39393)
			(xy 223.025085 135.3802) (xy 223.025085 135.36647) (xy 223.011355 135.36647) (xy 223.011355 135.35274)
			(xy 223.011355 135.339) (xy 223.011355 135.32527) (xy 222.997625 135.32527) (xy 222.997625 135.31154)
			(xy 222.997625 135.29781) (xy 222.983895 135.29781) (xy 222.983895 135.28408) (xy 222.983895 135.27034)
			(xy 222.983895 135.25661) (xy 222.970165 135.25661) (xy 222.970165 135.24288) (xy 222.970165 135.22915)
			(xy 222.970165 135.21542) (xy 222.956435 135.21542) (xy 222.956435 135.20169) (xy 222.956435 135.18795)
			(xy 222.942695 135.18795) (xy 222.942695 135.17422) (xy 222.942695 135.16049) (xy 222.942695 135.14676)
			(xy 222.928965 135.14676) (xy 222.928965 135.13303) (xy 222.928965 135.1193) (xy 222.915235 135.1193)
			(xy 222.915235 135.10556) (xy 222.915235 135.09183) (xy 222.915235 135.0781) (xy 222.901505 135.0781)
			(xy 222.901505 135.06437) (xy 222.901505 135.05064) (xy 222.887775 135.05064) (xy 222.887775 135.03691)
			(xy 222.887775 135.02317) (xy 222.874035 135.02317) (xy 222.874035 135.00944) (xy 222.874035 134.99571)
			(xy 222.874035 134.98198) (xy 222.860305 134.98198) (xy 222.860305 134.96825) (xy 222.860305 134.95452)
			(xy 222.846575 134.95452) (xy 222.846575 134.94078) (xy 222.846575 134.92705) (xy 222.832845 134.92705)
			(xy 222.832845 134.91332) (xy 222.832845 134.89959) (xy 222.819115 134.89959) (xy 222.819115 134.88586)
			(xy 222.819115 134.87213) (xy 222.819115 134.85839) (xy 222.805375 134.85839) (xy 222.805375 134.84466)
			(xy 222.805375 134.83093) (xy 222.791645 134.83093) (xy 222.791645 134.8172) (xy 222.791645 134.80347)
			(xy 222.777915 134.80347) (xy 222.777915 134.78973) (xy 222.777915 134.776) (xy 222.764185 134.776)
			(xy 222.764185 134.76227) (xy 222.764185 134.74854) (xy 222.750455 134.74854) (xy 222.750455 134.73481)
			(xy 222.750455 134.72107) (xy 222.736725 134.72107) (xy 222.736725 134.70734) (xy 222.736725 134.69361)
			(xy 222.722985 134.69361) (xy 222.722985 134.67988) (xy 222.722985 134.66615) (xy 222.709255 134.66615)
			(xy 222.709255 134.65242) (xy 222.709255 134.63868) (xy 222.695525 134.63868) (xy 222.695525 134.62495)
			(xy 222.695525 134.61122) (xy 222.681795 134.61122) (xy 222.681795 134.59749) (xy 222.668065 134.59749)
			(xy 222.668065 134.58376) (xy 222.668065 134.57003) (xy 222.654335 134.57003) (xy 222.654335 134.55629)
			(xy 222.654335 134.54256) (xy 222.640595 134.54256) (xy 222.640595 134.52883) (xy 222.640595 134.5151)
			(xy 222.626865 134.5151) (xy 222.626865 134.50137) (xy 222.626865 134.48764) (xy 222.613135 134.48764)
			(xy 222.613135 134.4739) (xy 222.599405 134.4739) (xy 222.599405 134.46017) (xy 222.599405 134.44644)
			(xy 222.585675 134.44644) (xy 222.585675 134.43271) (xy 222.585675 134.41898) (xy 222.571945 134.41898)
			(xy 222.571945 134.40525) (xy 222.558205 134.40525) (xy 222.558205 134.39151) (xy 222.558205 134.37778)
			(xy 222.544475 134.37778) (xy 222.544475 134.36405) (xy 222.544475 134.35032) (xy 222.530745 134.35032)
			(xy 222.530745 134.33659) (xy 222.517015 134.33659) (xy 222.517015 134.32286) (xy 222.517015 134.30912)
			(xy 222.503285 134.30912) (xy 222.503285 134.29539) (xy 222.503285 134.28166) (xy 222.489555 134.28166)
			(xy 222.489555 134.26793) (xy 222.475815 134.26793) (xy 222.475815 134.2542) (xy 222.475815 134.24046)
			(xy 222.462085 134.24046) (xy 222.462085 134.22673) (xy 222.448355 134.22673) (xy 222.448355 134.213)
			(xy 222.448355 134.19927) (xy 222.434625 134.19927) (xy 222.434625 134.18554) (xy 222.420895 134.18554)
			(xy 222.420895 134.1718) (xy 222.420895 134.15807) (xy 222.407165 134.15807) (xy 222.407165 134.14434)
			(xy 222.393425 134.14434) (xy 222.393425 134.13061) (xy 222.393425 134.11688) (xy 222.379695 134.11688)
			(xy 222.379695 134.10315) (xy 222.365965 134.10315) (xy 222.365965 134.08941) (xy 222.365965 134.07568)
			(xy 222.352235 134.07568) (xy 222.352235 134.06195) (xy 222.338505 134.06195) (xy 222.338505 134.04822)
			(xy 222.324765 134.04822) (xy 222.324765 134.03449) (xy 222.324765 134.02076) (xy 222.311035 134.02076)
			(xy 222.311035 134.00702) (xy 222.297305 134.00702) (xy 222.297305 133.99329) (xy 222.297305 133.97956)
			(xy 222.283575 133.97956) (xy 222.283575 133.96583) (xy 222.269845 133.96583) (xy 222.269845 133.9521)
			(xy 222.256105 133.9521) (xy 222.256105 133.93837) (xy 222.256105 133.92463) (xy 222.242375 133.92463)
			(xy 222.242375 133.9109) (xy 222.228645 133.9109) (xy 222.228645 133.89717) (xy 222.214915 133.89717)
			(xy 222.214915 133.88344) (xy 222.201185 133.88344) (xy 222.201185 133.86971) (xy 222.201185 133.85598)
			(xy 222.187455 133.85598) (xy 222.187455 133.84224) (xy 222.173715 133.84224) (xy 222.173715 133.82851)
			(xy 222.159985 133.82851) (xy 222.159985 133.81478) (xy 222.159985 133.80105) (xy 222.146255 133.80105)
			(xy 222.146255 133.78732) (xy 222.132525 133.78732) (xy 222.132525 133.77359) (xy 222.118795 133.77359)
			(xy 222.118795 133.75985) (xy 222.105065 133.75985) (xy 222.105065 133.74612) (xy 222.091325 133.74612)
			(xy 222.091325 133.73239) (xy 222.091325 133.71866) (xy 222.077595 133.71866) (xy 222.077595 133.70493)
			(xy 222.063865 133.70493) (xy 222.063865 133.69119) (xy 222.050135 133.69119) (xy 222.050135 133.67746)
			(xy 222.036405 133.67746) (xy 222.036405 133.66373) (xy 222.022675 133.66373) (xy 222.022675 133.65)
			(xy 222.022675 133.63627) (xy 222.008935 133.63627) (xy 222.008935 133.62253) (xy 221.995205 133.62253)
			(xy 221.995205 133.6088) (xy 221.981475 133.6088) (xy 221.981475 133.59507) (xy 221.967745 133.59507)
			(xy 221.967745 133.58134) (xy 221.954015 133.58134) (xy 221.954015 133.56761) (xy 221.940285 133.56761)
			(xy 221.940285 133.55388) (xy 221.926545 133.55388) (xy 221.926545 133.54014) (xy 221.912815 133.54014)
			(xy 221.912815 133.52641) (xy 221.912815 133.51268) (xy 221.899085 133.51268) (xy 221.899085 133.49895)
			(xy 221.885355 133.49895) (xy 221.885355 133.48522) (xy 221.871625 133.48522) (xy 221.871625 133.47149)
			(xy 221.857895 133.47149) (xy 221.857895 133.45775) (xy 221.844155 133.45775) (xy 221.844155 133.44402)
			(xy 221.830425 133.44402) (xy 221.830425 133.43029) (xy 221.816695 133.43029) (xy 221.816695 133.41656)
			(xy 221.802965 133.41656) (xy 221.802965 133.40283) (xy 221.789235 133.40283) (xy 221.789235 133.3891)
			(xy 221.775495 133.3891) (xy 221.775495 133.37536) (xy 221.761765 133.37536) (xy 221.761765 133.36163)
			(xy 221.748035 133.36163) (xy 221.748035 133.3479) (xy 221.734305 133.3479) (xy 221.734305 133.33417)
			(xy 221.720575 133.33417) (xy 221.720575 133.32044) (xy 221.706835 133.32044) (xy 221.706835 133.30671)
			(xy 221.693105 133.30671) (xy 221.693105 133.29297) (xy 221.679375 133.29297) (xy 221.679375 133.27924)
			(xy 221.665645 133.27924) (xy 221.665645 133.26551) (xy 221.651915 133.26551) (xy 221.651915 133.25178)
			(xy 221.638185 133.25178) (xy 221.638185 133.23805) (xy 221.624445 133.23805) (xy 221.624445 133.22431)
			(xy 221.596985 133.22431) (xy 221.596985 133.21058) (xy 221.583255 133.21058) (xy 221.583255 133.19685)
			(xy 221.569525 133.19685) (xy 221.569525 133.18312) (xy 221.555795 133.18312) (xy 221.555795 133.16939)
			(xy 221.542055 133.16939) (xy 221.542055 133.15565) (xy 221.528325 133.15565) (xy 221.528325 133.14192)
			(xy 221.514595 133.14192) (xy 221.514595 133.12819) (xy 221.500865 133.12819) (xy 221.500865 133.11446)
			(xy 221.487135 133.11446) (xy 221.487135 133.10073) (xy 221.459665 133.10073) (xy 221.459665 133.087)
			(xy 221.445935 133.087) (xy 221.445935 133.07326) (xy 221.432205 133.07326) (xy 221.432205 133.05953)
			(xy 221.418475 133.05953) (xy 221.418475 133.0458) (xy 221.404745 133.0458) (xy 221.404745 133.03207)
			(xy 221.377275 133.03207) (xy 221.377275 133.01834) (xy 221.363545 133.01834) (xy 221.363545 133.00461)
			(xy 221.349815 133.00461) (xy 221.349815 132.99087) (xy 221.336085 132.99087) (xy 221.336085 132.97714)
			(xy 221.322355 132.97714) (xy 221.322355 132.96341) (xy 221.294885 132.96341) (xy 221.294885 132.94968)
			(xy 221.281155 132.94968) (xy 221.281155 132.93595) (xy 221.267425 132.93595) (xy 221.267425 132.92222)
			(xy 221.239955 132.92222) (xy 221.239955 132.90848) (xy 221.226225 132.90848) (xy 221.226225 132.89475)
			(xy 221.212495 132.89475) (xy 221.212495 132.88102) (xy 221.198765 132.88102) (xy 221.198765 132.86729)
			(xy 221.171305 132.86729) (xy 221.171305 132.85356) (xy 221.157565 132.85356) (xy 221.157565 132.83983)
			(xy 221.130105 132.83983) (xy 221.130105 132.82609) (xy 221.116375 132.82609) (xy 221.116375 132.81236)
			(xy 221.102645 132.81236) (xy 221.102645 132.79863) (xy 221.075175 132.79863) (xy 221.075175 132.7849)
			(xy 221.061445 132.7849) (xy 221.061445 132.77117) (xy 221.047715 132.77117) (xy 221.047715 132.75744)
			(xy 221.020255 132.75744) (xy 221.020255 132.7437) (xy 221.006525 132.7437) (xy 221.006525 132.72997)
			(xy 220.979055 132.72997) (xy 220.979055 132.71624) (xy 220.965325 132.71624) (xy 220.965325 132.70251)
			(xy 220.937865 132.70251) (xy 220.937865 132.68878) (xy 220.924135 132.68878) (xy 220.924135 132.67504)
			(xy 220.896665 132.67504) (xy 220.896665 132.66131) (xy 220.882935 132.66131) (xy 220.882935 132.64758)
			(xy 220.855475 132.64758) (xy 220.855475 132.63385) (xy 220.828005 132.63385) (xy 220.828005 132.62012)
			(xy 220.814275 132.62012) (xy 220.814275 132.60638) (xy 220.786815 132.60638) (xy 220.786815 132.59265)
			(xy 220.773085 132.59265) (xy 220.773085 132.57892) (xy 220.745615 132.57892) (xy 220.745615 132.56519)
			(xy 220.718155 132.56519) (xy 220.718155 132.55146) (xy 220.704425 132.55146) (xy 220.704425 132.53773)
			(xy 220.676955 132.53773) (xy 220.676955 132.52399) (xy 220.649495 132.52399) (xy 220.649495 132.51026)
			(xy 220.622035 132.51026) (xy 220.622035 132.49653) (xy 220.608295 132.49653) (xy 220.608295 132.4828)
			(xy 220.580835 132.4828) (xy 220.580835 132.46907) (xy 220.553375 132.46907) (xy 220.553375 132.45534)
			(xy 220.525905 132.45534) (xy 220.525905 132.4416) (xy 220.498445 132.4416) (xy 220.498445 132.42787)
			(xy 220.484715 132.42787) (xy 220.484715 132.41414) (xy 220.443515 132.41414) (xy 220.443515 132.40041)
			(xy 220.429785 132.40041) (xy 220.429785 132.38668) (xy 220.402325 132.38668) (xy 220.402325 132.37295)
			(xy 220.361125 132.37295) (xy 220.361125 132.35921) (xy 220.333665 132.35921) (xy 220.333665 132.34548)
			(xy 220.319935 132.34548) (xy 220.319935 132.33175) (xy 220.292475 132.33175) (xy 220.292475 132.31802)
			(xy 220.251275 132.31802) (xy 220.251275 132.30429) (xy 220.223815 132.30429) (xy 220.223815 132.29056)
			(xy 220.196345 132.29056) (xy 220.196345 132.27682) (xy 220.168885 132.27682) (xy 220.168885 132.26309)
			(xy 220.141415 132.26309) (xy 220.141415 132.24936) (xy 220.100225 132.24936) (xy 220.100225 132.23563)
			(xy 220.072765 132.23563) (xy 220.072765 132.2219) (xy 220.045295 132.2219) (xy 220.045295 132.20817)
			(xy 220.004105 132.20817) (xy 220.004105 132.19443) (xy 219.976635 132.19443) (xy 219.976635 132.1807)
			(xy 219.935445 132.1807) (xy 219.935445 132.16697) (xy 219.894245 132.16697) (xy 219.894245 132.15324)
			(xy 219.866785 132.15324) (xy 219.866785 132.13951) (xy 219.825595 132.13951) (xy 219.825595 132.12577)
			(xy 219.784395 132.12577) (xy 219.784395 132.11204) (xy 219.743205 132.11204) (xy 219.743205 132.09831)
			(xy 219.715735 132.09831) (xy 219.715735 132.08458) (xy 219.674545 132.08458) (xy 219.674545 132.07085)
			(xy 219.633345 132.07085) (xy 219.633345 132.05711) (xy 219.578415 132.05711) (xy 219.578415 132.04338)
			(xy 219.537225 132.04338) (xy 219.537225 132.02965) (xy 219.496025 132.02965) (xy 219.496025 132.01592)
			(xy 219.441105 132.01592) (xy 219.441105 132.00219) (xy 219.399905 132.00219) (xy 219.399905 131.98846)
			(xy 219.344975 131.98846) (xy 219.344975 131.97472) (xy 219.290055 131.97472) (xy 219.290055 131.96099)
			(xy 219.235125 131.96099) (xy 219.235125 131.94726) (xy 219.180195 131.94726) (xy 219.180195 131.93353)
			(xy 219.111535 131.93353) (xy 219.111535 131.9198) (xy 219.042875 131.9198) (xy 219.042875 131.90607)
			(xy 218.974225 131.90607) (xy 218.974225 131.89233) (xy 218.891835 131.89233) (xy 218.891835 131.8786)
			(xy 218.809445 131.8786) (xy 218.809445 131.86487) (xy 218.699585 131.86487) (xy 218.699585 131.85114)
			(xy 218.589735 131.85114) (xy 218.589735 131.83741) (xy 218.466145 131.83741) (xy 218.466145 131.82368)
			(xy 218.260175 131.82368) (xy 218.260175 131.80995) (xy 217.752095 131.80995) (xy 217.752095 131.82368)
			(xy 217.546115 131.82368) (xy 217.546115 131.83741) (xy 217.408805 131.83741) (xy 217.408805 131.85114)
			(xy 217.298945 131.85114) (xy 217.298945 131.86487) (xy 217.216555 131.86487) (xy 217.216555 131.8786)
			(xy 217.120435 131.8786) (xy 217.120435 131.89233) (xy 217.038045 131.89233) (xy 217.038045 131.90607)
			(xy 216.969385 131.90607) (xy 216.969385 131.9198) (xy 216.900725 131.9198) (xy 216.900725 131.93353)
			(xy 216.832065 131.93353) (xy 216.832065 131.94726) (xy 216.777145 131.94726) (xy 216.777145 131.96099)
			(xy 216.722215 131.96099) (xy 216.722215 131.97472) (xy 216.667285 131.97472) (xy 216.667285 131.98846)
			(xy 216.612365 131.98846) (xy 216.612365 132.00219) (xy 216.571165 132.00219) (xy 216.571165 132.01592)
			(xy 216.516235 132.01592) (xy 216.516235 132.02965) (xy 216.475045 132.02965) (xy 216.475045 132.04338)
			(xy 216.433845 132.04338) (xy 216.433845 132.05711) (xy 216.378925 132.05711) (xy 216.378925 132.07085)
			(xy 216.337725 132.07085) (xy 216.337725 132.08458) (xy 216.296535 132.08458) (xy 216.296535 132.09831)
			(xy 216.255335 132.09831) (xy 216.255335 132.11204) (xy 216.227875 132.11204) (xy 216.227875 132.12577)
			(xy 216.186675 132.12577) (xy 216.186675 132.13951) (xy 216.145485 132.13951) (xy 216.145485 132.15324)
			(xy 216.104285 132.15324) (xy 216.104285 132.16697) (xy 216.076825 132.16697) (xy 216.076825 132.1807)
			(xy 216.035625 132.1807) (xy 216.035625 132.19443) (xy 216.008165 132.19443) (xy 216.008165 132.20817)
			(xy 215.966965 132.20817) (xy 215.966965 132.2219) (xy 215.939505 132.2219) (xy 215.939505 132.23563)
			(xy 215.912045 132.23563) (xy 215.912045 132.24936) (xy 215.870845 132.24936) (xy 215.870845 132.26309)
			(xy 215.843385 132.26309) (xy 215.843385 132.27682) (xy 215.815915 132.27682) (xy 215.815915 132.29056)
			(xy 215.788455 132.29056) (xy 215.788455 132.30429) (xy 215.747265 132.30429) (xy 215.747265 132.31802)
			(xy 215.719795 132.31802) (xy 215.719795 132.33175) (xy 215.692335 132.33175) (xy 215.692335 132.34548)
			(xy 215.664875 132.34548) (xy 215.664875 132.35921) (xy 215.637405 132.35921) (xy 215.637405 132.37295)
			(xy 215.609945 132.37295) (xy 215.609945 132.38668) (xy 215.582485 132.38668) (xy 215.582485 132.40041)
			(xy 215.555015 132.40041) (xy 215.555015 132.41414) (xy 215.527555 132.41414) (xy 215.527555 132.42787)
			(xy 215.500085 132.42787) (xy 215.500085 132.4416) (xy 215.486355 132.4416) (xy 215.486355 132.45534)
			(xy 215.458895 132.45534) (xy 215.458895 132.46907) (xy 215.431425 132.46907) (xy 215.431425 132.4828)
			(xy 215.403965 132.4828) (xy 215.403965 132.49653) (xy 215.376505 132.49653) (xy 215.376505 132.51026)
			(xy 215.362775 132.51026) (xy 215.362775 132.52399) (xy 215.335305 132.52399) (xy 215.335305 132.53773)
			(xy 215.307845 132.53773) (xy 215.307845 132.55146) (xy 215.294115 132.55146) (xy 215.294115 132.56519)
			(xy 215.266645 132.56519) (xy 215.266645 132.57892) (xy 215.239185 132.57892) (xy 215.239185 132.59265)
			(xy 215.225455 132.59265) (xy 215.225455 132.60638) (xy 215.197995 132.60638) (xy 215.197995 132.62012)
			(xy 215.170525 132.62012) (xy 215.170525 132.63385) (xy 215.156795 132.63385) (xy 215.156795 132.64758)
			(xy 215.129335 132.64758) (xy 215.129335 132.66131) (xy 215.115605 132.66131) (xy 215.115605 132.67504)
			(xy 215.088135 132.67504) (xy 215.088135 132.68878) (xy 215.074405 132.68878) (xy 215.074405 132.70251)
			(xy 215.046945 132.70251) (xy 215.046945 132.71624) (xy 215.033215 132.71624) (xy 215.033215 132.72997)
			(xy 215.005745 132.72997) (xy 215.005745 132.7437) (xy 214.992015 132.7437) (xy 214.992015 132.75744)
			(xy 214.964555 132.75744) (xy 214.964555 132.77117) (xy 214.950815 132.77117) (xy 214.950815 132.7849)
			(xy 214.937085 132.7849) (xy 214.937085 132.79863) (xy 214.909625 132.79863) (xy 214.909625 132.81236)
			(xy 214.895895 132.81236) (xy 214.895895 132.82609) (xy 214.868425 132.82609) (xy 214.868425 132.83983)
			(xy 214.854695 132.83983) (xy 214.854695 132.85356) (xy 214.840965 132.85356) (xy 214.840965 132.86729)
			(xy 214.813505 132.86729) (xy 214.813505 132.88102) (xy 214.799765 132.88102) (xy 214.799765 132.89475)
			(xy 214.786035 132.89475) (xy 214.786035 132.90848) (xy 214.758575 132.90848) (xy 214.758575 132.92222)
			(xy 214.744845 132.92222) (xy 214.744845 132.93595) (xy 214.731115 132.93595) (xy 214.731115 132.94968)
			(xy 214.717375 132.94968) (xy 214.717375 132.96341) (xy 214.689915 132.96341) (xy 214.689915 132.97714)
			(xy 214.676185 132.97714) (xy 214.676185 132.99087) (xy 214.662455 132.99087) (xy 214.662455 133.00461)
			(xy 214.648725 133.00461) (xy 214.648725 133.01834) (xy 214.621255 133.01834) (xy 214.621255 133.03207)
			(xy 214.607525 133.03207) (xy 214.607525 133.0458) (xy 214.593795 133.0458) (xy 214.593795 133.05953)
			(xy 214.580065 133.05953) (xy 214.580065 133.07326) (xy 214.566335 133.07326) (xy 214.566335 133.087)
			(xy 214.538865 133.087) (xy 214.538865 133.10073) (xy 214.525135 133.10073) (xy 214.525135 133.11446)
			(xy 214.511405 133.11446) (xy 214.511405 133.12819) (xy 214.497675 133.12819) (xy 214.497675 133.14192)
			(xy 214.483935 133.14192) (xy 214.483935 133.15565) (xy 214.470205 133.15565) (xy 214.470205 133.16939)
			(xy 214.456475 133.16939) (xy 214.456475 133.18312) (xy 214.442745 133.18312) (xy 214.442745 133.19685)
			(xy 214.415275 133.19685) (xy 214.415275 133.21058) (xy 214.401545 133.21058) (xy 214.401545 133.22431)
			(xy 214.387815 133.22431) (xy 214.387815 133.23805) (xy 214.374085 133.23805) (xy 214.374085 133.25178)
			(xy 214.360355 133.25178) (xy 214.360355 133.26551) (xy 214.346625 133.26551) (xy 214.346625 133.27924)
			(xy 214.332885 133.27924) (xy 214.332885 133.29297) (xy 214.319155 133.29297) (xy 214.319155 133.30671)
			(xy 214.305425 133.30671) (xy 214.305425 133.32044) (xy 214.291695 133.32044) (xy 214.291695 133.33417)
			(xy 214.277965 133.33417) (xy 214.277965 133.3479) (xy 214.264235 133.3479) (xy 214.264235 133.36163)
			(xy 214.250495 133.36163) (xy 214.250495 133.37536) (xy 214.236765 133.37536) (xy 214.236765 133.3891)
			(xy 214.223035 133.3891) (xy 214.223035 133.40283) (xy 214.209305 133.40283) (xy 214.209305 133.41656)
			(xy 214.195575 133.41656) (xy 214.195575 133.43029) (xy 214.181845 133.43029) (xy 214.181845 133.44402)
			(xy 214.168105 133.44402) (xy 214.168105 133.45775) (xy 214.154375 133.45775) (xy 214.154375 133.47149)
			(xy 214.140645 133.47149) (xy 214.140645 133.48522) (xy 214.126915 133.48522) (xy 214.126915 133.49895)
			(xy 214.113185 133.49895) (xy 214.113185 133.51268) (xy 214.099455 133.51268) (xy 214.099455 133.52641)
			(xy 214.085715 133.52641) (xy 214.085715 133.54014) (xy 214.085715 133.55388) (xy 214.071985 133.55388)
			(xy 214.071985 133.56761) (xy 214.058255 133.56761) (xy 214.058255 133.58134) (xy 214.044525 133.58134)
			(xy 214.044525 133.59507) (xy 214.030795 133.59507) (xy 214.030795 133.6088) (xy 214.017065 133.6088)
			(xy 214.017065 133.62253) (xy 214.003325 133.62253) (xy 214.003325 133.63627) (xy 213.989595 133.63627)
			(xy 213.989595 133.65) (xy 213.975865 133.65) (xy 213.975865 133.66373) (xy 213.975865 133.67746)
			(xy 213.962135 133.67746) (xy 213.962135 133.69119) (xy 213.948405 133.69119) (xy 213.948405 133.70493)
			(xy 213.934665 133.70493) (xy 213.934665 133.71866) (xy 213.920935 133.71866) (xy 213.920935 133.73239)
			(xy 213.907205 133.73239) (xy 213.907205 133.74612) (xy 213.907205 133.75985) (xy 213.893475 133.75985)
			(xy 213.893475 133.77359) (xy 213.879745 133.77359) (xy 213.879745 133.78732) (xy 213.866005 133.78732)
			(xy 209.526775 133.78732) (xy 209.526775 133.77359) (xy 209.526775 133.75985) (xy 209.526775 133.74612)
			(xy 209.526775 133.73239) (xy 209.526775 133.71866) (xy 209.526775 133.70493) (xy 209.526775 133.69119)
			(xy 209.526775 133.67746) (xy 209.526775 133.66373) (xy 209.526775 133.65) (xy 209.526775 133.63627)
			(xy 209.526775 133.62253) (xy 209.526775 133.6088) (xy 209.526775 133.59507) (xy 209.526775 133.58134)
			(xy 209.526775 133.56761) (xy 209.526775 133.55388) (xy 209.526775 133.54014) (xy 209.526775 133.52641)
			(xy 209.526775 133.51268) (xy 209.526775 133.49895) (xy 209.526775 133.48522) (xy 209.526775 133.47149)
			(xy 209.526775 133.45775) (xy 209.526775 133.44402) (xy 209.526775 133.43029) (xy 209.526775 133.41656)
			(xy 209.526775 133.40283) (xy 209.526775 133.3891) (xy 209.526775 133.37536) (xy 209.526775 133.36163)
			(xy 209.526775 133.3479) (xy 209.526775 133.33417) (xy 209.526775 133.32044) (xy 209.526775 133.30671)
			(xy 209.526775 133.29297) (xy 209.526775 133.27924) (xy 209.526775 133.26551) (xy 209.526775 133.25178)
			(xy 209.526775 133.23805) (xy 209.526775 133.22431) (xy 209.526775 133.21058) (xy 209.526775 133.19685)
			(xy 209.526775 133.18312) (xy 209.526775 133.16939) (xy 209.526775 133.15565) (xy 209.526775 133.14192)
			(xy 209.526775 133.12819) (xy 209.526775 133.11446) (xy 209.526775 133.10073) (xy 209.526775 133.087)
			(xy 209.526775 133.07326) (xy 209.526775 133.05953) (xy 209.526775 133.0458) (xy 209.526775 133.03207)
			(xy 209.526775 133.01834) (xy 209.526775 133.00461) (xy 209.526775 132.99087) (xy 209.526775 132.97714)
			(xy 209.526775 132.96341) (xy 209.526775 132.94968) (xy 209.526775 132.93595) (xy 209.526775 132.92222)
			(xy 209.526775 132.90848) (xy 209.526775 132.89475) (xy 209.526775 132.88102) (xy 209.526775 132.86729)
			(xy 209.526775 132.85356) (xy 209.526775 132.83983) (xy 209.526775 132.82609) (xy 209.526775 132.81236)
			(xy 209.526775 132.79863) (xy 209.526775 132.7849) (xy 209.526775 132.77117) (xy 209.526775 132.75744)
			(xy 209.526775 132.7437) (xy 209.526775 132.72997) (xy 209.526775 132.71624) (xy 209.526775 132.70251)
			(xy 209.526775 132.68878) (xy 209.526775 132.67504) (xy 209.526775 132.66131) (xy 209.526775 132.64758)
			(xy 209.526775 132.63385) (xy 209.526775 132.62012) (xy 209.526775 132.60638) (xy 209.526775 132.59265)
			(xy 209.526775 132.57892) (xy 209.526775 132.56519) (xy 209.526775 132.55146) (xy 209.526775 132.53773)
			(xy 209.526775 132.52399) (xy 209.526775 132.51026) (xy 209.526775 132.49653) (xy 209.526775 132.4828)
			(xy 209.526775 132.46907) (xy 209.526775 132.45534) (xy 209.526775 132.4416) (xy 209.526775 132.42787)
			(xy 209.526775 132.41414) (xy 209.526775 132.40041) (xy 209.526775 132.38668) (xy 209.526775 132.37295)
			(xy 209.526775 132.35921) (xy 209.526775 132.34548) (xy 209.526775 132.33175) (xy 209.526775 132.31802)
			(xy 209.526775 132.30429) (xy 209.526775 132.29056) (xy 209.526775 132.27682) (xy 209.526775 132.26309)
			(xy 209.526775 132.24936) (xy 209.526775 132.23563) (xy 209.526775 132.2219) (xy 209.526775 132.20817)
			(xy 209.526775 132.19443) (xy 209.526775 132.1807) (xy 209.526775 132.16697) (xy 209.526775 132.15324)
			(xy 209.526775 132.13951) (xy 209.526775 132.12577) (xy 209.526775 132.11204) (xy 209.526775 132.09831)
			(xy 209.526775 132.08458) (xy 209.526775 132.07085) (xy 209.526775 132.05711) (xy 209.526775 132.04338)
			(xy 209.526775 132.02965) (xy 209.526775 132.01592) (xy 209.526775 132.00219) (xy 209.526775 131.98846)
			(xy 209.526775 131.97472) (xy 209.526775 131.96099) (xy 209.526775 131.94726) (xy 209.526775 131.93353)
			(xy 209.526775 131.9198) (xy 209.526775 131.90607) (xy 209.526775 131.89233) (xy 209.526775 131.8786)
			(xy 209.526775 131.86487) (xy 209.526775 131.85114) (xy 209.526775 131.83741) (xy 209.526775 131.82368)
			(xy 209.526775 131.80995) (xy 209.526775 131.79621) (xy 209.526775 131.78248) (xy 209.526775 131.76875)
			(xy 209.526775 131.75502) (xy 209.526775 131.74129) (xy 209.526775 131.72756) (xy 209.526775 131.71382)
			(xy 209.526775 131.70009) (xy 209.526775 131.68636) (xy 209.526775 131.67263) (xy 209.526775 131.6589)
			(xy 209.526775 131.64516) (xy 209.526775 131.63143) (xy 209.526775 131.6177) (xy 209.526775 131.60397)
			(xy 209.526775 131.59024) (xy 209.526775 131.5765) (xy 209.526775 131.56277) (xy 209.526775 131.54904)
			(xy 209.526775 131.53531) (xy 209.526775 131.52158) (xy 209.526775 131.50785) (xy 209.526775 131.49411)
			(xy 209.526775 131.48038) (xy 209.526775 131.46665) (xy 209.526775 131.45292) (xy 209.526775 131.43919)
			(xy 209.526775 131.42546) (xy 209.526775 131.41172) (xy 209.526775 131.39799) (xy 209.526775 131.38426)
			(xy 209.526775 131.37053) (xy 209.526775 131.3568) (xy 209.526775 131.34307) (xy 209.526775 131.32933)
			(xy 209.526775 131.3156) (xy 209.526775 131.30187) (xy 209.526775 131.28814) (xy 209.526775 131.27441)
			(xy 209.526775 131.26068) (xy 209.526775 131.24694) (xy 209.526775 131.23321) (xy 209.526775 131.21948)
			(xy 209.526775 131.20575) (xy 209.526775 131.19202) (xy 209.526775 131.17828) (xy 209.526775 131.16455)
			(xy 209.526775 131.15082) (xy 209.526775 131.13709) (xy 209.526775 131.12336) (xy 209.526775 131.10962)
			(xy 209.526775 131.09589) (xy 209.526775 131.08216) (xy 209.526775 131.06843) (xy 209.526775 131.0547)
			(xy 209.526775 131.04097) (xy 209.526775 131.02723) (xy 209.526775 131.0135) (xy 209.526775 130.99977)
			(xy 209.526775 130.98604) (xy 209.526775 130.97231) (xy 209.526775 130.95858) (xy 209.526775 130.94484)
			(xy 209.526775 130.93111) (xy 209.526775 130.91738) (xy 209.526775 130.90365) (xy 209.526775 130.88992)
			(xy 209.526775 130.87619) (xy 209.526775 130.86245) (xy 209.526775 130.84872) (xy 209.526775 130.83499)
			(xy 209.526775 130.82126) (xy 209.526775 130.80753) (xy 209.526775 130.7938) (xy 209.526775 130.78006)
			(xy 209.526775 130.76633) (xy 209.526775 130.7526) (xy 209.526775 130.73887) (xy 209.526775 130.72514)
			(xy 209.526775 130.71141) (xy 209.526775 130.69767) (xy 209.526775 130.68394) (xy 209.540505 130.68394)
			(xy 209.540505 130.67021) (xy 226.869975 130.67021)
		)
		(stroke
			(width 0)
			(type default)
		)
		(fill yes)
		(layer "F.Cu")
	)
	(gr_rect
		(start 103.788595 154.6036)
		(end 106.463595 152.8786)
		(stroke
			(width 0)
			(type default)
		)
		(fill yes)
		(layer "F.Cu")
		(net "+12V_PCIE")
	)
	(gr_rect
		(start 105.188595 153.0786)
		(end 106.188595 146.7786)
		(stroke
			(width 0)
			(type default)
		)
		(fill yes)
		(layer "F.Cu")
		(net "+12V_PCIE")
	)
	(gr_rect
		(start 110.738595 154.5786)
		(end 113.543575 152.8786)
		(stroke
			(width 0)
			(type default)
		)
		(fill yes)
		(layer "F.Cu")
		(net "+3.3V_PCIE")
	)
	(gr_rect
		(start 111.238595 147.3286)
		(end 113.738595 144.0786)
		(stroke
			(width 0)
			(type default)
		)
		(fill yes)
		(layer "F.Cu")
		(net "+12V")
	)
	(gr_rect
		(start 104.588595 154.6036)
		(end 106.463595 152.8786)
		(stroke
			(width 0)
			(type default)
		)
		(fill yes)
		(layer "B.Cu")
		(net "+12V_PCIE")
	)
	(gr_rect
		(start 111.238595 147.3286)
		(end 113.738595 145.5786)
		(stroke
			(width 0)
			(type default)
		)
		(fill yes)
		(layer "B.Cu")
		(net "+12V")
	)
	(gr_rect
		(start 111.668575 154.62058)
		(end 113.543575 152.89558)
		(stroke
			(width 0)
			(type default)
		)
		(fill yes)
		(layer "B.Cu")
		(net "+3.3V_PCIE")
	)
	(gr_line
		(start 58.488595 49.4286)
		(end 58.488595 156.0786)
		(stroke
			(width 0.05)
			(type solid)
		)
		(layer "Edge.Cuts")
	)
	(gr_line
		(start 58.488595 156.0786)
		(end 73.488595 156.0786)
		(stroke
			(width 0.05)
			(type solid)
		)
		(layer "Edge.Cuts")
	)
	(gr_line
		(start 73.488595 147.8286)
		(end 91.838595 147.8286)
		(stroke
			(width 0.05)
			(type solid)
		)
		(layer "Edge.Cuts")
	)
	(gr_line
		(start 73.488595 156.0786)
		(end 73.488595 147.8286)
		(stroke
			(width 0.05)
			(type solid)
		)
		(layer "Edge.Cuts")
	)
	(gr_line
		(start 91.838595 147.8286)
		(end 91.838595 156.0786)
		(stroke
			(width 0.05)
			(type solid)
		)
		(layer "Edge.Cuts")
	)
	(gr_line
		(start 91.838595 156.0786)
		(end 99.838595 156.0786)
		(stroke
			(width 0.05)
			(type solid)
		)
		(layer "Edge.Cuts")
	)
	(gr_arc
		(start 99.838595 149.6536)
		(mid 101.663595 147.8286)
		(end 103.488595 149.6536)
		(stroke
			(width 0.05)
			(type solid)
		)
		(layer "Edge.Cuts")
	)
	(gr_line
		(start 99.838595 156.0786)
		(end 99.838595 149.6536)
		(stroke
			(width 0.05)
			(type solid)
		)
		(layer "Edge.Cuts")
	)
	(gr_line
		(start 103.488595 149.6536)
		(end 103.488595 160.0786)
		(stroke
			(width 0.05)
			(type solid)
		)
		(layer "Edge.Cuts")
	)
	(gr_line
		(start 103.488595 160.0786)
		(end 103.988595 160.5786)
		(stroke
			(width 0.05)
			(type solid)
		)
		(layer "Edge.Cuts")
	)
	(gr_line
		(start 103.988595 160.5786)
		(end 114.188595 160.5786)
		(stroke
			(width 0.05)
			(type solid)
		)
		(layer "Edge.Cuts")
	)
	(gr_line
		(start 114.188595 160.5786)
		(end 114.688595 160.0786)
		(stroke
			(width 0.05)
			(type solid)
		)
		(layer "Edge.Cuts")
	)
	(gr_arc
		(start 114.688595 153.1286)
		(mid 115.638595 152.1786)
		(end 116.588595 153.1286)
		(stroke
			(width 0.05)
			(type solid)
		)
		(layer "Edge.Cuts")
	)
	(gr_line
		(start 114.688595 160.0786)
		(end 114.688595 153.1286)
		(stroke
			(width 0.05)
			(type solid)
		)
		(layer "Edge.Cuts")
	)
	(gr_line
		(start 116.588595 153.1286)
		(end 116.588595 160.0786)
		(stroke
			(width 0.05)
			(type solid)
		)
		(layer "Edge.Cuts")
	)
	(gr_line
		(start 116.588595 160.0786)
		(end 117.088595 160.5786)
		(stroke
			(width 0.05)
			(type solid)
		)
		(layer "Edge.Cuts")
	)
	(gr_line
		(start 117.088595 160.5786)
		(end 137.288595 160.5786)
		(stroke
			(width 0.05)
			(type solid)
		)
		(layer "Edge.Cuts")
	)
	(gr_line
		(start 137.288595 160.5786)
		(end 137.788595 160.0786)
		(stroke
			(width 0.05)
			(type solid)
		)
		(layer "Edge.Cuts")
	)
	(gr_line
		(start 137.788595 147.8286)
		(end 238.513605 147.8286)
		(stroke
			(width 0.05)
			(type solid)
		)
		(layer "Edge.Cuts")
	)
	(gr_line
		(start 137.788595 160.0786)
		(end 137.788595 147.8286)
		(stroke
			(width 0.05)
			(type solid)
		)
		(layer "Edge.Cuts")
	)
	(gr_line
		(start 238.513595 49.4286)
		(end 58.488595 49.4286)
		(stroke
			(width 0.05)
			(type solid)
		)
		(layer "Edge.Cuts")
	)
	(gr_line
		(start 238.513605 147.8286)
		(end 238.513595 49.4286)
		(stroke
			(width 0.05)
			(type solid)
		)
		(layer "Edge.Cuts")
	)
	(via
		(at 120.496095 53.98361)
		(size 5.08)
		(drill 3.0988)
		(layers "F.Cu" "B.Cu")
		(net "")
	)
	(via
		(at 120.496095 79.98361)
		(size 5.08)
		(drill 3.0988)
		(layers "F.Cu" "B.Cu")
		(net "")
	)
	(via
		(at 180.996105 79.98361)
		(size 5.08)
		(drill 3.0988)
		(layers "F.Cu" "B.Cu")
		(net "")
	)
	(via
		(at 180.996105 53.98361)
		(size 5.08)
		(drill 3.0988)
		(layers "F.Cu" "B.Cu")
		(net "")
	)
	(segment
		(start 83.238595 136.1286)
		(end 83.338595 136.0286)
		(width 0.2032)
		(layer "F.Cu")
		(net "NetR25_1")
	)
	(segment
		(start 83.338595 136.0286)
		(end 84.988605 136.0286)
		(width 0.2032)
		(layer "F.Cu")
		(net "NetR25_1")
	)
	(segment
		(start 83.238595 109.3786)
		(end 83.438595 109.5786)
		(width 0.2032)
		(layer "F.Cu")
		(net "NetR17_1")
	)
	(segment
		(start 83.438595 109.5786)
		(end 85.238595 109.5786)
		(width 0.2032)
		(layer "F.Cu")
		(net "NetR17_1")
	)
	(segment
		(start 85.238595 109.5786)
		(end 85.288595 109.6286)
		(width 0.2032)
		(layer "F.Cu")
		(net "NetR17_1")
	)
	(segment
		(start 83.238595 123.1286)
		(end 83.238595 123.127)
		(width 0.2032)
		(layer "F.Cu")
		(net "NetR15_1")
	)
	(segment
		(start 83.288595 122.8286)
		(end 85.038595 122.8286)
		(width 0.2032)
		(layer "F.Cu")
		(net "NetR15_1")
	)
	(segment
		(start 83.238595 122.8786)
		(end 83.288595 122.8286)
		(width 0.2032)
		(layer "F.Cu")
		(net "NetR15_1")
	)
	(segment
		(start 83.238595 96.1286)
		(end 85.288595 96.1286)
		(width 0.2032)
		(layer "F.Cu")
		(net "NetR14_1")
	)
	(segment
		(start 182.738595 88.3286)
		(end 183.688595 88.3286)
		(width 0.2032)
		(layer "F.Cu")
		(net "NetR13_1")
	)
	(segment
		(start 181.338595 88.1936)
		(end 182.603595 88.1936)
		(width 0.2032)
		(layer "F.Cu")
		(net "NetR13_1")
	)
	(segment
		(start 183.688595 88.3286)
		(end 183.738595 88.3786)
		(width 0.2032)
		(layer "F.Cu")
		(net "NetR13_1")
	)
	(segment
		(start 182.603595 88.1936)
		(end 182.738595 88.3286)
		(width 0.2032)
		(layer "F.Cu")
		(net "NetR13_1")
	)
	(segment
		(start 160.660295 119.71188)
		(end 162.071115 119.71188)
		(width 0.2032)
		(layer "F.Cu")
		(net "MAC_PPS_IN1-")
	)
	(segment
		(start 199.288595 86.8086)
		(end 199.298595 86.8186)
		(width 0.2032)
		(layer "F.Cu")
		(net "MAC_PPS_IN1-")
	)
	(segment
		(start 160.543585 119.8286)
		(end 160.660295 119.71188)
		(width 0.2032)
		(layer "F.Cu")
		(net "MAC_PPS_IN1-")
	)
	(segment
		(start 201.978595 86.8186)
		(end 201.988595 86.8286)
		(width 0.2032)
		(layer "F.Cu")
		(net "MAC_PPS_IN1-")
	)
	(segment
		(start 160.488595 119.8286)
		(end 160.543585 119.8286)
		(width 0.2032)
		(layer "F.Cu")
		(net "MAC_PPS_IN1-")
	)
	(segment
		(start 199.298595 86.8186)
		(end 201.978595 86.8186)
		(width 0.2032)
		(layer "F.Cu")
		(net "MAC_PPS_IN1-")
	)
	(via
		(at 160.488595 119.8286)
		(size 0.4064)
		(drill 0.2032)
		(layers "F.Cu" "B.Cu")
		(tenting
			(front yes)
			(back yes)
		)
		(net "MAC_PPS_IN1-")
	)
	(via
		(at 201.978595 86.8186)
		(size 0.4064)
		(drill 0.2032)
		(layers "F.Cu" "B.Cu")
		(tenting
			(front yes)
			(back yes)
		)
		(net "MAC_PPS_IN1-")
	)
	(segment
		(start 201.978595 87.0165)
		(end 201.978595 86.8186)
		(width 0.2032)
		(layer "In2.Cu")
		(net "MAC_PPS_IN1-")
	)
	(segment
		(start 193.232545 119.33465)
		(end 204.744645 107.82255)
		(width 0.2032)
		(layer "In2.Cu")
		(net "MAC_PPS_IN1-")
	)
	(segment
		(start 160.488595 119.8286)
		(end 192.040045 119.8286)
		(width 0.2032)
		(layer "In2.Cu")
		(net "MAC_PPS_IN1-")
	)
	(segment
		(start 202.722545 88.81255)
		(end 204.744645 90.83465)
		(width 0.2032)
		(layer "In2.Cu")
		(net "MAC_PPS_IN1-")
	)
	(segment
		(start 205.488595 106.0265)
		(end 205.488595 92.6307)
		(width 0.2032)
		(layer "In2.Cu")
		(net "MAC_PPS_IN1-")
	)
	(arc
		(start 204.744646 90.834649)
		(mid 205.295249 91.658684)
		(end 205.488595 92.6307)
		(width 0.2032)
		(layer "In2.Cu")
		(net "MAC_PPS_IN1-")
	)
	(arc
		(start 205.488595 106.0265)
		(mid 205.295249 106.998516)
		(end 204.744646 107.822551)
		(width 0.2032)
		(layer "In2.Cu")
		(net "MAC_PPS_IN1-")
	)
	(arc
		(start 202.722544 88.812551)
		(mid 202.171941 87.988516)
		(end 201.978595 87.0165)
		(width 0.2032)
		(layer "In2.Cu")
		(net "MAC_PPS_IN1-")
	)
	(arc
		(start 193.232547 119.334649)
		(mid 192.685423 119.700227)
		(end 192.040045 119.8286)
		(width 0.2032)
		(layer "In2.Cu")
		(net "MAC_PPS_IN1-")
	)
	(segment
		(start 122.688235 100.66825)
		(end 122.711605 100.69162)
		(width 0.2032)
		(layer "F.Cu")
		(net "MAC_FREQ_CTRL")
	)
	(segment
		(start 122.711605 102.35161)
		(end 122.738595 102.3786)
		(width 0.2032)
		(layer "F.Cu")
		(net "MAC_FREQ_CTRL")
	)
	(segment
		(start 122.711605 102.35161)
		(end 122.711605 100.69162)
		(width 0.2032)
		(layer "F.Cu")
		(net "MAC_FREQ_CTRL")
	)
	(via
		(at 122.738595 102.3786)
		(size 0.4064)
		(drill 0.2032)
		(layers "F.Cu" "B.Cu")
		(tenting
			(front yes)
			(back yes)
		)
		(net "MAC_FREQ_CTRL")
	)
	(segment
		(start 122.738595 112.9765)
		(end 122.738595 102.3786)
		(width 0.2032)
		(layer "In3.Cu")
		(net "MAC_FREQ_CTRL")
	)
	(segment
		(start 140.315695 130.5536)
		(end 191.678975 130.5536)
		(width 0.2032)
		(layer "In3.Cu")
		(net "MAC_FREQ_CTRL")
	)
	(segment
		(start 193.475025 131.29755)
		(end 200.406075 138.2286)
		(width 0.2032)
		(layer "In3.Cu")
		(net "MAC_FREQ_CTRL")
	)
	(segment
		(start 123.482545 114.77255)
		(end 138.519645 129.80965)
		(width 0.2032)
		(layer "In3.Cu")
		(net "MAC_FREQ_CTRL")
	)
	(arc
		(start 140.315695 130.5536)
		(mid 139.343679 130.360254)
		(end 138.519644 129.809651)
		(width 0.2032)
		(layer "In3.Cu")
		(net "MAC_FREQ_CTRL")
	)
	(arc
		(start 191.678975 130.5536)
		(mid 192.650991 130.746946)
		(end 193.475026 131.297549)
		(width 0.2032)
		(layer "In3.Cu")
		(net "MAC_FREQ_CTRL")
	)
	(arc
		(start 123.482544 114.772551)
		(mid 122.931941 113.948516)
		(end 122.738595 112.9765)
		(width 0.2032)
		(layer "In3.Cu")
		(net "MAC_FREQ_CTRL")
	)
	(segment
		(start 125.188475 102.37848)
		(end 125.188475 100.66837)
		(width 0.2032)
		(layer "F.Cu")
		(net "FPGA_MAC_PPS_OUT-")
	)
	(segment
		(start 183.688595 90.7786)
		(end 183.688595 89.8286)
		(width 0.2032)
		(layer "F.Cu")
		(net "FPGA_MAC_PPS_OUT-")
	)
	(segment
		(start 125.188475 102.37848)
		(end 125.188595 102.3786)
		(width 0.2032)
		(layer "F.Cu")
		(net "FPGA_MAC_PPS_OUT-")
	)
	(segment
		(start 125.188355 100.66825)
		(end 125.188475 100.66837)
		(width 0.2032)
		(layer "F.Cu")
		(net "FPGA_MAC_PPS_OUT-")
	)
	(segment
		(start 183.688595 89.8286)
		(end 183.738595 89.7786)
		(width 0.2032)
		(layer "F.Cu")
		(net "FPGA_MAC_PPS_OUT-")
	)
	(via
		(at 125.188595 102.3786)
		(size 0.4064)
		(drill 0.2032)
		(layers "F.Cu" "B.Cu")
		(tenting
			(front yes)
			(back yes)
		)
		(net "FPGA_MAC_PPS_OUT-")
	)
	(via
		(at 183.688595 90.7786)
		(size 0.4064)
		(drill 0.2032)
		(layers "F.Cu" "B.Cu")
		(tenting
			(front yes)
			(back yes)
		)
		(net "FPGA_MAC_PPS_OUT-")
	)
	(segment
		(start 125.188595 88.6286)
		(end 129.488595 84.3286)
		(width 0.2032)
		(layer "In2.Cu")
		(net "FPGA_MAC_PPS_OUT-")
	)
	(segment
		(start 182.740695 90.7786)
		(end 183.688595 90.7786)
		(width 0.2032)
		(layer "In2.Cu")
		(net "FPGA_MAC_PPS_OUT-")
	)
	(segment
		(start 129.488595 84.3286)
		(end 174.186495 84.3286)
		(width 0.2032)
		(layer "In2.Cu")
		(net "FPGA_MAC_PPS_OUT-")
	)
	(segment
		(start 175.982545 85.07255)
		(end 180.944645 90.03465)
		(width 0.2032)
		(layer "In2.Cu")
		(net "FPGA_MAC_PPS_OUT-")
	)
	(segment
		(start 125.188595 102.3786)
		(end 125.188595 88.6286)
		(width 0.2032)
		(layer "In2.Cu")
		(net "FPGA_MAC_PPS_OUT-")
	)
	(arc
		(start 182.740695 90.7786)
		(mid 181.768679 90.585254)
		(end 180.944644 90.034651)
		(width 0.2032)
		(layer "In2.Cu")
		(net "FPGA_MAC_PPS_OUT-")
	)
	(arc
		(start 174.186495 84.3286)
		(mid 175.158511 84.521946)
		(end 175.982546 85.072549)
		(width 0.2032)
		(layer "In2.Cu")
		(net "FPGA_MAC_PPS_OUT-")
	)
	(segment
		(start 191.388595 89.0786)
		(end 191.388595 88.0786)
		(width 0.2032)
		(layer "F.Cu")
		(net "FPGA_MAC_PPS_IN1-")
	)
	(segment
		(start 127.688225 102.22324)
		(end 127.738595 102.27361)
		(width 0.2032)
		(layer "F.Cu")
		(net "FPGA_MAC_PPS_IN1-")
	)
	(segment
		(start 191.388595 89.0786)
		(end 191.388595 89.0786)
		(width 0.2032)
		(layer "F.Cu")
		(net "FPGA_MAC_PPS_IN1-")
	)
	(segment
		(start 191.388595 88.0786)
		(end 194.488595 88.0786)
		(width 0.2032)
		(layer "F.Cu")
		(net "FPGA_MAC_PPS_IN1-")
	)
	(segment
		(start 127.738595 102.3286)
		(end 127.738595 102.27361)
		(width 0.2032)
		(layer "F.Cu")
		(net "FPGA_MAC_PPS_IN1-")
	)
	(segment
		(start 127.688225 102.22324)
		(end 127.688225 100.66825)
		(width 0.2032)
		(layer "F.Cu")
		(net "FPGA_MAC_PPS_IN1-")
	)
	(via
		(at 191.388595 89.0786)
		(size 0.4064)
		(drill 0.2032)
		(layers "F.Cu" "B.Cu")
		(tenting
			(front yes)
			(back yes)
		)
		(net "FPGA_MAC_PPS_IN1-")
	)
	(via
		(at 127.738595 102.3286)
		(size 0.4064)
		(drill 0.2032)
		(layers "F.Cu" "B.Cu")
		(tenting
			(front yes)
			(back yes)
		)
		(net "FPGA_MAC_PPS_IN1-")
	)
	(segment
		(start 159.195705 85.8286)
		(end 173.686495 85.8286)
		(width 0.2032)
		(layer "In2.Cu")
		(net "FPGA_MAC_PPS_IN1-")
	)
	(segment
		(start 129.790705 103.3286)
		(end 149.936495 103.3286)
		(width 0.2032)
		(layer "In2.Cu")
		(net "FPGA_MAC_PPS_IN1-")
	)
	(segment
		(start 151.732545 102.58465)
		(end 155.244645 99.07255)
		(width 0.2032)
		(layer "In2.Cu")
		(net "FPGA_MAC_PPS_IN1-")
	)
	(segment
		(start 155.988595 97.2765)
		(end 155.988595 89.3807)
		(width 0.2032)
		(layer "In2.Cu")
		(net "FPGA_MAC_PPS_IN1-")
	)
	(segment
		(start 127.738595 102.3286)
		(end 127.994645 102.58465)
		(width 0.2032)
		(layer "In2.Cu")
		(net "FPGA_MAC_PPS_IN1-")
	)
	(segment
		(start 192.412615 89.50262)
		(end 192.412865 89.50286)
		(width 0.2032)
		(layer "In2.Cu")
		(net "FPGA_MAC_PPS_IN1-")
	)
	(segment
		(start 192.988595 91.37149)
		(end 192.988595 90.5786)
		(width 0.2032)
		(layer "In2.Cu")
		(net "FPGA_MAC_PPS_IN1-")
	)
	(segment
		(start 192.412865 89.50286)
		(end 192.635045 89.72504)
		(width 0.2032)
		(layer "In2.Cu")
		(net "FPGA_MAC_PPS_IN1-")
	)
	(segment
		(start 182.540695 92.5786)
		(end 192.488595 92.5786)
		(width 0.2032)
		(layer "In2.Cu")
		(net "FPGA_MAC_PPS_IN1-")
	)
	(segment
		(start 175.482545 86.57255)
		(end 180.744645 91.83465)
		(width 0.2032)
		(layer "In2.Cu")
		(net "FPGA_MAC_PPS_IN1-")
	)
	(segment
		(start 156.732545 87.58465)
		(end 157.988595 86.3286)
		(width 0.2032)
		(layer "In2.Cu")
		(net "FPGA_MAC_PPS_IN1-")
	)
	(arc
		(start 155.988595 97.2765)
		(mid 155.795249 98.248516)
		(end 155.244646 99.072551)
		(width 0.2032)
		(layer "In2.Cu")
		(net "FPGA_MAC_PPS_IN1-")
	)
	(arc
		(start 192.635041 89.725044)
		(mid 192.89671 90.116659)
		(end 192.988595 90.5786)
		(width 0.2032)
		(layer "In2.Cu")
		(net "FPGA_MAC_PPS_IN1-")
	)
	(arc
		(start 129.790705 103.3286)
		(mid 128.818689 103.135254)
		(end 127.994654 102.584651)
		(width 0.2032)
		(layer "In2.Cu")
		(net "FPGA_MAC_PPS_IN1-")
	)
	(arc
		(start 151.732546 102.584651)
		(mid 150.908511 103.135254)
		(end 149.936495 103.3286)
		(width 0.2032)
		(layer "In2.Cu")
		(net "FPGA_MAC_PPS_IN1-")
	)
	(arc
		(start 192.988595 91.37149)
		(mid 192.85865 92.024769)
		(end 192.488597 92.578592)
		(width 0.2032)
		(layer "In2.Cu")
		(net "FPGA_MAC_PPS_IN1-")
	)
	(arc
		(start 157.988596 86.328601)
		(mid 158.542422 85.958546)
		(end 159.195705 85.8286)
		(width 0.2032)
		(layer "In2.Cu")
		(net "FPGA_MAC_PPS_IN1-")
	)
	(arc
		(start 191.388595 89.0786)
		(mid 191.94276 89.188795)
		(end 192.41261 89.502614)
		(width 0.2032)
		(layer "In2.Cu")
		(net "FPGA_MAC_PPS_IN1-")
	)
	(arc
		(start 182.540695 92.5786)
		(mid 181.568679 92.385254)
		(end 180.744644 91.834651)
		(width 0.2032)
		(layer "In2.Cu")
		(net "FPGA_MAC_PPS_IN1-")
	)
	(arc
		(start 155.988595 89.3807)
		(mid 156.181941 88.408684)
		(end 156.732544 87.584649)
		(width 0.2032)
		(layer "In2.Cu")
		(net "FPGA_MAC_PPS_IN1-")
	)
	(arc
		(start 173.686495 85.8286)
		(mid 174.658511 86.021946)
		(end 175.482546 86.572549)
		(width 0.2032)
		(layer "In2.Cu")
		(net "FPGA_MAC_PPS_IN1-")
	)
	(segment
		(start 191.388595 91.0786)
		(end 191.388595 90.0786)
		(width 0.2032)
		(layer "F.Cu")
		(net "FPGA_MAC_PPS_IN0-")
	)
	(segment
		(start 126.175975 100.68063)
		(end 126.188355 100.66825)
		(width 0.2032)
		(layer "F.Cu")
		(net "FPGA_MAC_PPS_IN0-")
	)
	(segment
		(start 192.388595 90.0786)
		(end 193.118595 89.3486)
		(width 0.2032)
		(layer "F.Cu")
		(net "FPGA_MAC_PPS_IN0-")
	)
	(segment
		(start 126.163595 102.3786)
		(end 126.175975 102.36622)
		(width 0.2032)
		(layer "F.Cu")
		(net "FPGA_MAC_PPS_IN0-")
	)
	(segment
		(start 193.118595 89.3486)
		(end 194.488595 89.3486)
		(width 0.2032)
		(layer "F.Cu")
		(net "FPGA_MAC_PPS_IN0-")
	)
	(segment
		(start 126.175975 102.36622)
		(end 126.175975 100.68063)
		(width 0.2032)
		(layer "F.Cu")
		(net "FPGA_MAC_PPS_IN0-")
	)
	(segment
		(start 191.388595 91.0786)
		(end 191.388595 91.0786)
		(width 0.2032)
		(layer "F.Cu")
		(net "FPGA_MAC_PPS_IN0-")
	)
	(segment
		(start 191.388595 90.0786)
		(end 192.388595 90.0786)
		(width 0.2032)
		(layer "F.Cu")
		(net "FPGA_MAC_PPS_IN0-")
	)
	(via
		(at 126.163595 102.3786)
		(size 0.4064)
		(drill 0.2032)
		(layers "F.Cu" "B.Cu")
		(tenting
			(front yes)
			(back yes)
		)
		(net "FPGA_MAC_PPS_IN0-")
	)
	(via
		(at 191.388595 91.0786)
		(size 0.4064)
		(drill 0.2032)
		(layers "F.Cu" "B.Cu")
		(tenting
			(front yes)
			(back yes)
		)
		(net "FPGA_MAC_PPS_IN0-")
	)
	(segment
		(start 182.040695 91.3286)
		(end 190.785045 91.3286)
		(width 0.2032)
		(layer "In2.Cu")
		(net "FPGA_MAC_PPS_IN0-")
	)
	(segment
		(start 126.907545 87.90965)
		(end 128.744645 86.07255)
		(width 0.2032)
		(layer "In2.Cu")
		(net "FPGA_MAC_PPS_IN0-")
	)
	(segment
		(start 126.163595 102.3786)
		(end 126.163595 89.7057)
		(width 0.2032)
		(layer "In2.Cu")
		(net "FPGA_MAC_PPS_IN0-")
	)
	(segment
		(start 175.732545 86.07255)
		(end 180.244645 90.58465)
		(width 0.2032)
		(layer "In2.Cu")
		(net "FPGA_MAC_PPS_IN0-")
	)
	(segment
		(start 130.540695 85.3286)
		(end 173.936495 85.3286)
		(width 0.2032)
		(layer "In2.Cu")
		(net "FPGA_MAC_PPS_IN0-")
	)
	(arc
		(start 191.388596 91.078601)
		(mid 191.111684 91.263627)
		(end 190.785045 91.3286)
		(width 0.2032)
		(layer "In2.Cu")
		(net "FPGA_MAC_PPS_IN0-")
	)
	(arc
		(start 126.163595 89.7057)
		(mid 126.356941 88.733684)
		(end 126.907544 87.909649)
		(width 0.2032)
		(layer "In2.Cu")
		(net "FPGA_MAC_PPS_IN0-")
	)
	(arc
		(start 173.936495 85.3286)
		(mid 174.908511 85.521946)
		(end 175.732546 86.072549)
		(width 0.2032)
		(layer "In2.Cu")
		(net "FPGA_MAC_PPS_IN0-")
	)
	(arc
		(start 128.744644 86.072549)
		(mid 129.568679 85.521946)
		(end 130.540695 85.3286)
		(width 0.2032)
		(layer "In2.Cu")
		(net "FPGA_MAC_PPS_IN0-")
	)
	(arc
		(start 182.040695 91.3286)
		(mid 181.068679 91.135254)
		(end 180.244644 90.584651)
		(width 0.2032)
		(layer "In2.Cu")
		(net "FPGA_MAC_PPS_IN0-")
	)
	(segment
		(start 121.188365 102.00418)
		(end 121.507795 102.32361)
		(width 0.2032)
		(layer "F.Cu")
		(net "ANT4")
	)
	(segment
		(start 87.538605 136.8286)
		(end 88.338595 136.8286)
		(width 0.2032)
		(layer "F.Cu")
		(net "ANT4")
	)
	(segment
		(start 88.338595 136.8286)
		(end 88.863595 137.3536)
		(width 0.2032)
		(layer "F.Cu")
		(net "ANT4")
	)
	(segment
		(start 121.188365 102.00418)
		(end 121.188365 100.66825)
		(width 0.2032)
		(layer "F.Cu")
		(net "ANT4")
	)
	(segment
		(start 121.507795 102.3786)
		(end 121.507795 102.32361)
		(width 0.2032)
		(layer "F.Cu")
		(net "ANT4")
	)
	(segment
		(start 87.388605 136.9786)
		(end 87.538605 136.8286)
		(width 0.2032)
		(layer "F.Cu")
		(net "ANT4")
	)
	(via
		(at 88.863595 137.3536)
		(size 0.4064)
		(drill 0.2032)
		(layers "F.Cu" "B.Cu")
		(tenting
			(front yes)
			(back yes)
		)
		(net "ANT4")
	)
	(via
		(at 121.507795 102.3786)
		(size 0.4064)
		(drill 0.2032)
		(layers "F.Cu" "B.Cu")
		(tenting
			(front yes)
			(back yes)
		)
		(net "ANT4")
	)
	(segment
		(start 97.207545 136.60965)
		(end 120.763845 113.05335)
		(width 0.2032)
		(layer "In3.Cu")
		(net "ANT4")
	)
	(segment
		(start 88.863595 137.3536)
		(end 95.411495 137.3536)
		(width 0.2032)
		(layer "In3.Cu")
		(net "ANT4")
	)
	(segment
		(start 121.507795 111.2573)
		(end 121.507795 102.3786)
		(width 0.2032)
		(layer "In3.Cu")
		(net "ANT4")
	)
	(arc
		(start 121.507795 111.2573)
		(mid 121.314449 112.229316)
		(end 120.763846 113.053351)
		(width 0.2032)
		(layer "In3.Cu")
		(net "ANT4")
	)
	(arc
		(start 97.207546 136.609651)
		(mid 96.383511 137.160254)
		(end 95.411495 137.3536)
		(width 0.2032)
		(layer "In3.Cu")
		(net "ANT4")
	)
	(segment
		(start 120.850975 102.4402)
		(end 120.850975 101.99125)
		(width 0.2032)
		(layer "F.Cu")
		(net "ANT3")
	)
	(segment
		(start 120.850975 102.4402)
		(end 120.889855 102.47908)
		(width 0.2032)
		(layer "F.Cu")
		(net "ANT3")
	)
	(segment
		(start 87.488595 123.8286)
		(end 88.458605 123.8286)
		(width 0.2032)
		(layer "F.Cu")
		(net "ANT3")
	)
	(segment
		(start 88.458605 123.8286)
		(end 88.758605 124.1286)
		(width 0.2032)
		(layer "F.Cu")
		(net "ANT3")
	)
	(segment
		(start 120.688245 100.66825)
		(end 120.688595 100.66861)
		(width 0.2032)
		(layer "F.Cu")
		(net "ANT3")
	)
	(segment
		(start 120.688595 101.82887)
		(end 120.688595 100.66861)
		(width 0.2032)
		(layer "F.Cu")
		(net "ANT3")
	)
	(segment
		(start 120.688595 101.82887)
		(end 120.850975 101.99125)
		(width 0.2032)
		(layer "F.Cu")
		(net "ANT3")
	)
	(segment
		(start 88.758605 124.1286)
		(end 88.813595 124.1286)
		(width 0.2032)
		(layer "F.Cu")
		(net "ANT3")
	)
	(segment
		(start 87.438595 123.7786)
		(end 87.488595 123.8286)
		(width 0.2032)
		(layer "F.Cu")
		(net "ANT3")
	)
	(via
		(at 120.889855 102.47908)
		(size 0.4064)
		(drill 0.2032)
		(layers "F.Cu" "B.Cu")
		(tenting
			(front yes)
			(back yes)
		)
		(net "ANT3")
	)
	(via
		(at 88.813595 124.1286)
		(size 0.4064)
		(drill 0.2032)
		(layers "F.Cu" "B.Cu")
		(tenting
			(front yes)
			(back yes)
		)
		(net "ANT3")
	)
	(segment
		(start 109.182545 123.38465)
		(end 120.154245 112.41295)
		(width 0.2032)
		(layer "In3.Cu")
		(net "ANT3")
	)
	(segment
		(start 88.813595 124.1286)
		(end 107.386495 124.1286)
		(width 0.2032)
		(layer "In3.Cu")
		(net "ANT3")
	)
	(segment
		(start 120.898195 110.61689)
		(end 120.898195 102.48742)
		(width 0.2032)
		(layer "In3.Cu")
		(net "ANT3")
	)
	(segment
		(start 120.889855 102.47908)
		(end 120.898195 102.48742)
		(width 0.2032)
		(layer "In3.Cu")
		(net "ANT3")
	)
	(arc
		(start 120.898195 110.61689)
		(mid 120.704849 111.588906)
		(end 120.154246 112.412941)
		(width 0.2032)
		(layer "In3.Cu")
		(net "ANT3")
	)
	(arc
		(start 109.182546 123.384651)
		(mid 108.358511 123.935254)
		(end 107.386495 124.1286)
		(width 0.2032)
		(layer "In3.Cu")
		(net "ANT3")
	)
	(segment
		(start 120.188365 102.22338)
		(end 120.188365 100.66825)
		(width 0.2032)
		(layer "F.Cu")
		(net "ANT2")
	)
	(segment
		(start 87.713595 110.6036)
		(end 88.888595 110.6036)
		(width 0.2032)
		(layer "F.Cu")
		(net "ANT2")
	)
	(segment
		(start 120.288595 102.3786)
		(end 120.288595 102.32361)
		(width 0.2032)
		(layer "F.Cu")
		(net "ANT2")
	)
	(segment
		(start 87.688595 110.5786)
		(end 87.713595 110.6036)
		(width 0.2032)
		(layer "F.Cu")
		(net "ANT2")
	)
	(segment
		(start 120.188365 102.22338)
		(end 120.288595 102.32361)
		(width 0.2032)
		(layer "F.Cu")
		(net "ANT2")
	)
	(via
		(at 88.888595 110.6036)
		(size 0.4064)
		(drill 0.2032)
		(layers "F.Cu" "B.Cu")
		(tenting
			(front yes)
			(back yes)
		)
		(net "ANT2")
	)
	(via
		(at 120.288595 102.3786)
		(size 0.4064)
		(drill 0.2032)
		(layers "F.Cu" "B.Cu")
		(tenting
			(front yes)
			(back yes)
		)
		(net "ANT2")
	)
	(segment
		(start 95.565695 104.9786)
		(end 116.636495 104.9786)
		(width 0.2032)
		(layer "In3.Cu")
		(net "ANT2")
	)
	(segment
		(start 118.432545 104.23465)
		(end 120.288595 102.3786)
		(width 0.2032)
		(layer "In3.Cu")
		(net "ANT2")
	)
	(segment
		(start 88.888595 110.6036)
		(end 93.769645 105.72255)
		(width 0.2032)
		(layer "In3.Cu")
		(net "ANT2")
	)
	(arc
		(start 118.432546 104.234651)
		(mid 117.608511 104.785254)
		(end 116.636495 104.9786)
		(width 0.2032)
		(layer "In3.Cu")
		(net "ANT2")
	)
	(arc
		(start 93.769644 105.722549)
		(mid 94.593679 105.171946)
		(end 95.565695 104.9786)
		(width 0.2032)
		(layer "In3.Cu")
		(net "ANT2")
	)
	(segment
		(start 119.604385 102.34439)
		(end 119.663845 101.75519)
		(width 0.2032)
		(layer "F.Cu")
		(net "ANT1")
	)
	(segment
		(start 119.664875 101.73479)
		(end 119.664875 100.69162)
		(width 0.2032)
		(layer "F.Cu")
		(net "ANT1")
	)
	(segment
		(start 119.664875 100.69162)
		(end 119.688245 100.66825)
		(width 0.2032)
		(layer "F.Cu")
		(net "ANT1")
	)
	(segment
		(start 87.688595 97.0786)
		(end 87.738595 97.0286)
		(width 0.2032)
		(layer "F.Cu")
		(net "ANT1")
	)
	(segment
		(start 87.738595 97.0286)
		(end 88.963595 97.0286)
		(width 0.2032)
		(layer "F.Cu")
		(net "ANT1")
	)
	(via
		(at 119.604385 102.34439)
		(size 0.4064)
		(drill 0.2032)
		(layers "F.Cu" "B.Cu")
		(tenting
			(front yes)
			(back yes)
		)
		(net "ANT1")
	)
	(via
		(at 88.963595 97.0286)
		(size 0.4064)
		(drill 0.2032)
		(layers "F.Cu" "B.Cu")
		(tenting
			(front yes)
			(back yes)
		)
		(net "ANT1")
	)
	(arc
		(start 119.664875 101.73479)
		(mid 119.664618 101.745005)
		(end 119.663848 101.755194)
		(width 0.2032)
		(layer "F.Cu")
		(net "ANT1")
	)
	(segment
		(start 119.218945 102.79732)
		(end 119.604385 102.34439)
		(width 0.2032)
		(layer "In3.Cu")
		(net "ANT1")
	)
	(segment
		(start 118.029285 103.98791)
		(end 119.207535 102.80966)
		(width 0.2032)
		(layer "In3.Cu")
		(net "ANT1")
	)
	(segment
		(start 88.963595 97.0286)
		(end 95.744645 103.80965)
		(width 0.2032)
		(layer "In3.Cu")
		(net "ANT1")
	)
	(segment
		(start 97.540695 104.5536)
		(end 116.663595 104.5536)
		(width 0.2032)
		(layer "In3.Cu")
		(net "ANT1")
	)
	(arc
		(start 97.540695 104.5536)
		(mid 96.568679 104.360254)
		(end 95.744644 103.809651)
		(width 0.2032)
		(layer "In3.Cu")
		(net "ANT1")
	)
	(arc
		(start 118.02928 103.987915)
		(mid 117.402698 104.406583)
		(end 116.663595 104.5536)
		(width 0.2032)
		(layer "In3.Cu")
		(net "ANT1")
	)
	(arc
		(start 119.218952 102.797319)
		(mid 119.213374 102.803605)
		(end 119.207541 102.809655)
		(width 0.2032)
		(layer "In3.Cu")
		(net "ANT1")
	)
	(segment
		(start 107.866095 143.4761)
		(end 107.888595 143.4986)
		(width 0.508)
		(layer "F.Cu")
		(net "NetD3_1")
	)
	(segment
		(start 107.642595 143.3926)
		(end 107.726095 143.4761)
		(width 0.508)
		(layer "F.Cu")
		(net "NetD3_1")
	)
	(segment
		(start 107.642595 143.3926)
		(end 107.939395 143.3926)
		(width 0.508)
		(layer "F.Cu")
		(net "NetD3_1")
	)
	(segment
		(start 105.688595 143.4536)
		(end 105.711095 143.4761)
		(width 0.508)
		(layer "F.Cu")
		(net "NetD3_1")
	)
	(segment
		(start 107.726095 143.4761)
		(end 107.866095 143.4761)
		(width 0.508)
		(layer "F.Cu")
		(net "NetD3_1")
	)
	(segment
		(start 105.711095 143.4761)
		(end 107.726095 143.4761)
		(width 0.508)
		(layer "F.Cu")
		(net "NetD3_1")
	)
	(segment
		(start 117.163595 102.4036)
		(end 117.175985 102.39121)
		(width 0.2032)
		(layer "F.Cu")
		(net "MAC_RF_OUT")
	)
	(segment
		(start 117.688245 102.22327)
		(end 117.688245 100.66825)
		(width 0.2032)
		(layer "F.Cu")
		(net "MAC_RF_OUT")
	)
	(segment
		(start 117.813595 102.4036)
		(end 117.813595 102.34861)
		(width 0.2032)
		(layer "F.Cu")
		(net "MAC_RF_OUT")
	)
	(segment
		(start 117.175985 102.39121)
		(end 117.175985 100.68064)
		(width 0.2032)
		(layer "F.Cu")
		(net "MAC_RF_OUT")
	)
	(segment
		(start 117.175985 100.68064)
		(end 117.188375 100.66825)
		(width 0.2032)
		(layer "F.Cu")
		(net "MAC_RF_OUT")
	)
	(segment
		(start 117.688245 102.22327)
		(end 117.813595 102.34861)
		(width 0.2032)
		(layer "F.Cu")
		(net "MAC_RF_OUT")
	)
	(via
		(at 117.163595 102.4036)
		(size 0.4064)
		(drill 0.2032)
		(layers "F.Cu" "B.Cu")
		(tenting
			(front yes)
			(back yes)
		)
		(net "MAC_RF_OUT")
	)
	(via
		(at 117.813595 102.4036)
		(size 0.4064)
		(drill 0.2032)
		(layers "F.Cu" "B.Cu")
		(tenting
			(front yes)
			(back yes)
		)
		(net "MAC_RF_OUT")
	)
	(segment
		(start 117.163595 102.4036)
		(end 117.813595 102.4036)
		(width 0.2032)
		(layer "In3.Cu")
		(net "MAC_RF_OUT")
	)
	(segment
		(start 200.406075 97.7636)
		(end 200.406075 97.6286)
		(width 0.2032)
		(layer "In3.Cu")
		(net "MAC_RF_OUT")
	)
	(segment
		(start 119.913595 100.3036)
		(end 197.866075 100.3036)
		(width 0.2032)
		(layer "In3.Cu")
		(net "MAC_RF_OUT")
	)
	(arc
		(start 200.406075 97.7636)
		(mid 199.662126 99.559651)
		(end 197.866075 100.3036)
		(width 0.2032)
		(layer "In3.Cu")
		(net "MAC_RF_OUT")
	)
	(arc
		(start 117.813595 102.4036)
		(mid 118.428671 100.918676)
		(end 119.913595 100.3036)
		(width 0.2032)
		(layer "In3.Cu")
		(net "MAC_RF_OUT")
	)
	(segment
		(start 153.223015 118.07102)
		(end 153.238595 118.0866)
		(width 0.2032)
		(layer "F.Cu")
		(net "EXT_EEPROM_WP")
	)
	(segment
		(start 134.888595 92.0786)
		(end 135.988595 92.0786)
		(width 0.2032)
		(layer "F.Cu")
		(net "EXT_EEPROM_WP")
	)
	(segment
		(start 134.313595 92.0786)
		(end 134.338595 92.1036)
		(width 0.2032)
		(layer "F.Cu")
		(net "EXT_EEPROM_WP")
	)
	(segment
		(start 134.313595 92.0786)
		(end 134.888595 92.0786)
		(width 0.2032)
		(layer "F.Cu")
		(net "EXT_EEPROM_WP")
	)
	(segment
		(start 135.988595 92.0786)
		(end 139.238595 95.3286)
		(width 0.2032)
		(layer "F.Cu")
		(net "EXT_EEPROM_WP")
	)
	(segment
		(start 139.238595 114.5786)
		(end 142.738595 118.0786)
		(width 0.2032)
		(layer "F.Cu")
		(net "EXT_EEPROM_WP")
	)
	(segment
		(start 151.225895 118.06344)
		(end 151.233475 118.07102)
		(width 0.2032)
		(layer "F.Cu")
		(net "EXT_EEPROM_WP")
	)
	(segment
		(start 151.233475 118.07102)
		(end 153.223015 118.07102)
		(width 0.2032)
		(layer "F.Cu")
		(net "EXT_EEPROM_WP")
	)
	(segment
		(start 134.888595 92.0786)
		(end 135.188595 91.7786)
		(width 0.2032)
		(layer "F.Cu")
		(net "EXT_EEPROM_WP")
	)
	(segment
		(start 139.238595 114.5786)
		(end 139.238595 95.3286)
		(width 0.2032)
		(layer "F.Cu")
		(net "EXT_EEPROM_WP")
	)
	(segment
		(start 135.188595 91.7786)
		(end 135.188595 90.14481)
		(width 0.2032)
		(layer "F.Cu")
		(net "EXT_EEPROM_WP")
	)
	(via
		(at 153.238595 118.0866)
		(size 0.4064)
		(drill 0.2032)
		(layers "F.Cu" "B.Cu")
		(tenting
			(front yes)
			(back yes)
		)
		(net "EXT_EEPROM_WP")
	)
	(via
		(at 142.766385 118.17292)
		(size 0.4064)
		(drill 0.2032)
		(layers "F.Cu" "B.Cu")
		(tenting
			(front yes)
			(back yes)
		)
		(net "EXT_EEPROM_WP")
	)
	(segment
		(start 153.097295 118.17292)
		(end 153.183615 118.0866)
		(width 0.2032)
		(layer "B.Cu")
		(net "EXT_EEPROM_WP")
	)
	(segment
		(start 153.183615 118.0866)
		(end 153.238595 118.0866)
		(width 0.2032)
		(layer "B.Cu")
		(net "EXT_EEPROM_WP")
	)
	(segment
		(start 142.766385 118.17292)
		(end 153.097295 118.17292)
		(width 0.2032)
		(layer "B.Cu")
		(net "EXT_EEPROM_WP")
	)
	(segment
		(start 134.188475 96.61834)
		(end 134.188475 94.40373)
		(width 0.2032)
		(layer "F.Cu")
		(net "GPS1_TX")
	)
	(segment
		(start 134.188345 96.61847)
		(end 134.188475 96.61834)
		(width 0.2032)
		(layer "F.Cu")
		(net "GPS1_TX")
	)
	(segment
		(start 134.188475 94.40373)
		(end 134.188595 94.4036)
		(width 0.2032)
		(layer "F.Cu")
		(net "GPS1_TX")
	)
	(segment
		(start 118.988595 72.5786)
		(end 121.043595 72.5786)
		(width 0.2032)
		(layer "F.Cu")
		(net "GPS1_TX")
	)
	(via
		(at 118.988595 72.5786)
		(size 0.4064)
		(drill 0.2032)
		(layers "F.Cu" "B.Cu")
		(tenting
			(front yes)
			(back yes)
		)
		(net "GPS1_TX")
	)
	(via
		(at 134.188595 94.4036)
		(size 0.4064)
		(drill 0.2032)
		(layers "F.Cu" "B.Cu")
		(tenting
			(front yes)
			(back yes)
		)
		(net "GPS1_TX")
	)
	(segment
		(start 118.988595 72.5786)
		(end 123.234545 72.5786)
		(width 0.2032)
		(layer "B.Cu")
		(net "GPS1_TX")
	)
	(segment
		(start 123.234545 72.5786)
		(end 134.188595 83.53265)
		(width 0.2032)
		(layer "B.Cu")
		(net "GPS1_TX")
	)
	(segment
		(start 134.188595 94.4036)
		(end 134.188595 83.53265)
		(width 0.2032)
		(layer "B.Cu")
		(net "GPS1_TX")
	)
	(segment
		(start 153.183615 114.8286)
		(end 153.238595 114.8286)
		(width 0.2032)
		(layer "F.Cu")
		(net "GPS1_TP1")
	)
	(segment
		(start 125.488595 70.5786)
		(end 127.488595 70.5786)
		(width 0.2032)
		(layer "F.Cu")
		(net "GPS1_TP1")
	)
	(segment
		(start 151.225895 115.06345)
		(end 152.948765 115.06345)
		(width 0.2032)
		(layer "F.Cu")
		(net "GPS1_TP1")
	)
	(segment
		(start 152.948765 115.06345)
		(end 153.183615 114.8286)
		(width 0.2032)
		(layer "F.Cu")
		(net "GPS1_TP1")
	)
	(via
		(at 127.488595 70.5786)
		(size 0.4064)
		(drill 0.2032)
		(layers "F.Cu" "B.Cu")
		(tenting
			(front yes)
			(back yes)
		)
		(net "GPS1_TP1")
	)
	(via
		(at 153.238595 114.8286)
		(size 0.4064)
		(drill 0.2032)
		(layers "F.Cu" "B.Cu")
		(tenting
			(front yes)
			(back yes)
		)
		(net "GPS1_TP1")
	)
	(segment
		(start 155.658395 112.4088)
		(end 155.658395 79.4984)
		(width 0.2032)
		(layer "B.Cu")
		(net "GPS1_TP1")
	)
	(segment
		(start 127.488595 70.5786)
		(end 146.738595 70.5786)
		(width 0.2032)
		(layer "B.Cu")
		(net "GPS1_TP1")
	)
	(segment
		(start 153.238595 114.8286)
		(end 155.658395 112.4088)
		(width 0.2032)
		(layer "B.Cu")
		(net "GPS1_TP1")
	)
	(segment
		(start 146.738595 70.5786)
		(end 155.658395 79.4984)
		(width 0.2032)
		(layer "B.Cu")
		(net "GPS1_TP1")
	)
	(segment
		(start 134.200965 102.34097)
		(end 134.213595 102.3536)
		(width 0.2032)
		(layer "F.Cu")
		(net "GPS1_RX")
	)
	(segment
		(start 134.188345 100.66825)
		(end 134.200965 100.68088)
		(width 0.2032)
		(layer "F.Cu")
		(net "GPS1_RX")
	)
	(segment
		(start 118.988595 70.5786)
		(end 121.043595 70.5786)
		(width 0.2032)
		(layer "F.Cu")
		(net "GPS1_RX")
	)
	(segment
		(start 134.200965 102.34097)
		(end 134.200965 100.68088)
		(width 0.2032)
		(layer "F.Cu")
		(net "GPS1_RX")
	)
	(via
		(at 134.213595 102.3536)
		(size 0.4064)
		(drill 0.2032)
		(layers "F.Cu" "B.Cu")
		(tenting
			(front yes)
			(back yes)
		)
		(net "GPS1_RX")
	)
	(via
		(at 118.988595 70.5786)
		(size 0.4064)
		(drill 0.2032)
		(layers "F.Cu" "B.Cu")
		(tenting
			(front yes)
			(back yes)
		)
		(net "GPS1_RX")
	)
	(segment
		(start 135.488595 101.0786)
		(end 135.488595 84.3286)
		(width 0.2032)
		(layer "B.Cu")
		(net "GPS1_RX")
	)
	(segment
		(start 118.988595 70.5786)
		(end 121.738595 70.5786)
		(width 0.2032)
		(layer "B.Cu")
		(net "GPS1_RX")
	)
	(segment
		(start 134.213595 102.3536)
		(end 135.488595 101.0786)
		(width 0.2032)
		(layer "B.Cu")
		(net "GPS1_RX")
	)
	(segment
		(start 121.738595 70.5786)
		(end 135.488595 84.3286)
		(width 0.2032)
		(layer "B.Cu")
		(net "GPS1_RX")
	)
	(segment
		(start 118.158595 157.7576)
		(end 118.174595 157.7416)
		(width 0.2032)
		(layer "B.Cu")
		(net "NetC44_1")
	)
	(segment
		(start 118.174595 156.99168)
		(end 118.174595 152.2186)
		(width 0.127)
		(layer "B.Cu")
		(net "NetC44_1")
	)
	(arc
		(start 118.174595 156.99168)
		(mid 118.165238 157.038719)
		(end 118.138593 157.078598)
		(width 0.127)
		(layer "B.Cu")
		(net "NetC44_1")
	)
	(arc
		(start 118.158585 152.25723)
		(mid 118.162744 152.236321)
		(end 118.174588 152.218594)
		(width 0.127)
		(layer "B.Cu")
		(net "NetC44_1")
	)
	(segment
		(start 119.190595 156.95305)
		(end 119.190595 152.2186)
		(width 0.127)
		(layer "B.Cu")
		(net "NetC45_1")
	)
	(arc
		(start 119.190595 156.95305)
		(mid 119.17708 157.020995)
		(end 119.138592 157.078597)
		(width 0.127)
		(layer "B.Cu")
		(net "NetC45_1")
	)
	(segment
		(start 121.197195 156.93711)
		(end 121.197195 152.2186)
		(width 0.127)
		(layer "B.Cu")
		(net "NetC46_1")
	)
	(arc
		(start 121.197195 157.66439)
		(mid 121.187182 157.714783)
		(end 121.158666 157.757521)
		(width 0.127)
		(layer "B.Cu")
		(net "NetC46_1")
	)
	(arc
		(start 121.197195 156.93711)
		(mid 121.181963 157.013685)
		(end 121.138587 157.078602)
		(width 0.127)
		(layer "B.Cu")
		(net "NetC46_1")
	)
	(segment
		(start 122.289395 156.71451)
		(end 122.289395 152.2186)
		(width 0.127)
		(layer "B.Cu")
		(net "NetC47_1")
	)
	(arc
		(start 122.289395 156.71451)
		(mid 122.250201 156.911554)
		(end 122.138584 157.078599)
		(width 0.127)
		(layer "B.Cu")
		(net "NetC47_1")
	)
	(segment
		(start 126.175595 156.98923)
		(end 126.175595 152.2186)
		(width 0.127)
		(layer "B.Cu")
		(net "NetC48_1")
	)
	(arc
		(start 126.175595 156.98923)
		(mid 126.165974 157.037597)
		(end 126.138576 157.078601)
		(width 0.127)
		(layer "B.Cu")
		(net "NetC48_1")
	)
	(arc
		(start 126.175595 157.71651)
		(mid 126.171172 157.738744)
		(end 126.158578 157.757593)
		(width 0.127)
		(layer "B.Cu")
		(net "NetC48_1")
	)
	(segment
		(start 130.112595 157.01589)
		(end 130.112595 152.2186)
		(width 0.127)
		(layer "B.Cu")
		(net "NetC50_1")
	)
	(arc
		(start 130.138569 157.078596)
		(mid 130.119346 157.049826)
		(end 130.112595 157.01589)
		(width 0.127)
		(layer "B.Cu")
		(net "NetC50_1")
	)
	(arc
		(start 130.112592 152.218603)
		(mid 130.146617 152.269524)
		(end 130.158564 152.32959)
		(width 0.127)
		(layer "B.Cu")
		(net "NetC50_1")
	)
	(segment
		(start 131.001595 156.74792)
		(end 131.001595 152.2186)
		(width 0.127)
		(layer "B.Cu")
		(net "NetC51_1")
	)
	(arc
		(start 131.158095 157.757133)
		(mid 131.042263 157.583426)
		(end 131.001595 157.37864)
		(width 0.127)
		(layer "B.Cu")
		(net "NetC51_1")
	)
	(arc
		(start 131.138567 157.078598)
		(mid 131.037193 156.926882)
		(end 131.001596 156.74792)
		(width 0.127)
		(layer "B.Cu")
		(net "NetC51_1")
	)
	(segment
		(start 134.176595 156.98678)
		(end 134.176595 152.2186)
		(width 0.127)
		(layer "B.Cu")
		(net "NetC52_1")
	)
	(arc
		(start 134.176595 157.71406)
		(mid 134.171908 157.737622)
		(end 134.158562 157.757597)
		(width 0.127)
		(layer "B.Cu")
		(net "NetC52_1")
	)
	(arc
		(start 134.158565 152.26214)
		(mid 134.163252 152.238578)
		(end 134.176598 152.218603)
		(width 0.127)
		(layer "B.Cu")
		(net "NetC52_1")
	)
	(arc
		(start 134.176605 156.98678)
		(mid 134.16672 157.036475)
		(end 134.13857 157.078605)
		(width 0.127)
		(layer "B.Cu")
		(net "NetC52_1")
	)
	(segment
		(start 135.158555 157.7576)
		(end 135.192595 157.72356)
		(width 0.2032)
		(layer "B.Cu")
		(net "NetC53_1")
	)
	(segment
		(start 135.192595 156.94814)
		(end 135.192595 152.2186)
		(width 0.127)
		(layer "B.Cu")
		(net "NetC53_1")
	)
	(arc
		(start 135.192595 156.94814)
		(mid 135.178552 157.018741)
		(end 135.138559 157.078594)
		(width 0.127)
		(layer "B.Cu")
		(net "NetC53_1")
	)
	(arc
		(start 135.158555 152.30077)
		(mid 135.167401 152.256298)
		(end 135.192592 152.218597)
		(width 0.127)
		(layer "B.Cu")
		(net "NetC53_1")
	)
	(segment
		(start 74.718395 56.6106)
		(end 74.867595 56.4614)
		(width 0.2032)
		(layer "F.Cu")
		(net "NetD11_1")
	)
	(segment
		(start 74.867595 56.4614)
		(end 74.867595 53.9616)
		(width 0.2032)
		(layer "F.Cu")
		(net "NetD11_1")
	)
	(segment
		(start 79.840725 56.6106)
		(end 79.989925 56.4614)
		(width 0.2032)
		(layer "F.Cu")
		(net "NetD12_1")
	)
	(segment
		(start 79.989925 56.4614)
		(end 79.989925 54.0886)
		(width 0.2032)
		(layer "F.Cu")
		(net "NetD12_1")
	)
	(segment
		(start 122.188595 157.02859)
		(end 122.188595 153.6786)
		(width 0.2032)
		(layer "F.Cu")
		(net "NetP2_B17")
	)
	(segment
		(start 122.088595 148.7786)
		(end 122.988595 149.6786)
		(width 0.2032)
		(layer "F.Cu")
		(net "NetP2_B17")
	)
	(segment
		(start 122.188595 153.6786)
		(end 122.988595 152.8786)
		(width 0.2032)
		(layer "F.Cu")
		(net "NetP2_B17")
	)
	(segment
		(start 122.088595 148.7786)
		(end 122.088595 146.0036)
		(width 0.2032)
		(layer "F.Cu")
		(net "NetP2_B17")
	)
	(segment
		(start 122.988595 152.8786)
		(end 122.988595 149.6786)
		(width 0.2032)
		(layer "F.Cu")
		(net "NetP2_B17")
	)
	(segment
		(start 122.138585 157.0786)
		(end 122.188595 157.02859)
		(width 0.2032)
		(layer "F.Cu")
		(net "NetP2_B17")
	)
	(segment
		(start 136.088595 156.53334)
		(end 136.088595 146.0036)
		(width 0.2032)
		(layer "F.Cu")
		(net "NetP2_B31")
	)
	(segment
		(start 136.038555 146.05364)
		(end 136.088595 146.0036)
		(width 0.2032)
		(layer "F.Cu")
		(net "NetP2_B31")
	)
	(segment
		(start 136.088595 156.53334)
		(end 136.138555 156.5833)
		(width 0.2032)
		(layer "F.Cu")
		(net "NetP2_B31")
	)
	(segment
		(start 136.158555 157.2623)
		(end 136.208595 157.21226)
		(width 0.2032)
		(layer "F.Cu")
		(net "NetP2_B31")
	)
	(segment
		(start 216.853595 105.1246)
		(end 216.853595 103.6526)
		(width 0.2032)
		(layer "F.Cu")
		(net "NetR3_1")
	)
	(segment
		(start 215.586595 102.3856)
		(end 216.853595 103.6526)
		(width 0.2032)
		(layer "F.Cu")
		(net "NetR3_1")
	)
	(segment
		(start 214.886595 102.3856)
		(end 215.586595 102.3856)
		(width 0.2032)
		(layer "F.Cu")
		(net "NetR3_1")
	)
	(segment
		(start 230.917595 112.7996)
		(end 231.328595 112.7996)
		(width 0.2032)
		(layer "F.Cu")
		(net "NetR4_2")
	)
	(segment
		(start 232.028595 112.7996)
		(end 233.259595 112.7996)
		(width 0.2032)
		(layer "F.Cu")
		(net "NetR4_2")
	)
	(segment
		(start 231.328595 112.7996)
		(end 232.028595 112.7996)
		(width 0.2032)
		(layer "F.Cu")
		(net "NetR4_2")
	)
	(segment
		(start 233.672595 114.4506)
		(end 233.672595 113.2126)
		(width 0.2032)
		(layer "F.Cu")
		(net "NetR4_2")
	)
	(segment
		(start 230.751595 114.4506)
		(end 230.751595 114.3786)
		(width 0.2032)
		(layer "F.Cu")
		(net "NetR4_2")
	)
	(segment
		(start 231.328595 112.7996)
		(end 232.028595 112.7996)
		(width 0.2032)
		(layer "F.Cu")
		(net "NetR4_2")
	)
	(segment
		(start 233.259595 112.7996)
		(end 233.672595 113.2126)
		(width 0.2032)
		(layer "F.Cu")
		(net "NetR4_2")
	)
	(segment
		(start 230.751595 112.9656)
		(end 230.751595 114.3786)
		(width 0.2032)
		(layer "F.Cu")
		(net "NetR4_2")
	)
	(segment
		(start 230.751595 112.9656)
		(end 230.917595 112.7996)
		(width 0.2032)
		(layer "F.Cu")
		(net "NetR4_2")
	)
	(segment
		(start 215.586595 99.8456)
		(end 217.110595 98.3216)
		(width 0.2032)
		(layer "F.Cu")
		(net "NetR5_1")
	)
	(segment
		(start 214.407195 99.156)
		(end 214.626025 99.37483)
		(width 0.2032)
		(layer "F.Cu")
		(net "NetR5_1")
	)
	(segment
		(start 214.148795 98.7576)
		(end 214.407195 99.016)
		(width 0.2032)
		(layer "F.Cu")
		(net "NetR5_1")
	)
	(segment
		(start 214.886595 99.8456)
		(end 215.586595 99.8456)
		(width 0.2032)
		(layer "F.Cu")
		(net "NetR5_1")
	)
	(segment
		(start 214.809425 99.8456)
		(end 214.886595 99.8456)
		(width 0.2032)
		(layer "F.Cu")
		(net "NetR5_1")
	)
	(segment
		(start 217.110595 98.3216)
		(end 218.830595 98.3216)
		(width 0.2032)
		(layer "F.Cu")
		(net "NetR5_1")
	)
	(segment
		(start 214.626025 99.6622)
		(end 214.809425 99.8456)
		(width 0.2032)
		(layer "F.Cu")
		(net "NetR5_1")
	)
	(segment
		(start 214.008795 98.7576)
		(end 214.148795 98.7576)
		(width 0.2032)
		(layer "F.Cu")
		(net "NetR5_1")
	)
	(segment
		(start 214.407195 99.156)
		(end 214.407195 99.016)
		(width 0.2032)
		(layer "F.Cu")
		(net "NetR5_1")
	)
	(segment
		(start 214.626025 99.6622)
		(end 214.626025 99.37483)
		(width 0.2032)
		(layer "F.Cu")
		(net "NetR5_1")
	)
	(segment
		(start 99.488595 64.3286)
		(end 99.537595 64.2796)
		(width 0.3048)
		(layer "F.Cu")
		(net "NetR18_2")
	)
	(segment
		(start 99.537595 64.2796)
		(end 99.537595 60.2216)
		(width 0.3048)
		(layer "F.Cu")
		(net "NetR18_2")
	)
	(segment
		(start 104.617595 64.1996)
		(end 104.617595 60.2216)
		(width 0.3048)
		(layer "F.Cu")
		(net "NetR20_2")
	)
	(segment
		(start 104.488595 64.3286)
		(end 104.617595 64.1996)
		(width 0.3048)
		(layer "F.Cu")
		(net "NetR20_2")
	)
	(segment
		(start 109.697595 60.2216)
		(end 109.824595 60.3486)
		(width 0.2032)
		(layer "F.Cu")
		(net "NetR21_2")
	)
	(segment
		(start 109.697595 64.2876)
		(end 109.738595 64.3286)
		(width 0.3048)
		(layer "F.Cu")
		(net "NetR21_2")
	)
	(segment
		(start 109.697595 64.2876)
		(end 109.697595 60.2216)
		(width 0.3048)
		(layer "F.Cu")
		(net "NetR21_2")
	)
	(segment
		(start 133.269845 87.99364)
		(end 133.269845 86.60985)
		(width 0.2032)
		(layer "F.Cu")
		(net "SDA")
	)
	(segment
		(start 129.711595 102.30159)
		(end 129.738595 102.3286)
		(width 0.2032)
		(layer "F.Cu")
		(net "SDA")
	)
	(segment
		(start 129.688225 100.66825)
		(end 129.711595 100.69162)
		(width 0.2032)
		(layer "F.Cu")
		(net "SDA")
	)
	(segment
		(start 120.238595 92.5706)
		(end 120.238595 91.3286)
		(width 0.2032)
		(layer "F.Cu")
		(net "SDA")
	)
	(segment
		(start 133.251095 86.5911)
		(end 133.269845 86.60985)
		(width 0.2032)
		(layer "F.Cu")
		(net "SDA")
	)
	(segment
		(start 149.263595 89.1536)
		(end 149.301095 89.1161)
		(width 0.2032)
		(layer "F.Cu")
		(net "SDA")
	)
	(segment
		(start 139.988595 86.0786)
		(end 140.238595 86.3286)
		(width 0.2032)
		(layer "F.Cu")
		(net "SDA")
	)
	(segment
		(start 140.238595 87.8161)
		(end 140.238595 87.8161)
		(width 0.2032)
		(layer "F.Cu")
		(net "SDA")
	)
	(segment
		(start 140.238595 87.8161)
		(end 140.238595 86.3286)
		(width 0.2032)
		(layer "F.Cu")
		(net "SDA")
	)
	(segment
		(start 149.301095 89.1161)
		(end 150.451095 89.1161)
		(width 0.2032)
		(layer "F.Cu")
		(net "SDA")
	)
	(segment
		(start 133.269845 87.99364)
		(end 133.288595 88.01239)
		(width 0.2032)
		(layer "F.Cu")
		(net "SDA")
	)
	(segment
		(start 150.451095 89.1161)
		(end 150.488595 89.0786)
		(width 0.2032)
		(layer "F.Cu")
		(net "SDA")
	)
	(segment
		(start 129.711595 102.30159)
		(end 129.711595 100.69162)
		(width 0.2032)
		(layer "F.Cu")
		(net "SDA")
	)
	(via
		(at 133.251095 86.5911)
		(size 0.4064)
		(drill 0.2032)
		(layers "F.Cu" "B.Cu")
		(tenting
			(front yes)
			(back yes)
		)
		(net "SDA")
	)
	(via
		(at 139.988595 86.0786)
		(size 0.4064)
		(drill 0.2032)
		(layers "F.Cu" "B.Cu")
		(tenting
			(front yes)
			(back yes)
		)
		(net "SDA")
	)
	(via
		(at 186.988595 54.8286)
		(size 0.4064)
		(drill 0.2032)
		(layers "F.Cu" "B.Cu")
		(tenting
			(front yes)
			(back yes)
		)
		(net "SDA")
	)
	(via
		(at 150.488595 89.0786)
		(size 0.4064)
		(drill 0.2032)
		(layers "F.Cu" "B.Cu")
		(tenting
			(front yes)
			(back yes)
		)
		(net "SDA")
	)
	(via
		(at 129.738595 102.3286)
		(size 0.4064)
		(drill 0.2032)
		(layers "F.Cu" "B.Cu")
		(tenting
			(front yes)
			(back yes)
		)
		(net "SDA")
	)
	(via
		(at 120.238595 92.5706)
		(size 0.4064)
		(drill 0.2032)
		(layers "F.Cu" "B.Cu")
		(tenting
			(front yes)
			(back yes)
		)
		(net "SDA")
	)
	(segment
		(start 143.658395 85.2484)
		(end 147.488595 89.0786)
		(width 0.2032)
		(layer "B.Cu")
		(net "SDA")
	)
	(segment
		(start 147.488595 89.0786)
		(end 150.488595 89.0786)
		(width 0.2032)
		(layer "B.Cu")
		(net "SDA")
	)
	(segment
		(start 140.818795 85.2484)
		(end 143.658395 85.2484)
		(width 0.2032)
		(layer "B.Cu")
		(net "SDA")
	)
	(segment
		(start 194.068595 54.8286)
		(end 196.568595 52.3286)
		(width 0.2032)
		(layer "B.Cu")
		(net "SDA")
	)
	(segment
		(start 186.988595 54.8286)
		(end 194.068595 54.8286)
		(width 0.2032)
		(layer "B.Cu")
		(net "SDA")
	)
	(segment
		(start 139.988595 86.0786)
		(end 140.818795 85.2484)
		(width 0.2032)
		(layer "B.Cu")
		(net "SDA")
	)
	(segment
		(start 186.488595 69.3286)
		(end 186.488595 55.3286)
		(width 0.2032)
		(layer "In2.Cu")
		(net "SDA")
	)
	(segment
		(start 130.238595 101.8286)
		(end 130.238595 92.3286)
		(width 0.2032)
		(layer "In2.Cu")
		(net "SDA")
	)
	(segment
		(start 126.738595 83.0786)
		(end 172.738595 83.0786)
		(width 0.2032)
		(layer "In2.Cu")
		(net "SDA")
	)
	(segment
		(start 129.738595 102.3286)
		(end 130.238595 101.8286)
		(width 0.2032)
		(layer "In2.Cu")
		(net "SDA")
	)
	(segment
		(start 172.738595 83.0786)
		(end 186.488595 69.3286)
		(width 0.2032)
		(layer "In2.Cu")
		(net "SDA")
	)
	(segment
		(start 186.488595 55.3286)
		(end 186.988595 54.8286)
		(width 0.2032)
		(layer "In2.Cu")
		(net "SDA")
	)
	(segment
		(start 120.238595 89.5786)
		(end 126.738595 83.0786)
		(width 0.2032)
		(layer "In2.Cu")
		(net "SDA")
	)
	(segment
		(start 133.251095 89.3161)
		(end 133.251095 86.5911)
		(width 0.2032)
		(layer "In2.Cu")
		(net "SDA")
	)
	(segment
		(start 130.238595 92.3286)
		(end 133.251095 89.3161)
		(width 0.2032)
		(layer "In2.Cu")
		(net "SDA")
	)
	(segment
		(start 120.238595 92.5706)
		(end 120.238595 89.5786)
		(width 0.2032)
		(layer "In2.Cu")
		(net "SDA")
	)
	(segment
		(start 120.238595 92.5706)
		(end 120.246595 92.5706)
		(width 0.2032)
		(layer "In3.Cu")
		(net "SDA")
	)
	(segment
		(start 133.763595 86.0786)
		(end 139.988595 86.0786)
		(width 0.2032)
		(layer "In3.Cu")
		(net "SDA")
	)
	(segment
		(start 133.251095 86.5911)
		(end 133.763595 86.0786)
		(width 0.2032)
		(layer "In3.Cu")
		(net "SDA")
	)
	(segment
		(start 126.226095 86.5911)
		(end 133.251095 86.5911)
		(width 0.2032)
		(layer "In3.Cu")
		(net "SDA")
	)
	(segment
		(start 120.246595 92.5706)
		(end 126.226095 86.5911)
		(width 0.2032)
		(layer "In3.Cu")
		(net "SDA")
	)
	(segment
		(start 118.738595 92.5786)
		(end 118.738595 91.3286)
		(width 0.2032)
		(layer "F.Cu")
		(net "SCL")
	)
	(segment
		(start 149.263595 89.8036)
		(end 149.269845 89.80985)
		(width 0.2032)
		(layer "F.Cu")
		(net "SCL")
	)
	(segment
		(start 149.269845 89.80985)
		(end 150.469845 89.80985)
		(width 0.2032)
		(layer "F.Cu")
		(net "SCL")
	)
	(segment
		(start 140.988595 86.13358)
		(end 140.988595 86.0866)
		(width 0.2032)
		(layer "F.Cu")
		(net "SCL")
	)
	(segment
		(start 140.738595 86.38358)
		(end 140.988595 86.13358)
		(width 0.2032)
		(layer "F.Cu")
		(net "SCL")
	)
	(segment
		(start 131.138595 102.3536)
		(end 131.164975 102.32722)
		(width 0.2032)
		(layer "F.Cu")
		(net "SCL")
	)
	(segment
		(start 150.469845 89.80985)
		(end 150.476095 89.8161)
		(width 0.2032)
		(layer "F.Cu")
		(net "SCL")
	)
	(segment
		(start 140.738595 87.8161)
		(end 140.738595 86.38358)
		(width 0.2032)
		(layer "F.Cu")
		(net "SCL")
	)
	(segment
		(start 134.980595 86.63359)
		(end 135.188595 86.84159)
		(width 0.2032)
		(layer "F.Cu")
		(net "SCL")
	)
	(segment
		(start 134.980595 86.63359)
		(end 134.980595 86.5866)
		(width 0.2032)
		(layer "F.Cu")
		(net "SCL")
	)
	(segment
		(start 131.164975 102.32722)
		(end 131.164975 100.69162)
		(width 0.2032)
		(layer "F.Cu")
		(net "SCL")
	)
	(segment
		(start 135.188595 88.01239)
		(end 135.188595 86.84159)
		(width 0.2032)
		(layer "F.Cu")
		(net "SCL")
	)
	(segment
		(start 131.164975 100.69162)
		(end 131.188345 100.66825)
		(width 0.2032)
		(layer "F.Cu")
		(net "SCL")
	)
	(via
		(at 134.980595 86.5866)
		(size 0.4064)
		(drill 0.2032)
		(layers "F.Cu" "B.Cu")
		(tenting
			(front yes)
			(back yes)
		)
		(net "SCL")
	)
	(via
		(at 140.988595 86.0866)
		(size 0.4064)
		(drill 0.2032)
		(layers "F.Cu" "B.Cu")
		(tenting
			(front yes)
			(back yes)
		)
		(net "SCL")
	)
	(via
		(at 118.738595 92.5786)
		(size 0.4064)
		(drill 0.2032)
		(layers "F.Cu" "B.Cu")
		(tenting
			(front yes)
			(back yes)
		)
		(net "SCL")
	)
	(via
		(at 150.476095 89.8161)
		(size 0.4064)
		(drill 0.2032)
		(layers "F.Cu" "B.Cu")
		(tenting
			(front yes)
			(back yes)
		)
		(net "SCL")
	)
	(via
		(at 131.138595 102.3536)
		(size 0.4064)
		(drill 0.2032)
		(layers "F.Cu" "B.Cu")
		(tenting
			(front yes)
			(back yes)
		)
		(net "SCL")
	)
	(segment
		(start 143.238595 85.5786)
		(end 147.488595 89.8286)
		(width 0.2032)
		(layer "B.Cu")
		(net "SCL")
	)
	(segment
		(start 147.488595 89.8286)
		(end 150.463595 89.8286)
		(width 0.2032)
		(layer "B.Cu")
		(net "SCL")
	)
	(segment
		(start 140.988595 86.0866)
		(end 141.496595 85.5786)
		(width 0.2032)
		(layer "B.Cu")
		(net "SCL")
	)
	(segment
		(start 150.463595 89.8286)
		(end 150.476095 89.8161)
		(width 0.2032)
		(layer "B.Cu")
		(net "SCL")
	)
	(segment
		(start 141.496595 85.5786)
		(end 143.238595 85.5786)
		(width 0.2032)
		(layer "B.Cu")
		(net "SCL")
	)
	(segment
		(start 172.488595 82.5786)
		(end 185.488595 69.5786)
		(width 0.2032)
		(layer "In2.Cu")
		(net "SCL")
	)
	(segment
		(start 185.488595 51.8286)
		(end 186.988595 50.3286)
		(width 0.2032)
		(layer "In2.Cu")
		(net "SCL")
	)
	(segment
		(start 192.028595 50.3286)
		(end 194.028595 52.3286)
		(width 0.2032)
		(layer "In2.Cu")
		(net "SCL")
	)
	(segment
		(start 125.988595 82.5786)
		(end 172.488595 82.5786)
		(width 0.2032)
		(layer "In2.Cu")
		(net "SCL")
	)
	(segment
		(start 131.138595 92.4286)
		(end 134.980595 88.5866)
		(width 0.2032)
		(layer "In2.Cu")
		(net "SCL")
	)
	(segment
		(start 185.488595 69.5786)
		(end 185.488595 51.8286)
		(width 0.2032)
		(layer "In2.Cu")
		(net "SCL")
	)
	(segment
		(start 118.738595 92.5786)
		(end 118.738595 89.8286)
		(width 0.2032)
		(layer "In2.Cu")
		(net "SCL")
	)
	(segment
		(start 134.980595 88.5866)
		(end 134.980595 86.5866)
		(width 0.2032)
		(layer "In2.Cu")
		(net "SCL")
	)
	(segment
		(start 186.988595 50.3286)
		(end 192.028595 50.3286)
		(width 0.2032)
		(layer "In2.Cu")
		(net "SCL")
	)
	(segment
		(start 131.138595 102.3536)
		(end 131.138595 92.4286)
		(width 0.2032)
		(layer "In2.Cu")
		(net "SCL")
	)
	(segment
		(start 118.738595 89.8286)
		(end 125.988595 82.5786)
		(width 0.2032)
		(layer "In2.Cu")
		(net "SCL")
	)
	(segment
		(start 134.472595 86.5946)
		(end 134.972595 86.5946)
		(width 0.2032)
		(layer "In3.Cu")
		(net "SCL")
	)
	(segment
		(start 126.488595 87.3286)
		(end 133.738595 87.3286)
		(width 0.2032)
		(layer "In3.Cu")
		(net "SCL")
	)
	(segment
		(start 133.738595 87.3286)
		(end 134.472595 86.5946)
		(width 0.2032)
		(layer "In3.Cu")
		(net "SCL")
	)
	(segment
		(start 134.980595 86.5866)
		(end 140.488595 86.5866)
		(width 0.2032)
		(layer "In3.Cu")
		(net "SCL")
	)
	(segment
		(start 120.738595 93.0786)
		(end 126.488595 87.3286)
		(width 0.2032)
		(layer "In3.Cu")
		(net "SCL")
	)
	(segment
		(start 140.488595 86.5866)
		(end 140.988595 86.0866)
		(width 0.2032)
		(layer "In3.Cu")
		(net "SCL")
	)
	(segment
		(start 119.238595 93.0786)
		(end 120.738595 93.0786)
		(width 0.2032)
		(layer "In3.Cu")
		(net "SCL")
	)
	(segment
		(start 134.972595 86.5946)
		(end 134.980595 86.5866)
		(width 0.2032)
		(layer "In3.Cu")
		(net "SCL")
	)
	(segment
		(start 118.738595 92.5786)
		(end 119.238595 93.0786)
		(width 0.2032)
		(layer "In3.Cu")
		(net "SCL")
	)
	(segment
		(start 102.077595 64.2396)
		(end 102.077595 60.2216)
		(width 0.3048)
		(layer "F.Cu")
		(net "NetR19_2")
	)
	(segment
		(start 101.988595 64.3286)
		(end 102.077595 64.2396)
		(width 0.3048)
		(layer "F.Cu")
		(net "NetR19_2")
	)
	(segment
		(start 231.328595 110.2596)
		(end 232.028595 110.2596)
		(width 0.2032)
		(layer "F.Cu")
		(net "NetR2_1")
	)
	(segment
		(start 229.934595 108.8656)
		(end 229.934595 107.5206)
		(width 0.2032)
		(layer "F.Cu")
		(net "NetR2_1")
	)
	(segment
		(start 229.934595 108.8656)
		(end 231.328595 110.2596)
		(width 0.2032)
		(layer "F.Cu")
		(net "NetR2_1")
	)
	(segment
		(start 90.234595 56.4614)
		(end 90.234595 54.0886)
		(width 0.2032)
		(layer "F.Cu")
		(net "NetD14_1")
	)
	(segment
		(start 90.085395 56.6106)
		(end 90.234595 56.4614)
		(width 0.2032)
		(layer "F.Cu")
		(net "NetD14_1")
	)
	(segment
		(start 84.963055 56.6106)
		(end 85.112255 56.4614)
		(width 0.2032)
		(layer "F.Cu")
		(net "NetD13_1")
	)
	(segment
		(start 85.112255 56.4614)
		(end 85.112255 54.0886)
		(width 0.2032)
		(layer "F.Cu")
		(net "NetD13_1")
	)
	(segment
		(start 214.732175 87.4536)
		(end 215.788595 87.4536)
		(width 0.508)
		(layer "F.Cu")
		(net "NetD4_1")
	)
	(segment
		(start 214.434595 87.75118)
		(end 214.732175 87.4536)
		(width 0.508)
		(layer "F.Cu")
		(net "NetD4_1")
	)
	(segment
		(start 214.188595 87.8886)
		(end 214.328595 87.8886)
		(width 0.508)
		(layer "F.Cu")
		(net "NetD4_1")
	)
	(segment
		(start 214.434595 87.7826)
		(end 214.434595 87.75118)
		(width 0.508)
		(layer "F.Cu")
		(net "NetD4_1")
	)
	(segment
		(start 214.328595 87.8886)
		(end 214.434595 87.7826)
		(width 0.508)
		(layer "F.Cu")
		(net "NetD4_1")
	)
	(segment
		(start 127.191595 156.9506)
		(end 127.191595 152.2186)
		(width 0.127)
		(layer "B.Cu")
		(net "NetC49_1")
	)
	(segment
		(start 127.158575 157.7576)
		(end 127.191595 157.72458)
		(width 0.2032)
		(layer "B.Cu")
		(net "NetC49_1")
	)
	(arc
		(start 127.191595 156.9506)
		(mid 127.177816 157.019873)
		(end 127.138575 157.0786)
		(width 0.127)
		(layer "B.Cu")
		(net "NetC49_1")
	)
	(arc
		(start 127.191595 157.67788)
		(mid 127.183013 157.721024)
		(end 127.158574 157.757599)
		(width 0.127)
		(layer "B.Cu")
		(net "NetC49_1")
	)
	(segment
		(start 213.388595 100.8786)
		(end 213.388595 100.1786)
		(width 0.2032)
		(layer "F.Cu")
		(net "NetC22_2")
	)
	(segment
		(start 212.535595 99.9326)
		(end 212.581595 99.9786)
		(width 0.2032)
		(layer "F.Cu")
		(net "NetC22_2")
	)
	(segment
		(start 213.625595 101.1156)
		(end 214.886595 101.1156)
		(width 0.2032)
		(layer "F.Cu")
		(net "NetC22_2")
	)
	(segment
		(start 212.581595 99.9786)
		(end 213.188595 99.9786)
		(width 0.2032)
		(layer "F.Cu")
		(net "NetC22_2")
	)
	(segment
		(start 213.188595 99.9786)
		(end 213.388595 100.1786)
		(width 0.2032)
		(layer "F.Cu")
		(net "NetC22_2")
	)
	(segment
		(start 213.388595 100.8786)
		(end 213.625595 101.1156)
		(width 0.2032)
		(layer "F.Cu")
		(net "NetC22_2")
	)
	(segment
		(start 212.535595 101.0376)
		(end 212.613595 101.1156)
		(width 0.2032)
		(layer "F.Cu")
		(net "NetC22_1")
	)
	(segment
		(start 210.988595 101.2686)
		(end 211.002595 101.2826)
		(width 0.2032)
		(layer "F.Cu")
		(net "NetC22_1")
	)
	(segment
		(start 211.002595 101.2826)
		(end 212.535595 101.2826)
		(width 0.2032)
		(layer "F.Cu")
		(net "NetC22_1")
	)
	(segment
		(start 214.859595 105.4336)
		(end 214.859595 103.6826)
		(width 0.2032)
		(layer "F.Cu")
		(net "NetC21_2")
	)
	(segment
		(start 214.859595 103.6826)
		(end 214.886595 103.6556)
		(width 0.2032)
		(layer "F.Cu")
		(net "NetC21_2")
	)
	(segment
		(start 233.688595 112.4786)
		(end 233.988595 112.7786)
		(width 0.2032)
		(layer "F.Cu")
		(net "NetC20_2")
	)
	(segment
		(start 234.699595 112.7786)
		(end 234.760595 112.8396)
		(width 0.2032)
		(layer "F.Cu")
		(net "NetC20_2")
	)
	(segment
		(start 232.028595 111.5296)
		(end 233.439595 111.5296)
		(width 0.2032)
		(layer "F.Cu")
		(net "NetC20_2")
	)
	(segment
		(start 233.688595 112.4786)
		(end 233.688595 111.7786)
		(width 0.2032)
		(layer "F.Cu")
		(net "NetC20_2")
	)
	(segment
		(start 233.439595 111.5296)
		(end 233.688595 111.7786)
		(width 0.2032)
		(layer "F.Cu")
		(net "NetC20_2")
	)
	(segment
		(start 233.988595 112.7786)
		(end 234.699595 112.7786)
		(width 0.2032)
		(layer "F.Cu")
		(net "NetC20_2")
	)
	(segment
		(start 236.287595 111.4896)
		(end 236.288595 111.4886)
		(width 0.2032)
		(layer "F.Cu")
		(net "NetC20_1")
	)
	(segment
		(start 234.760595 111.4896)
		(end 236.287595 111.4896)
		(width 0.2032)
		(layer "F.Cu")
		(net "NetC20_1")
	)
	(segment
		(start 234.555595 111.5296)
		(end 234.760595 111.7346)
		(width 0.2032)
		(layer "F.Cu")
		(net "NetC20_1")
	)
	(segment
		(start 232.309595 108.8062)
		(end 232.309595 107.3386)
		(width 0.2032)
		(layer "F.Cu")
		(net "NetC19_2")
	)
	(segment
		(start 232.126195 108.9896)
		(end 232.309595 108.8062)
		(width 0.2032)
		(layer "F.Cu")
		(net "NetC19_2")
	)
	(segment
		(start 232.028595 108.9896)
		(end 232.126195 108.9896)
		(width 0.2032)
		(layer "F.Cu")
		(net "NetC19_2")
	)
	(segment
		(start 224.664595 111.5296)
		(end 227.078595 111.5296)
		(width 0.2032)
		(layer "F.Cu")
		(net "NetC4_2")
	)
	(segment
		(start 224.092595 110.9576)
		(end 224.092595 110.9326)
		(width 0.2032)
		(layer "F.Cu")
		(net "NetC4_2")
	)
	(segment
		(start 224.092595 110.9576)
		(end 224.664595 111.5296)
		(width 0.2032)
		(layer "F.Cu")
		(net "NetC4_2")
	)
	(segment
		(start 219.012595 113.7916)
		(end 220.262595 113.7916)
		(width 0.2032)
		(layer "F.Cu")
		(net "NetC4_2")
	)
	(segment
		(start 223.121595 110.9326)
		(end 224.092595 110.9326)
		(width 0.2032)
		(layer "F.Cu")
		(net "NetC4_2")
	)
	(segment
		(start 220.262595 113.7916)
		(end 223.121595 110.9326)
		(width 0.2032)
		(layer "F.Cu")
		(net "NetC4_2")
	)
	(segment
		(start 224.092595 109.3326)
		(end 224.435595 108.9896)
		(width 0.2032)
		(layer "F.Cu")
		(net "NetC4_1")
	)
	(segment
		(start 224.435595 108.9896)
		(end 227.078595 108.9896)
		(width 0.2032)
		(layer "F.Cu")
		(net "NetC4_1")
	)
	(segment
		(start 221.953595 102.0936)
		(end 222.822595 102.0936)
		(width 0.2032)
		(layer "F.Cu")
		(net "NetC3_2")
	)
	(segment
		(start 227.223595 102.0936)
		(end 228.156595 101.1606)
		(width 0.2032)
		(layer "F.Cu")
		(net "NetC3_2")
	)
	(segment
		(start 222.822595 102.0936)
		(end 227.223595 102.0936)
		(width 0.2032)
		(layer "F.Cu")
		(net "NetC3_2")
	)
	(segment
		(start 219.836595 101.1156)
		(end 220.975595 101.1156)
		(width 0.2032)
		(layer "F.Cu")
		(net "NetC3_2")
	)
	(segment
		(start 228.156595 101.1606)
		(end 228.156595 99.1076)
		(width 0.2032)
		(layer "F.Cu")
		(net "NetC3_2")
	)
	(segment
		(start 220.975595 101.1156)
		(end 221.953595 102.0936)
		(width 0.2032)
		(layer "F.Cu")
		(net "NetC3_2")
	)
	(segment
		(start 219.836595 103.6556)
		(end 222.784595 103.6556)
		(width 0.2032)
		(layer "F.Cu")
		(net "NetC3_1")
	)
	(segment
		(start 222.784595 103.6556)
		(end 222.822595 103.6936)
		(width 0.2032)
		(layer "F.Cu")
		(net "NetC3_1")
	)
	(segment
		(start 116.188375 96.61847)
		(end 116.188375 94.8088)
		(width 0.2032)
		(layer "F.Cu")
		(net "MAC_USB_PWR")
	)
	(segment
		(start 116.413595 94.58359)
		(end 116.413595 94.5286)
		(width 0.2032)
		(layer "F.Cu")
		(net "MAC_USB_PWR")
	)
	(segment
		(start 156.627045 119.05816)
		(end 156.660615 119.05816)
		(width 0.2032)
		(layer "F.Cu")
		(net "MAC_USB_PWR")
	)
	(segment
		(start 156.660615 119.05816)
		(end 156.806325 119.20388)
		(width 0.2032)
		(layer "F.Cu")
		(net "MAC_USB_PWR")
	)
	(segment
		(start 156.806325 119.20388)
		(end 158.071115 119.20388)
		(width 0.2032)
		(layer "F.Cu")
		(net "MAC_USB_PWR")
	)
	(segment
		(start 116.188375 94.8088)
		(end 116.413595 94.58359)
		(width 0.2032)
		(layer "F.Cu")
		(net "MAC_USB_PWR")
	)
	(via
		(at 156.627045 119.05816)
		(size 0.4064)
		(drill 0.2032)
		(layers "F.Cu" "B.Cu")
		(tenting
			(front yes)
			(back yes)
		)
		(net "MAC_USB_PWR")
	)
	(via
		(at 116.413595 94.5286)
		(size 0.4064)
		(drill 0.2032)
		(layers "F.Cu" "B.Cu")
		(tenting
			(front yes)
			(back yes)
		)
		(net "MAC_USB_PWR")
	)
	(segment
		(start 116.358605 94.5286)
		(end 116.413595 94.5286)
		(width 0.2032)
		(layer "B.Cu")
		(net "MAC_USB_PWR")
	)
	(segment
		(start 115.988595 94.89861)
		(end 116.358605 94.5286)
		(width 0.2032)
		(layer "B.Cu")
		(net "MAC_USB_PWR")
	)
	(segment
		(start 130.468155 119.05816)
		(end 156.627045 119.05816)
		(width 0.2032)
		(layer "B.Cu")
		(net "MAC_USB_PWR")
	)
	(segment
		(start 115.988595 104.5786)
		(end 130.468155 119.05816)
		(width 0.2032)
		(layer "B.Cu")
		(net "MAC_USB_PWR")
	)
	(segment
		(start 115.988595 104.5786)
		(end 115.988595 94.89861)
		(width 0.2032)
		(layer "B.Cu")
		(net "MAC_USB_PWR")
	)
	(segment
		(start 132.688215 96.61847)
		(end 132.688215 95.3458)
		(width 0.2032)
		(layer "F.Cu")
		(net "MAC_USB-")
	)
	(segment
		(start 156.642495 119.71187)
		(end 158.071095 119.71187)
		(width 0.2032)
		(layer "F.Cu")
		(net "MAC_USB-")
	)
	(segment
		(start 156.642475 119.71185)
		(end 156.642495 119.71187)
		(width 0.2032)
		(layer "F.Cu")
		(net "MAC_USB-")
	)
	(segment
		(start 158.071095 119.71187)
		(end 158.071115 119.71188)
		(width 0.2032)
		(layer "F.Cu")
		(net "MAC_USB-")
	)
	(segment
		(start 132.688215 95.3458)
		(end 132.928015 95.10601)
		(width 0.2032)
		(layer "F.Cu")
		(net "MAC_USB-")
	)
	(segment
		(start 132.928015 95.10601)
		(end 132.928015 95.05102)
		(width 0.2032)
		(layer "F.Cu")
		(net "MAC_USB-")
	)
	(via
		(at 156.642475 119.71185)
		(size 0.4064)
		(drill 0.2032)
		(layers "F.Cu" "B.Cu")
		(tenting
			(front yes)
			(back yes)
		)
		(net "MAC_USB-")
	)
	(via
		(at 132.928015 95.05102)
		(size 0.4064)
		(drill 0.2032)
		(layers "F.Cu" "B.Cu")
		(tenting
			(front yes)
			(back yes)
		)
		(net "MAC_USB-")
	)
	(via
		(at 132.988595 105.3286)
		(size 0.4064)
		(drill 0.2032)
		(layers "F.Cu" "B.Cu")
		(tenting
			(front yes)
			(back yes)
		)
		(net "MAC_USB-")
	)
	(segment
		(start 132.928015 95.05102)
		(end 132.958305 95.08131)
		(width 0.2032)
		(layer "B.Cu")
		(net "MAC_USB-")
	)
	(segment
		(start 132.958305 105.29831)
		(end 132.958305 95.08131)
		(width 0.2032)
		(layer "B.Cu")
		(net "MAC_USB-")
	)
	(segment
		(start 132.958305 105.29831)
		(end 132.988595 105.3286)
		(width 0.2032)
		(layer "B.Cu")
		(net "MAC_USB-")
	)
	(segment
		(start 144.625365 120.9984)
		(end 153.068795 120.9984)
		(width 0.2032)
		(layer "In3.Cu")
		(net "MAC_USB-")
	)
	(segment
		(start 154.355345 119.71185)
		(end 156.642475 119.71185)
		(width 0.2032)
		(layer "In3.Cu")
		(net "MAC_USB-")
	)
	(segment
		(start 132.988595 109.36163)
		(end 132.988595 105.3286)
		(width 0.2032)
		(layer "In3.Cu")
		(net "MAC_USB-")
	)
	(segment
		(start 132.988595 109.36163)
		(end 144.625365 120.9984)
		(width 0.2032)
		(layer "In3.Cu")
		(net "MAC_USB-")
	)
	(segment
		(start 153.068795 120.9984)
		(end 154.355345 119.71185)
		(width 0.2032)
		(layer "In3.Cu")
		(net "MAC_USB-")
	)
	(segment
		(start 156.703825 120.50084)
		(end 156.961375 120.24328)
		(width 0.2032)
		(layer "F.Cu")
		(net "MAC_USB+")
	)
	(segment
		(start 132.163595 94.3786)
		(end 132.175975 94.39097)
		(width 0.2032)
		(layer "F.Cu")
		(net "MAC_USB+")
	)
	(segment
		(start 158.047715 120.24328)
		(end 158.071115 120.21988)
		(width 0.2032)
		(layer "F.Cu")
		(net "MAC_USB+")
	)
	(segment
		(start 132.175975 96.6061)
		(end 132.175975 94.39097)
		(width 0.2032)
		(layer "F.Cu")
		(net "MAC_USB+")
	)
	(segment
		(start 156.961375 120.24328)
		(end 158.047715 120.24328)
		(width 0.2032)
		(layer "F.Cu")
		(net "MAC_USB+")
	)
	(segment
		(start 132.175975 96.6061)
		(end 132.188345 96.61847)
		(width 0.2032)
		(layer "F.Cu")
		(net "MAC_USB+")
	)
	(segment
		(start 156.648835 120.50084)
		(end 156.703825 120.50084)
		(width 0.2032)
		(layer "F.Cu")
		(net "MAC_USB+")
	)
	(via
		(at 132.163595 94.3786)
		(size 0.4064)
		(drill 0.2032)
		(layers "F.Cu" "B.Cu")
		(tenting
			(front yes)
			(back yes)
		)
		(net "MAC_USB+")
	)
	(via
		(at 132.128995 105.3286)
		(size 0.4064)
		(drill 0.2032)
		(layers "F.Cu" "B.Cu")
		(tenting
			(front yes)
			(back yes)
		)
		(net "MAC_USB+")
	)
	(via
		(at 156.648835 120.50084)
		(size 0.4064)
		(drill 0.2032)
		(layers "F.Cu" "B.Cu")
		(tenting
			(front yes)
			(back yes)
		)
		(net "MAC_USB+")
	)
	(segment
		(start 132.128995 105.3286)
		(end 132.163595 105.294)
		(width 0.2032)
		(layer "B.Cu")
		(net "MAC_USB+")
	)
	(segment
		(start 132.163595 105.294)
		(end 132.163595 94.3786)
		(width 0.2032)
		(layer "B.Cu")
		(net "MAC_USB+")
	)
	(segment
		(start 153.488595 121.3286)
		(end 154.316355 120.50084)
		(width 0.2032)
		(layer "In3.Cu")
		(net "MAC_USB+")
	)
	(segment
		(start 132.128995 108.969)
		(end 144.488595 121.3286)
		(width 0.2032)
		(layer "In3.Cu")
		(net "MAC_USB+")
	)
	(segment
		(start 132.128995 108.969)
		(end 132.128995 105.3286)
		(width 0.2032)
		(layer "In3.Cu")
		(net "MAC_USB+")
	)
	(segment
		(start 154.316355 120.50084)
		(end 156.648835 120.50084)
		(width 0.2032)
		(layer "In3.Cu")
		(net "MAC_USB+")
	)
	(segment
		(start 144.488595 121.3286)
		(end 153.488595 121.3286)
		(width 0.2032)
		(layer "In3.Cu")
		(net "MAC_USB+")
	)
	(segment
		(start 120.688245 94.47896)
		(end 120.688595 94.4786)
		(width 0.2032)
		(layer "F.Cu")
		(net "MAC_TX")
	)
	(segment
		(start 120.688245 96.61847)
		(end 120.688245 94.47896)
		(width 0.2032)
		(layer "F.Cu")
		(net "MAC_TX")
	)
	(via
		(at 120.688595 94.4786)
		(size 0.4064)
		(drill 0.2032)
		(layers "F.Cu" "B.Cu")
		(tenting
			(front yes)
			(back yes)
		)
		(net "MAC_TX")
	)
	(segment
		(start 122.400375 92.7484)
		(end 165.725875 92.7484)
		(width 0.2032)
		(layer "In3.Cu")
		(net "MAC_TX")
	)
	(segment
		(start 165.725875 92.7484)
		(end 167.906075 94.9286)
		(width 0.2032)
		(layer "In3.Cu")
		(net "MAC_TX")
	)
	(segment
		(start 120.688595 94.46018)
		(end 122.400375 92.7484)
		(width 0.2032)
		(layer "In3.Cu")
		(net "MAC_TX")
	)
	(segment
		(start 120.688595 94.4786)
		(end 120.688595 94.46018)
		(width 0.2032)
		(layer "In3.Cu")
		(net "MAC_TX")
	)
	(segment
		(start 121.188365 96.61847)
		(end 121.188365 94.73382)
		(width 0.2032)
		(layer "F.Cu")
		(net "MAC_RX")
	)
	(segment
		(start 121.388595 94.53359)
		(end 121.388595 94.4786)
		(width 0.2032)
		(layer "F.Cu")
		(net "MAC_RX")
	)
	(segment
		(start 121.188365 94.73382)
		(end 121.388595 94.53359)
		(width 0.2032)
		(layer "F.Cu")
		(net "MAC_RX")
	)
	(via
		(at 121.388595 94.4786)
		(size 0.4064)
		(drill 0.2032)
		(layers "F.Cu" "B.Cu")
		(tenting
			(front yes)
			(back yes)
		)
		(net "MAC_RX")
	)
	(segment
		(start 121.388595 94.4786)
		(end 122.788595 93.0786)
		(width 0.2032)
		(layer "In3.Cu")
		(net "MAC_RX")
	)
	(segment
		(start 163.056085 93.0786)
		(end 164.906075 94.9286)
		(width 0.2032)
		(layer "In3.Cu")
		(net "MAC_RX")
	)
	(segment
		(start 122.788595 93.0786)
		(end 163.056085 93.0786)
		(width 0.2032)
		(layer "In3.Cu")
		(net "MAC_RX")
	)
	(segment
		(start 174.311025 86.9236)
		(end 176.638595 86.9236)
		(width 0.2032)
		(layer "F.Cu")
		(net "MAC_PPS_OUT-")
	)
	(segment
		(start 160.862865 115.64788)
		(end 162.071115 115.64788)
		(width 0.2032)
		(layer "F.Cu")
		(net "MAC_PPS_OUT-")
	)
	(segment
		(start 160.488595 115.3286)
		(end 160.543585 115.3286)
		(width 0.2032)
		(layer "F.Cu")
		(net "MAC_PPS_OUT-")
	)
	(segment
		(start 172.738595 87.0786)
		(end 174.113595 87.0786)
		(width 0.2032)
		(layer "F.Cu")
		(net "MAC_PPS_OUT-")
	)
	(segment
		(start 160.543585 115.3286)
		(end 160.862865 115.64788)
		(width 0.2032)
		(layer "F.Cu")
		(net "MAC_PPS_OUT-")
	)
	(segment
		(start 174.113595 87.0786)
		(end 174.238595 86.9536)
		(width 0.2032)
		(layer "F.Cu")
		(net "MAC_PPS_OUT-")
	)
	(via
		(at 160.488595 115.3286)
		(size 0.4064)
		(drill 0.2032)
		(layers "F.Cu" "B.Cu")
		(tenting
			(front yes)
			(back yes)
		)
		(net "MAC_PPS_OUT-")
	)
	(via
		(at 172.738595 87.0786)
		(size 0.4064)
		(drill 0.2032)
		(layers "F.Cu" "B.Cu")
		(tenting
			(front yes)
			(back yes)
		)
		(net "MAC_PPS_OUT-")
	)
	(arc
		(start 174.238769 86.953429)
		(mid 174.27194 86.931351)
		(end 174.311025 86.9236)
		(width 0.2032)
		(layer "F.Cu")
		(net "MAC_PPS_OUT-")
	)
	(arc
		(start 174.238596 86.953601)
		(mid 174.238682 86.953515)
		(end 174.238769 86.953429)
		(width 0.2032)
		(layer "F.Cu")
		(net "MAC_PPS_OUT-")
	)
	(segment
		(start 172.732545 87.08465)
		(end 172.738595 87.0786)
		(width 0.2032)
		(layer "In2.Cu")
		(net "MAC_PPS_OUT-")
	)
	(segment
		(start 160.488595 115.3286)
		(end 168.986495 115.3286)
		(width 0.2032)
		(layer "In2.Cu")
		(net "MAC_PPS_OUT-")
	)
	(segment
		(start 171.988595 112.3265)
		(end 171.988595 88.8807)
		(width 0.2032)
		(layer "In2.Cu")
		(net "MAC_PPS_OUT-")
	)
	(segment
		(start 170.782545 114.58465)
		(end 171.244645 114.12255)
		(width 0.2032)
		(layer "In2.Cu")
		(net "MAC_PPS_OUT-")
	)
	(arc
		(start 170.782546 114.584651)
		(mid 169.958511 115.135254)
		(end 168.986495 115.3286)
		(width 0.2032)
		(layer "In2.Cu")
		(net "MAC_PPS_OUT-")
	)
	(arc
		(start 171.988595 112.3265)
		(mid 171.795249 113.298516)
		(end 171.244646 114.122551)
		(width 0.2032)
		(layer "In2.Cu")
		(net "MAC_PPS_OUT-")
	)
	(arc
		(start 171.988595 88.8807)
		(mid 172.181941 87.908684)
		(end 172.732544 87.084649)
		(width 0.2032)
		(layer "In2.Cu")
		(net "MAC_PPS_OUT-")
	)
	(segment
		(start 160.514625 115.96307)
		(end 160.707425 116.15588)
		(width 0.2032)
		(layer "F.Cu")
		(net "MAC_PPS_OUT+")
	)
	(segment
		(start 174.113595 88.3286)
		(end 174.238595 88.2036)
		(width 0.2032)
		(layer "F.Cu")
		(net "MAC_PPS_OUT+")
	)
	(segment
		(start 174.262735 88.1936)
		(end 176.638595 88.1936)
		(width 0.2032)
		(layer "F.Cu")
		(net "MAC_PPS_OUT+")
	)
	(segment
		(start 172.738595 88.3286)
		(end 174.113595 88.3286)
		(width 0.2032)
		(layer "F.Cu")
		(net "MAC_PPS_OUT+")
	)
	(segment
		(start 160.459635 115.96307)
		(end 160.514625 115.96307)
		(width 0.2032)
		(layer "F.Cu")
		(net "MAC_PPS_OUT+")
	)
	(segment
		(start 160.707425 116.15588)
		(end 162.071115 116.15588)
		(width 0.2032)
		(layer "F.Cu")
		(net "MAC_PPS_OUT+")
	)
	(via
		(at 172.738595 88.3286)
		(size 0.4064)
		(drill 0.2032)
		(layers "F.Cu" "B.Cu")
		(tenting
			(front yes)
			(back yes)
		)
		(net "MAC_PPS_OUT+")
	)
	(via
		(at 160.459635 115.96307)
		(size 0.4064)
		(drill 0.2032)
		(layers "F.Cu" "B.Cu")
		(tenting
			(front yes)
			(back yes)
		)
		(net "MAC_PPS_OUT+")
	)
	(arc
		(start 174.238594 88.203599)
		(mid 174.24967 88.196198)
		(end 174.262735 88.193599)
		(width 0.2032)
		(layer "F.Cu")
		(net "MAC_PPS_OUT+")
	)
	(segment
		(start 171.248075 115.21912)
		(end 171.994645 114.47255)
		(width 0.2032)
		(layer "In2.Cu")
		(net "MAC_PPS_OUT+")
	)
	(segment
		(start 160.459635 115.96307)
		(end 169.452015 115.96307)
		(width 0.2032)
		(layer "In2.Cu")
		(net "MAC_PPS_OUT+")
	)
	(segment
		(start 172.738595 112.6765)
		(end 172.738595 88.3286)
		(width 0.2032)
		(layer "In2.Cu")
		(net "MAC_PPS_OUT+")
	)
	(arc
		(start 171.248066 115.219121)
		(mid 170.424031 115.769724)
		(end 169.452015 115.96307)
		(width 0.2032)
		(layer "In2.Cu")
		(net "MAC_PPS_OUT+")
	)
	(arc
		(start 172.738595 112.6765)
		(mid 172.545249 113.648516)
		(end 171.994646 114.472551)
		(width 0.2032)
		(layer "In2.Cu")
		(net "MAC_PPS_OUT+")
	)
	(segment
		(start 199.288595 88.0786)
		(end 203.488595 88.0786)
		(width 0.2032)
		(layer "F.Cu")
		(net "MAC_PPS_IN1+")
	)
	(segment
		(start 160.527475 120.53972)
		(end 160.777475 120.53972)
		(width 0.2032)
		(layer "F.Cu")
		(net "MAC_PPS_IN1+")
	)
	(segment
		(start 161.073915 120.24328)
		(end 162.047715 120.24328)
		(width 0.2032)
		(layer "F.Cu")
		(net "MAC_PPS_IN1+")
	)
	(segment
		(start 162.047715 120.24328)
		(end 162.071115 120.21988)
		(width 0.2032)
		(layer "F.Cu")
		(net "MAC_PPS_IN1+")
	)
	(segment
		(start 160.777475 120.53972)
		(end 161.073915 120.24328)
		(width 0.2032)
		(layer "F.Cu")
		(net "MAC_PPS_IN1+")
	)
	(segment
		(start 160.488595 120.5786)
		(end 160.527475 120.53972)
		(width 0.2032)
		(layer "F.Cu")
		(net "MAC_PPS_IN1+")
	)
	(via
		(at 160.488595 120.5786)
		(size 0.4064)
		(drill 0.2032)
		(layers "F.Cu" "B.Cu")
		(tenting
			(front yes)
			(back yes)
		)
		(net "MAC_PPS_IN1+")
	)
	(via
		(at 203.488595 88.0786)
		(size 0.4064)
		(drill 0.2032)
		(layers "F.Cu" "B.Cu")
		(tenting
			(front yes)
			(back yes)
		)
		(net "MAC_PPS_IN1+")
	)
	(segment
		(start 206.238595 106.5265)
		(end 206.238595 91.8807)
		(width 0.2032)
		(layer "In2.Cu")
		(net "MAC_PPS_IN1+")
	)
	(segment
		(start 193.982545 119.83465)
		(end 205.494645 108.32255)
		(width 0.2032)
		(layer "In2.Cu")
		(net "MAC_PPS_IN1+")
	)
	(segment
		(start 160.488595 120.5786)
		(end 192.186485 120.5786)
		(width 0.2032)
		(layer "In2.Cu")
		(net "MAC_PPS_IN1+")
	)
	(segment
		(start 203.488595 88.0786)
		(end 205.494645 90.08465)
		(width 0.2032)
		(layer "In2.Cu")
		(net "MAC_PPS_IN1+")
	)
	(arc
		(start 193.982546 119.834651)
		(mid 193.158508 120.385255)
		(end 192.18649 120.5786)
		(width 0.2032)
		(layer "In2.Cu")
		(net "MAC_PPS_IN1+")
	)
	(arc
		(start 206.238595 106.5265)
		(mid 206.045249 107.498519)
		(end 205.494645 108.322557)
		(width 0.2032)
		(layer "In2.Cu")
		(net "MAC_PPS_IN1+")
	)
	(arc
		(start 205.494646 90.084649)
		(mid 206.045249 90.908684)
		(end 206.238595 91.8807)
		(width 0.2032)
		(layer "In2.Cu")
		(net "MAC_PPS_IN1+")
	)
	(segment
		(start 199.303595 90.6036)
		(end 201.963595 90.6036)
		(width 0.2032)
		(layer "F.Cu")
		(net "MAC_PPS_IN0-")
	)
	(segment
		(start 160.543585 118.5786)
		(end 160.660865 118.69588)
		(width 0.2032)
		(layer "F.Cu")
		(net "MAC_PPS_IN0-")
	)
	(segment
		(start 160.660865 118.69588)
		(end 162.071115 118.69588)
		(width 0.2032)
		(layer "F.Cu")
		(net "MAC_PPS_IN0-")
	)
	(segment
		(start 160.488595 118.5786)
		(end 160.543585 118.5786)
		(width 0.2032)
		(layer "F.Cu")
		(net "MAC_PPS_IN0-")
	)
	(segment
		(start 201.963595 90.6036)
		(end 201.978595 90.5886)
		(width 0.2032)
		(layer "F.Cu")
		(net "MAC_PPS_IN0-")
	)
	(segment
		(start 199.288595 90.6186)
		(end 199.303595 90.6036)
		(width 0.2032)
		(layer "F.Cu")
		(net "MAC_PPS_IN0-")
	)
	(via
		(at 160.488595 118.5786)
		(size 0.4064)
		(drill 0.2032)
		(layers "F.Cu" "B.Cu")
		(tenting
			(front yes)
			(back yes)
		)
		(net "MAC_PPS_IN0-")
	)
	(via
		(at 201.978595 90.5886)
		(size 0.4064)
		(drill 0.2032)
		(layers "F.Cu" "B.Cu")
		(tenting
			(front yes)
			(back yes)
		)
		(net "MAC_PPS_IN0-")
	)
	(segment
		(start 192.482545 117.83465)
		(end 203.244645 107.07255)
		(width 0.2032)
		(layer "In2.Cu")
		(net "MAC_PPS_IN0-")
	)
	(segment
		(start 160.488595 118.5786)
		(end 190.686495 118.5786)
		(width 0.2032)
		(layer "In2.Cu")
		(net "MAC_PPS_IN0-")
	)
	(segment
		(start 201.978595 90.5886)
		(end 203.244645 91.85465)
		(width 0.2032)
		(layer "In2.Cu")
		(net "MAC_PPS_IN0-")
	)
	(segment
		(start 203.988595 105.2765)
		(end 203.988595 93.6507)
		(width 0.2032)
		(layer "In2.Cu")
		(net "MAC_PPS_IN0-")
	)
	(arc
		(start 203.988595 105.2765)
		(mid 203.795249 106.248516)
		(end 203.244646 107.072551)
		(width 0.2032)
		(layer "In2.Cu")
		(net "MAC_PPS_IN0-")
	)
	(arc
		(start 192.482546 117.834651)
		(mid 191.658511 118.385254)
		(end 190.686495 118.5786)
		(width 0.2032)
		(layer "In2.Cu")
		(net "MAC_PPS_IN0-")
	)
	(arc
		(start 203.244646 91.854649)
		(mid 203.795249 92.678684)
		(end 203.988595 93.6507)
		(width 0.2032)
		(layer "In2.Cu")
		(net "MAC_PPS_IN0-")
	)
	(segment
		(start 199.288595 89.3486)
		(end 199.298595 89.3386)
		(width 0.2032)
		(layer "F.Cu")
		(net "MAC_PPS_IN0+")
	)
	(segment
		(start 162.063555 119.21144)
		(end 162.071115 119.20388)
		(width 0.2032)
		(layer "F.Cu")
		(net "MAC_PPS_IN0+")
	)
	(segment
		(start 160.496155 119.21144)
		(end 162.063555 119.21144)
		(width 0.2032)
		(layer "F.Cu")
		(net "MAC_PPS_IN0+")
	)
	(segment
		(start 199.298595 89.3386)
		(end 201.978595 89.3386)
		(width 0.2032)
		(layer "F.Cu")
		(net "MAC_PPS_IN0+")
	)
	(segment
		(start 201.978595 89.3386)
		(end 201.988595 89.3286)
		(width 0.2032)
		(layer "F.Cu")
		(net "MAC_PPS_IN0+")
	)
	(segment
		(start 160.488595 119.219)
		(end 160.496155 119.21144)
		(width 0.2032)
		(layer "F.Cu")
		(net "MAC_PPS_IN0+")
	)
	(via
		(at 160.488595 119.219)
		(size 0.4064)
		(drill 0.2032)
		(layers "F.Cu" "B.Cu")
		(tenting
			(front yes)
			(back yes)
		)
		(net "MAC_PPS_IN0+")
	)
	(via
		(at 201.988595 89.3286)
		(size 0.4064)
		(drill 0.2032)
		(layers "F.Cu" "B.Cu")
		(tenting
			(front yes)
			(back yes)
		)
		(net "MAC_PPS_IN0+")
	)
	(segment
		(start 160.488595 119.219)
		(end 191.201085 119.219)
		(width 0.2032)
		(layer "In2.Cu")
		(net "MAC_PPS_IN0+")
	)
	(segment
		(start 192.732545 118.58465)
		(end 203.994645 107.32255)
		(width 0.2032)
		(layer "In2.Cu")
		(net "MAC_PPS_IN0+")
	)
	(segment
		(start 204.738595 105.5265)
		(end 204.738595 93.1307)
		(width 0.2032)
		(layer "In2.Cu")
		(net "MAC_PPS_IN0+")
	)
	(segment
		(start 201.988595 89.3286)
		(end 203.994645 91.33465)
		(width 0.2032)
		(layer "In2.Cu")
		(net "MAC_PPS_IN0+")
	)
	(arc
		(start 203.994646 91.334649)
		(mid 204.545249 92.158684)
		(end 204.738595 93.1307)
		(width 0.2032)
		(layer "In2.Cu")
		(net "MAC_PPS_IN0+")
	)
	(arc
		(start 204.738595 105.5265)
		(mid 204.545249 106.498516)
		(end 203.994646 107.322551)
		(width 0.2032)
		(layer "In2.Cu")
		(net "MAC_PPS_IN0+")
	)
	(arc
		(start 192.732545 118.584658)
		(mid 192.029905 119.054147)
		(end 191.201085 119.21901)
		(width 0.2032)
		(layer "In2.Cu")
		(net "MAC_PPS_IN0+")
	)
	(segment
		(start 123.688235 100.66825)
		(end 123.711605 100.69162)
		(width 0.2032)
		(layer "F.Cu")
		(net "MAC_BITE")
	)
	(segment
		(start 123.711605 101.70161)
		(end 124.413595 102.4036)
		(width 0.2032)
		(layer "F.Cu")
		(net "MAC_BITE")
	)
	(segment
		(start 123.711605 101.70161)
		(end 123.711605 100.69162)
		(width 0.2032)
		(layer "F.Cu")
		(net "MAC_BITE")
	)
	(via
		(at 124.238595 93.8286)
		(size 0.4064)
		(drill 0.2032)
		(layers "F.Cu" "B.Cu")
		(tenting
			(front yes)
			(back yes)
		)
		(net "MAC_BITE")
	)
	(via
		(at 124.413595 102.4036)
		(size 0.4064)
		(drill 0.2032)
		(layers "F.Cu" "B.Cu")
		(tenting
			(front yes)
			(back yes)
		)
		(net "MAC_BITE")
	)
	(segment
		(start 123.738595 101.7286)
		(end 124.413595 102.4036)
		(width 0.2032)
		(layer "B.Cu")
		(net "MAC_BITE")
	)
	(segment
		(start 123.738595 101.7286)
		(end 123.738595 94.3286)
		(width 0.2032)
		(layer "B.Cu")
		(net "MAC_BITE")
	)
	(segment
		(start 123.738595 94.3286)
		(end 124.238595 93.8286)
		(width 0.2032)
		(layer "B.Cu")
		(net "MAC_BITE")
	)
	(segment
		(start 156.318795 93.6588)
		(end 157.588595 94.9286)
		(width 0.2032)
		(layer "In3.Cu")
		(net "MAC_BITE")
	)
	(segment
		(start 146.238595 93.8286)
		(end 146.408395 93.6588)
		(width 0.2032)
		(layer "In3.Cu")
		(net "MAC_BITE")
	)
	(segment
		(start 146.408395 93.6588)
		(end 156.318795 93.6588)
		(width 0.2032)
		(layer "In3.Cu")
		(net "MAC_BITE")
	)
	(segment
		(start 124.238595 93.8286)
		(end 146.238595 93.8286)
		(width 0.2032)
		(layer "In3.Cu")
		(net "MAC_BITE")
	)
	(segment
		(start 157.588595 94.9286)
		(end 161.906085 94.9286)
		(width 0.2032)
		(layer "In3.Cu")
		(net "MAC_BITE")
	)
	(segment
		(start 156.946195 115.64788)
		(end 158.071115 115.64788)
		(width 0.2032)
		(layer "F.Cu")
		(net "MAC_ALARM")
	)
	(segment
		(start 123.188365 102.02338)
		(end 123.488595 102.32361)
		(width 0.2032)
		(layer "F.Cu")
		(net "MAC_ALARM")
	)
	(segment
		(start 156.626915 115.3286)
		(end 156.946195 115.64788)
		(width 0.2032)
		(layer "F.Cu")
		(net "MAC_ALARM")
	)
	(segment
		(start 123.488595 102.3786)
		(end 123.488595 102.32361)
		(width 0.2032)
		(layer "F.Cu")
		(net "MAC_ALARM")
	)
	(segment
		(start 123.188365 102.02338)
		(end 123.188365 100.66825)
		(width 0.2032)
		(layer "F.Cu")
		(net "MAC_ALARM")
	)
	(via
		(at 123.488595 102.3786)
		(size 0.4064)
		(drill 0.2032)
		(layers "F.Cu" "B.Cu")
		(tenting
			(front yes)
			(back yes)
		)
		(net "MAC_ALARM")
	)
	(via
		(at 156.626915 115.3286)
		(size 0.4064)
		(drill 0.2032)
		(layers "F.Cu" "B.Cu")
		(tenting
			(front yes)
			(back yes)
		)
		(net "MAC_ALARM")
	)
	(segment
		(start 154.376915 117.5786)
		(end 156.626915 115.3286)
		(width 0.2032)
		(layer "B.Cu")
		(net "MAC_ALARM")
	)
	(segment
		(start 136.988595 117.5786)
		(end 154.376915 117.5786)
		(width 0.2032)
		(layer "B.Cu")
		(net "MAC_ALARM")
	)
	(segment
		(start 123.488595 104.0786)
		(end 123.488595 102.3786)
		(width 0.2032)
		(layer "B.Cu")
		(net "MAC_ALARM")
	)
	(segment
		(start 123.488595 104.0786)
		(end 136.988595 117.5786)
		(width 0.2032)
		(layer "B.Cu")
		(net "MAC_ALARM")
	)
	(segment
		(start 153.230955 115.57096)
		(end 153.238595 115.5786)
		(width 0.2032)
		(layer "F.Cu")
		(net "GPS1_TP2")
	)
	(segment
		(start 118.988595 68.5786)
		(end 121.043595 68.5786)
		(width 0.2032)
		(layer "F.Cu")
		(net "GPS1_TP2")
	)
	(segment
		(start 151.233535 115.57096)
		(end 153.230955 115.57096)
		(width 0.2032)
		(layer "F.Cu")
		(net "GPS1_TP2")
	)
	(segment
		(start 151.225895 115.56332)
		(end 151.233535 115.57096)
		(width 0.2032)
		(layer "F.Cu")
		(net "GPS1_TP2")
	)
	(via
		(at 153.238595 115.5786)
		(size 0.4064)
		(drill 0.2032)
		(layers "F.Cu" "B.Cu")
		(tenting
			(front yes)
			(back yes)
		)
		(net "GPS1_TP2")
	)
	(via
		(at 118.988595 68.5786)
		(size 0.4064)
		(drill 0.2032)
		(layers "F.Cu" "B.Cu")
		(tenting
			(front yes)
			(back yes)
		)
		(net "GPS1_TP2")
	)
	(segment
		(start 155.988595 112.8286)
		(end 155.988595 79.36163)
		(width 0.2032)
		(layer "B.Cu")
		(net "GPS1_TP2")
	)
	(segment
		(start 118.988595 67.0786)
		(end 120.488595 65.5786)
		(width 0.2032)
		(layer "B.Cu")
		(net "GPS1_TP2")
	)
	(segment
		(start 153.238595 115.5786)
		(end 155.988595 112.8286)
		(width 0.2032)
		(layer "B.Cu")
		(net "GPS1_TP2")
	)
	(segment
		(start 118.988595 68.5786)
		(end 118.988595 67.0786)
		(width 0.2032)
		(layer "B.Cu")
		(net "GPS1_TP2")
	)
	(segment
		(start 142.205565 65.5786)
		(end 155.988595 79.36163)
		(width 0.2032)
		(layer "B.Cu")
		(net "GPS1_TP2")
	)
	(segment
		(start 120.488595 65.5786)
		(end 142.205565 65.5786)
		(width 0.2032)
		(layer "B.Cu")
		(net "GPS1_TP2")
	)
	(segment
		(start 125.488595 72.5786)
		(end 127.488595 72.5786)
		(width 0.2032)
		(layer "F.Cu")
		(net "GPS1_RST")
	)
	(segment
		(start 153.230955 112.57096)
		(end 153.238595 112.5786)
		(width 0.2032)
		(layer "F.Cu")
		(net "GPS1_RST")
	)
	(segment
		(start 151.233535 112.57096)
		(end 153.230955 112.57096)
		(width 0.2032)
		(layer "F.Cu")
		(net "GPS1_RST")
	)
	(segment
		(start 151.225895 112.56332)
		(end 151.233535 112.57096)
		(width 0.2032)
		(layer "F.Cu")
		(net "GPS1_RST")
	)
	(via
		(at 153.238595 112.5786)
		(size 0.4064)
		(drill 0.2032)
		(layers "F.Cu" "B.Cu")
		(tenting
			(front yes)
			(back yes)
		)
		(net "GPS1_RST")
	)
	(via
		(at 127.488595 72.5786)
		(size 0.4064)
		(drill 0.2032)
		(layers "F.Cu" "B.Cu")
		(tenting
			(front yes)
			(back yes)
		)
		(net "GPS1_RST")
	)
	(segment
		(start 153.238595 112.5786)
		(end 155.238595 110.5786)
		(width 0.2032)
		(layer "B.Cu")
		(net "GPS1_RST")
	)
	(segment
		(start 127.488595 72.5786)
		(end 148.271625 72.5786)
		(width 0.2032)
		(layer "B.Cu")
		(net "GPS1_RST")
	)
	(segment
		(start 148.271625 72.5786)
		(end 155.238595 79.54557)
		(width 0.2032)
		(layer "B.Cu")
		(net "GPS1_RST")
	)
	(segment
		(start 155.238595 110.5786)
		(end 155.238595 79.54557)
		(width 0.2032)
		(layer "B.Cu")
		(net "GPS1_RST")
	)
	(segment
		(start 73.438595 137.4756)
		(end 73.438595 131.9286)
		(width 0.2032)
		(layer "F.Cu")
		(net "NetAN4_1")
	)
	(segment
		(start 73.349595 137.5646)
		(end 73.363595 137.5786)
		(width 0.2032)
		(layer "F.Cu")
		(net "NetAN4_1")
	)
	(segment
		(start 73.363595 137.5786)
		(end 73.513595 137.4286)
		(width 0.2032)
		(layer "F.Cu")
		(net "NetAN4_1")
	)
	(segment
		(start 83.138595 137.4286)
		(end 83.238595 137.5286)
		(width 0.2032)
		(layer "F.Cu")
		(net "NetAN4_1")
	)
	(segment
		(start 73.513595 137.4286)
		(end 83.138595 137.4286)
		(width 0.2032)
		(layer "F.Cu")
		(net "NetAN4_1")
	)
	(segment
		(start 63.564595 137.5646)
		(end 73.349595 137.5646)
		(width 0.2032)
		(layer "F.Cu")
		(net "NetAN4_1")
	)
	(segment
		(start 73.349595 137.5646)
		(end 73.438595 137.4756)
		(width 0.2032)
		(layer "F.Cu")
		(net "NetAN4_1")
	)
	(segment
		(start 73.363595 129.6536)
		(end 73.363595 124.1786)
		(width 0.2032)
		(layer "F.Cu")
		(net "NetAN3_1")
	)
	(segment
		(start 63.564595 124.2296)
		(end 73.312595 124.2296)
		(width 0.2032)
		(layer "F.Cu")
		(net "NetAN3_1")
	)
	(segment
		(start 83.138595 124.1786)
		(end 83.238595 124.2786)
		(width 0.2032)
		(layer "F.Cu")
		(net "NetAN3_1")
	)
	(segment
		(start 73.312595 124.2296)
		(end 73.363595 124.1786)
		(width 0.2032)
		(layer "F.Cu")
		(net "NetAN3_1")
	)
	(segment
		(start 73.363595 124.1786)
		(end 83.138595 124.1786)
		(width 0.2032)
		(layer "F.Cu")
		(net "NetAN3_1")
	)
	(segment
		(start 73.363595 129.6536)
		(end 73.438595 129.7286)
		(width 0.2032)
		(layer "F.Cu")
		(net "NetAN3_1")
	)
	(segment
		(start 73.413595 110.9286)
		(end 73.488595 110.8536)
		(width 0.2032)
		(layer "F.Cu")
		(net "NetAN2_1")
	)
	(segment
		(start 73.363595 110.9786)
		(end 73.413595 110.9286)
		(width 0.2032)
		(layer "F.Cu")
		(net "NetAN2_1")
	)
	(segment
		(start 73.488595 110.8536)
		(end 73.488595 105.0286)
		(width 0.2032)
		(layer "F.Cu")
		(net "NetAN2_1")
	)
	(segment
		(start 73.279595 110.8946)
		(end 73.363595 110.9786)
		(width 0.2032)
		(layer "F.Cu")
		(net "NetAN2_1")
	)
	(segment
		(start 73.413595 110.9286)
		(end 83.088595 110.9286)
		(width 0.2032)
		(layer "F.Cu")
		(net "NetAN2_1")
	)
	(segment
		(start 63.564595 110.8946)
		(end 73.279595 110.8946)
		(width 0.2032)
		(layer "F.Cu")
		(net "NetAN2_1")
	)
	(segment
		(start 83.088595 110.9286)
		(end 83.238595 110.7786)
		(width 0.2032)
		(layer "F.Cu")
		(net "NetAN2_1")
	)
	(segment
		(start 73.363595 97.5786)
		(end 73.488595 97.7036)
		(width 0.2032)
		(layer "F.Cu")
		(net "NetAN1_1")
	)
	(segment
		(start 73.488595 102.8286)
		(end 73.488595 97.7036)
		(width 0.2032)
		(layer "F.Cu")
		(net "NetAN1_1")
	)
	(segment
		(start 63.564595 97.5596)
		(end 73.344595 97.5596)
		(width 0.2032)
		(layer "F.Cu")
		(net "NetAN1_1")
	)
	(segment
		(start 73.344595 97.5596)
		(end 73.363595 97.5786)
		(width 0.2032)
		(layer "F.Cu")
		(net "NetAN1_1")
	)
	(segment
		(start 73.363595 97.5786)
		(end 83.188595 97.5786)
		(width 0.2032)
		(layer "F.Cu")
		(net "NetAN1_1")
	)
	(segment
		(start 83.188595 97.5786)
		(end 83.238595 97.5286)
		(width 0.2032)
		(layer "F.Cu")
		(net "NetAN1_1")
	)
	(segment
		(start 145.798425 125.06343)
		(end 147.176125 125.06343)
		(width 0.2032)
		(layer "F.Cu")
		(net "LED4")
	)
	(segment
		(start 90.085395 58.57379)
		(end 90.085395 57.9906)
		(width 0.2032)
		(layer "F.Cu")
		(net "LED4")
	)
	(segment
		(start 145.138595 124.4036)
		(end 145.798425 125.06343)
		(width 0.2032)
		(layer "F.Cu")
		(net "LED4")
	)
	(via
		(at 90.085395 58.57379)
		(size 0.4064)
		(drill 0.2032)
		(layers "F.Cu" "B.Cu")
		(tenting
			(front yes)
			(back yes)
		)
		(net "LED4")
	)
	(via
		(at 145.138595 124.4036)
		(size 0.4064)
		(drill 0.2032)
		(layers "F.Cu" "B.Cu")
		(tenting
			(front yes)
			(back yes)
		)
		(net "LED4")
	)
	(segment
		(start 90.085395 78.58342)
		(end 105.506295 94.00433)
		(width 0.2032)
		(layer "B.Cu")
		(net "LED4")
	)
	(segment
		(start 105.506295 97.5713)
		(end 105.506295 94.00433)
		(width 0.2032)
		(layer "B.Cu")
		(net "LED4")
	)
	(segment
		(start 105.506295 97.5713)
		(end 105.563595 97.6286)
		(width 0.2032)
		(layer "B.Cu")
		(net "LED4")
	)
	(segment
		(start 128.780565 124.4036)
		(end 145.138595 124.4036)
		(width 0.2032)
		(layer "B.Cu")
		(net "LED4")
	)
	(segment
		(start 90.085395 78.58342)
		(end 90.085395 58.57379)
		(width 0.2032)
		(layer "B.Cu")
		(net "LED4")
	)
	(segment
		(start 105.563595 101.18663)
		(end 128.780565 124.4036)
		(width 0.2032)
		(layer "B.Cu")
		(net "LED4")
	)
	(segment
		(start 105.563595 101.18663)
		(end 105.563595 97.6286)
		(width 0.2032)
		(layer "B.Cu")
		(net "LED4")
	)
	(segment
		(start 84.963055 58.60766)
		(end 84.963055 57.9906)
		(width 0.2032)
		(layer "F.Cu")
		(net "LED3")
	)
	(segment
		(start 145.138595 125.2036)
		(end 145.498295 125.5633)
		(width 0.2032)
		(layer "F.Cu")
		(net "LED3")
	)
	(segment
		(start 145.498295 125.5633)
		(end 147.176125 125.5633)
		(width 0.2032)
		(layer "F.Cu")
		(net "LED3")
	)
	(via
		(at 145.138595 125.2036)
		(size 0.4064)
		(drill 0.2032)
		(layers "F.Cu" "B.Cu")
		(tenting
			(front yes)
			(back yes)
		)
		(net "LED3")
	)
	(via
		(at 84.963055 58.60766)
		(size 0.4064)
		(drill 0.2032)
		(layers "F.Cu" "B.Cu")
		(tenting
			(front yes)
			(back yes)
		)
		(net "LED3")
	)
	(segment
		(start 105.176095 101.2661)
		(end 105.176095 94.1411)
		(width 0.2032)
		(layer "B.Cu")
		(net "LED3")
	)
	(segment
		(start 84.963055 73.92806)
		(end 84.963055 58.60766)
		(width 0.2032)
		(layer "B.Cu")
		(net "LED3")
	)
	(segment
		(start 84.963055 73.92806)
		(end 105.176095 94.1411)
		(width 0.2032)
		(layer "B.Cu")
		(net "LED3")
	)
	(segment
		(start 105.176095 101.2661)
		(end 129.113595 125.2036)
		(width 0.2032)
		(layer "B.Cu")
		(net "LED3")
	)
	(segment
		(start 129.113595 125.2036)
		(end 145.138595 125.2036)
		(width 0.2032)
		(layer "B.Cu")
		(net "LED3")
	)
	(segment
		(start 104.158625 154.48357)
		(end 104.591375 154.05081)
		(width 0.508)
		(layer "F.Cu")
		(net "+12V_PCIE")
	)
	(segment
		(start 105.392115 153.77608)
		(end 105.474595 153.77608)
		(width 0.508)
		(layer "F.Cu")
		(net "+12V_PCIE")
	)
	(segment
		(start 105.117385 154.05081)
		(end 105.392115 153.77608)
		(width 0.508)
		(layer "F.Cu")
		(net "+12V_PCIE")
	)
	(segment
		(start 105.158615 157.7576)
		(end 105.158615 154.09205)
		(width 0.508)
		(layer "F.Cu")
		(net "+12V_PCIE")
	)
	(segment
		(start 105.158615 154.09205)
		(end 105.474595 153.77608)
		(width 0.508)
		(layer "F.Cu")
		(net "+12V_PCIE")
	)
	(segment
		(start 106.158615 157.7576)
		(end 106.158615 154.4601)
		(width 0.508)
		(layer "F.Cu")
		(net "+12V_PCIE")
	)
	(segment
		(start 104.158625 157.7576)
		(end 104.158625 154.48357)
		(width 0.508)
		(layer "F.Cu")
		(net "+12V_PCIE")
	)
	(segment
		(start 104.591375 154.05081)
		(end 105.117385 154.05081)
		(width 0.508)
		(layer "F.Cu")
		(net "+12V_PCIE")
	)
	(via
		(at 106.038595 153.2786)
		(size 0.4064)
		(drill 0.2032)
		(layers "F.Cu" "B.Cu")
		(tenting
			(front yes)
			(back yes)
		)
		(net "+12V_PCIE")
	)
	(via
		(at 105.038595 154.0786)
		(size 0.4064)
		(drill 0.2032)
		(layers "F.Cu" "B.Cu")
		(tenting
			(front yes)
			(back yes)
		)
		(net "+12V_PCIE")
	)
	(via
		(at 105.038595 153.2786)
		(size 0.4064)
		(drill 0.2032)
		(layers "F.Cu" "B.Cu")
		(tenting
			(front yes)
			(back yes)
		)
		(net "+12V_PCIE")
	)
	(via
		(at 105.538595 154.0786)
		(size 0.4064)
		(drill 0.2032)
		(layers "F.Cu" "B.Cu")
		(tenting
			(front yes)
			(back yes)
		)
		(net "+12V_PCIE")
	)
	(via
		(at 105.538595 153.2786)
		(size 0.4064)
		(drill 0.2032)
		(layers "F.Cu" "B.Cu")
		(tenting
			(front yes)
			(back yes)
		)
		(net "+12V_PCIE")
	)
	(via
		(at 106.038595 154.0786)
		(size 0.4064)
		(drill 0.2032)
		(layers "F.Cu" "B.Cu")
		(tenting
			(front yes)
			(back yes)
		)
		(net "+12V_PCIE")
	)
	(segment
		(start 105.158615 154.0786)
		(end 105.158615 154.03707)
		(width 0.508)
		(layer "B.Cu")
		(net "+12V_PCIE")
	)
	(segment
		(start 105.158615 154.03707)
		(end 105.474595 153.72109)
		(width 0.508)
		(layer "B.Cu")
		(net "+12V_PCIE")
	)
	(segment
		(start 106.158615 157.7576)
		(end 106.158615 154.40511)
		(width 0.508)
		(layer "B.Cu")
		(net "+12V_PCIE")
	)
	(segment
		(start 105.158615 157.7576)
		(end 105.158615 154.0786)
		(width 0.508)
		(layer "B.Cu")
		(net "+12V_PCIE")
	)
	(segment
		(start 105.474595 153.72109)
		(end 106.158615 154.40511)
		(width 0.508)
		(layer "B.Cu")
		(net "+12V_PCIE")
	)
	(segment
		(start 111.138605 153.97858)
		(end 111.438595 153.6786)
		(width 0.508)
		(layer "F.Cu")
		(net "+3.3V_PCIE")
	)
	(segment
		(start 111.438595 153.6786)
		(end 112.138595 153.6786)
		(width 0.508)
		(layer "F.Cu")
		(net "+3.3V_PCIE")
	)
	(segment
		(start 111.158605 157.7576)
		(end 111.236665 157.67954)
		(width 0.508)
		(layer "F.Cu")
		(net "+3.3V_PCIE")
	)
	(segment
		(start 111.138605 157.0786)
		(end 111.138605 153.97858)
		(width 0.508)
		(layer "F.Cu")
		(net "+3.3V_PCIE")
	)
	(via
		(at 112.138595 154.0786)
		(size 0.4064)
		(drill 0.2032)
		(layers "F.Cu" "B.Cu")
		(tenting
			(front yes)
			(back yes)
		)
		(net "+3.3V_PCIE")
	)
	(via
		(at 113.138595 154.0786)
		(size 0.4064)
		(drill 0.2032)
		(layers "F.Cu" "B.Cu")
		(tenting
			(front yes)
			(back yes)
		)
		(net "+3.3V_PCIE")
	)
	(via
		(at 113.138595 153.2786)
		(size 0.4064)
		(drill 0.2032)
		(layers "F.Cu" "B.Cu")
		(tenting
			(front yes)
			(back yes)
		)
		(net "+3.3V_PCIE")
	)
	(via
		(at 112.138595 153.2786)
		(size 0.4064)
		(drill 0.2032)
		(layers "F.Cu" "B.Cu")
		(tenting
			(front yes)
			(back yes)
		)
		(net "+3.3V_PCIE")
	)
	(via
		(at 111.238595 154.0786)
		(size 0.4064)
		(drill 0.2032)
		(layers "F.Cu" "B.Cu")
		(tenting
			(front yes)
			(back yes)
		)
		(net "+3.3V_PCIE")
	)
	(via
		(at 111.238595 153.2786)
		(size 0.4064)
		(drill 0.2032)
		(layers "F.Cu" "B.Cu")
		(tenting
			(front yes)
			(back yes)
		)
		(net "+3.3V_PCIE")
	)
	(segment
		(start 113.127535 157.72653)
		(end 113.127535 154.16754)
		(width 0.508)
		(layer "B.Cu")
		(net "+3.3V_PCIE")
	)
	(segment
		(start 113.127535 157.72653)
		(end 113.158605 157.7576)
		(width 0.508)
		(layer "B.Cu")
		(net "+3.3V_PCIE")
	)
	(segment
		(start 112.205595 153.2456)
		(end 113.127535 154.16754)
		(width 0.508)
		(layer "B.Cu")
		(net "+3.3V_PCIE")
	)
	(segment
		(start 112.138605 157.0786)
		(end 112.138605 154.07861)
		(width 0.508)
		(layer "B.Cu")
		(net "+3.3V_PCIE")
	)
	(segment
		(start 112.138595 154.0786)
		(end 112.138605 154.07861)
		(width 0.508)
		(layer "B.Cu")
		(net "+3.3V_PCIE")
	)
	(segment
		(start 111.088595 150.9786)
		(end 116.913595 145.1536)
		(width 0.2032)
		(layer "F.Cu")
		(net "PRSNT")
	)
	(segment
		(start 116.913595 145.1536)
		(end 136.088595 145.1536)
		(width 0.2032)
		(layer "F.Cu")
		(net "PRSNT")
	)
	(via
		(at 111.088595 150.9786)
		(size 0.4064)
		(drill 0.2032)
		(layers "F.Cu" "B.Cu")
		(tenting
			(front yes)
			(back yes)
		)
		(net "PRSNT")
	)
	(segment
		(start 106.057545 150.9786)
		(end 111.088595 150.9786)
		(width 0.2032)
		(layer "B.Cu")
		(net "PRSNT")
	)
	(segment
		(start 104.283795 157.13713)
		(end 104.283795 152.75235)
		(width 0.2032)
		(layer "B.Cu")
		(net "PRSNT")
	)
	(segment
		(start 104.283795 152.75235)
		(end 106.057545 150.9786)
		(width 0.2032)
		(layer "B.Cu")
		(net "PRSNT")
	)
	(segment
		(start 104.158625 157.2623)
		(end 104.283795 157.13713)
		(width 0.2032)
		(layer "B.Cu")
		(net "PRSNT")
	)
	(segment
		(start 129.698325 135.66887)
		(end 129.698325 134.20545)
		(width 0.127)
		(layer "F.Cu")
		(net "PCIE_TX3_N")
	)
	(segment
		(start 129.698325 134.20545)
		(end 129.706195 134.21332)
		(width 0.127)
		(layer "F.Cu")
		(net "PCIE_TX3_N")
	)
	(via
		(at 135.188595 150.2786)
		(size 0.4064)
		(drill 0.2032)
		(layers "F.Cu" "B.Cu")
		(tenting
			(front yes)
			(back yes)
		)
		(net "PCIE_TX3_N")
	)
	(via
		(at 129.588595 135.7786)
		(size 0.4064)
		(drill 0.2032)
		(layers "F.Cu" "B.Cu")
		(tenting
			(front yes)
			(back yes)
		)
		(net "PCIE_TX3_N")
	)
	(arc
		(start 129.698325 135.66887)
		(mid 129.666186 135.746461)
		(end 129.588595 135.7786)
		(width 0.127)
		(layer "F.Cu")
		(net "PCIE_TX3_N")
	)
	(segment
		(start 135.188595 151.3546)
		(end 135.188595 150.2786)
		(width 0.127)
		(layer "B.Cu")
		(net "PCIE_TX3_N")
	)
	(segment
		(start 135.188595 151.3546)
		(end 135.192595 151.3586)
		(width 0.127)
		(layer "B.Cu")
		(net "PCIE_TX3_N")
	)
	(segment
		(start 133.510195 150.42592)
		(end 133.519825 150.43523)
		(width 0.127)
		(layer "In3.Cu")
		(net "PCIE_TX3_N")
	)
	(segment
		(start 133.519825 150.43523)
		(end 133.519825 150.43524)
		(width 0.127)
		(layer "In3.Cu")
		(net "PCIE_TX3_N")
	)
	(segment
		(start 134.293785 150.64667)
		(end 134.293785 150.64667)
		(width 0.127)
		(layer "In3.Cu")
		(net "PCIE_TX3_N")
	)
	(segment
		(start 129.588595 135.78239)
		(end 129.588595 135.7786)
		(width 0.127)
		(layer "In3.Cu")
		(net "PCIE_TX3_N")
	)
	(segment
		(start 134.275165 150.64861)
		(end 134.275165 150.64861)
		(width 0.127)
		(layer "In3.Cu")
		(net "PCIE_TX3_N")
	)
	(segment
		(start 133.507015 150.42273)
		(end 133.507015 150.42273)
		(width 0.127)
		(layer "In3.Cu")
		(net "PCIE_TX3_N")
	)
	(segment
		(start 129.588595 135.78239)
		(end 129.625185 135.81898)
		(width 0.127)
		(layer "In3.Cu")
		(net "PCIE_TX3_N")
	)
	(segment
		(start 129.972615 136.65774)
		(end 132.044645 138.72978)
		(width 0.127)
		(layer "In3.Cu")
		(net "PCIE_TX3_N")
	)
	(segment
		(start 132.788595 148.64002)
		(end 132.788595 140.52583)
		(width 0.127)
		(layer "In3.Cu")
		(net "PCIE_TX3_N")
	)
	(arc
		(start 133.507016 150.42273)
		(mid 132.974072 149.60139)
		(end 132.788599 148.640023)
		(width 0.127)
		(layer "In3.Cu")
		(net "PCIE_TX3_N")
	)
	(arc
		(start 129.625183 135.818982)
		(mid 129.753749 136.011394)
		(end 129.798895 136.23836)
		(width 0.127)
		(layer "In3.Cu")
		(net "PCIE_TX3_N")
	)
	(arc
		(start 134.030654 150.629214)
		(mid 133.772087 150.560395)
		(end 133.531788 150.44271)
		(width 0.127)
		(layer "In3.Cu")
		(net "PCIE_TX3_N")
	)
	(arc
		(start 133.531788 150.44271)
		(mid 133.525797 150.43899)
		(end 133.519825 150.43524)
		(width 0.127)
		(layer "In3.Cu")
		(net "PCIE_TX3_N")
	)
	(arc
		(start 133.510196 150.425916)
		(mid 133.50859 150.424335)
		(end 133.507013 150.422726)
		(width 0.127)
		(layer "In3.Cu")
		(net "PCIE_TX3_N")
	)
	(arc
		(start 129.97261 136.657745)
		(mid 129.844042 136.46533)
		(end 129.798895 136.23836)
		(width 0.127)
		(layer "In3.Cu")
		(net "PCIE_TX3_N")
	)
	(arc
		(start 134.030659 150.629212)
		(mid 134.039841 150.631067)
		(end 134.048861 150.633594)
		(width 0.127)
		(layer "In3.Cu")
		(net "PCIE_TX3_N")
	)
	(arc
		(start 134.275164 150.648606)
		(mid 134.28444 150.647293)
		(end 134.293787 150.646667)
		(width 0.127)
		(layer "In3.Cu")
		(net "PCIE_TX3_N")
	)
	(arc
		(start 135.18859 150.278611)
		(mid 134.774702 150.544116)
		(end 134.293788 150.646673)
		(width 0.127)
		(layer "In3.Cu")
		(net "PCIE_TX3_N")
	)
	(arc
		(start 134.275166 150.648609)
		(mid 134.161092 150.654959)
		(end 134.048857 150.633592)
		(width 0.127)
		(layer "In3.Cu")
		(net "PCIE_TX3_N")
	)
	(arc
		(start 132.044647 138.72978)
		(mid 132.595249 139.553815)
		(end 132.788595 140.52583)
		(width 0.127)
		(layer "In3.Cu")
		(net "PCIE_TX3_N")
	)
	(segment
		(start 130.198445 135.68845)
		(end 130.198445 134.20545)
		(width 0.127)
		(layer "F.Cu")
		(net "PCIE_TX3_P")
	)
	(via
		(at 134.192205 150.18609)
		(size 0.4064)
		(drill 0.2032)
		(layers "F.Cu" "B.Cu")
		(tenting
			(front yes)
			(back yes)
		)
		(net "PCIE_TX3_P")
	)
	(via
		(at 130.288595 135.7786)
		(size 0.4064)
		(drill 0.2032)
		(layers "F.Cu" "B.Cu")
		(tenting
			(front yes)
			(back yes)
		)
		(net "PCIE_TX3_P")
	)
	(arc
		(start 130.288595 135.7786)
		(mid 130.224849 135.752196)
		(end 130.198445 135.68845)
		(width 0.127)
		(layer "F.Cu")
		(net "PCIE_TX3_P")
	)
	(segment
		(start 134.191905 150.18639)
		(end 134.192205 150.18609)
		(width 0.127)
		(layer "B.Cu")
		(net "PCIE_TX3_P")
	)
	(segment
		(start 134.188595 151.32962)
		(end 134.188595 150.21614)
		(width 0.127)
		(layer "B.Cu")
		(net "PCIE_TX3_P")
	)
	(segment
		(start 134.190585 150.19377)
		(end 134.191905 150.18639)
		(width 0.127)
		(layer "B.Cu")
		(net "PCIE_TX3_P")
	)
	(arc
		(start 134.188605 151.32962)
		(mid 134.185486 151.345302)
		(end 134.176602 151.358597)
		(width 0.127)
		(layer "B.Cu")
		(net "PCIE_TX3_P")
	)
	(arc
		(start 134.188595 150.21614)
		(mid 134.189092 150.20491)
		(end 134.190581 150.193768)
		(width 0.127)
		(layer "B.Cu")
		(net "PCIE_TX3_P")
	)
	(segment
		(start 130.288595 135.7824)
		(end 130.288595 135.7786)
		(width 0.127)
		(layer "In3.Cu")
		(net "PCIE_TX3_P")
	)
	(segment
		(start 133.090925 147.98296)
		(end 133.114295 148.04767)
		(width 0.127)
		(layer "In3.Cu")
		(net "PCIE_TX3_P")
	)
	(segment
		(start 133.843785 149.31647)
		(end 133.843815 149.31647)
		(width 0.127)
		(layer "In3.Cu")
		(net "PCIE_TX3_P")
	)
	(segment
		(start 130.211095 135.8599)
		(end 130.288595 135.7824)
		(width 0.127)
		(layer "In3.Cu")
		(net "PCIE_TX3_P")
	)
	(segment
		(start 133.664615 149.57167)
		(end 133.664615 149.57167)
		(width 0.127)
		(layer "In3.Cu")
		(net "PCIE_TX3_P")
	)
	(segment
		(start 130.211095 136.5011)
		(end 132.588595 138.8786)
		(width 0.127)
		(layer "In3.Cu")
		(net "PCIE_TX3_P")
	)
	(segment
		(start 133.297275 148.55447)
		(end 133.548565 148.55447)
		(width 0.127)
		(layer "In3.Cu")
		(net "PCIE_TX3_P")
	)
	(segment
		(start 133.114295 148.04767)
		(end 133.114295 148.04767)
		(width 0.127)
		(layer "In3.Cu")
		(net "PCIE_TX3_P")
	)
	(segment
		(start 133.293475 148.17347)
		(end 133.548565 148.17347)
		(width 0.127)
		(layer "In3.Cu")
		(net "PCIE_TX3_P")
	)
	(segment
		(start 133.067995 147.91946)
		(end 133.090925 147.98296)
		(width 0.127)
		(layer "In3.Cu")
		(net "PCIE_TX3_P")
	)
	(segment
		(start 133.746375 149.79808)
		(end 134.069625 150.10465)
		(width 0.127)
		(layer "In3.Cu")
		(net "PCIE_TX3_P")
	)
	(segment
		(start 134.192195 150.1861)
		(end 134.192205 150.18609)
		(width 0.127)
		(layer "In3.Cu")
		(net "PCIE_TX3_P")
	)
	(segment
		(start 133.664615 149.57167)
		(end 133.746375 149.79808)
		(width 0.127)
		(layer "In3.Cu")
		(net "PCIE_TX3_P")
	)
	(segment
		(start 133.297275 148.93547)
		(end 133.843815 148.93547)
		(width 0.127)
		(layer "In3.Cu")
		(net "PCIE_TX3_P")
	)
	(segment
		(start 133.067995 147.91946)
		(end 133.067995 140.03598)
		(width 0.127)
		(layer "In3.Cu")
		(net "PCIE_TX3_P")
	)
	(arc
		(start 134.1922 150.186098)
		(mid 134.177643 150.1772)
		(end 134.163174 150.168158)
		(width 0.127)
		(layer "In3.Cu")
		(net "PCIE_TX3_P")
	)
	(arc
		(start 133.293475 148.17347)
		(mid 133.184011 148.13888)
		(end 133.114299 148.04767)
		(width 0.127)
		(layer "In3.Cu")
		(net "PCIE_TX3_P")
	)
	(arc
		(start 133.548565 148.17347)
		(mid 133.739065 148.36397)
		(end 133.548565 148.55447)
		(width 0.127)
		(layer "In3.Cu")
		(net "PCIE_TX3_P")
	)
	(arc
		(start 133.66461 149.571673)
		(mid 133.687875 149.397507)
		(end 133.843785 149.31647)
		(width 0.127)
		(layer "In3.Cu")
		(net "PCIE_TX3_P")
	)
	(arc
		(start 133.843815 148.93547)
		(mid 134.034315 149.12597)
		(end 133.843815 149.31647)
		(width 0.127)
		(layer "In3.Cu")
		(net "PCIE_TX3_P")
	)
	(arc
		(start 133.297275 148.93547)
		(mid 133.106775 148.74497)
		(end 133.297275 148.55447)
		(width 0.127)
		(layer "In3.Cu")
		(net "PCIE_TX3_P")
	)
	(arc
		(start 132.588593 138.878598)
		(mid 132.943402 139.40961)
		(end 133.067995 140.03598)
		(width 0.127)
		(layer "In3.Cu")
		(net "PCIE_TX3_P")
	)
	(arc
		(start 130.078305 136.1805)
		(mid 130.112817 136.006996)
		(end 130.211099 135.859906)
		(width 0.127)
		(layer "In3.Cu")
		(net "PCIE_TX3_P")
	)
	(arc
		(start 130.211093 136.501102)
		(mid 130.112808 136.354009)
		(end 130.078295 136.1805)
		(width 0.127)
		(layer "In3.Cu")
		(net "PCIE_TX3_P")
	)
	(arc
		(start 134.163174 150.168157)
		(mid 134.115879 150.137175)
		(end 134.069626 150.104657)
		(width 0.127)
		(layer "In3.Cu")
		(net "PCIE_TX3_P")
	)
	(segment
		(start 131.198445 140.35482)
		(end 131.198445 138.25523)
		(width 0.127)
		(layer "F.Cu")
		(net "PCIE_TX2_N")
	)
	(via
		(at 130.988595 150.2786)
		(size 0.4064)
		(drill 0.2032)
		(layers "F.Cu" "B.Cu")
		(tenting
			(front yes)
			(back yes)
		)
		(net "PCIE_TX2_N")
	)
	(via
		(at 131.188595 140.3786)
		(size 0.4064)
		(drill 0.2032)
		(layers "F.Cu" "B.Cu")
		(tenting
			(front yes)
			(back yes)
		)
		(net "PCIE_TX2_N")
	)
	(arc
		(start 131.198445 140.35482)
		(mid 131.195885 140.36769)
		(end 131.188595 140.3786)
		(width 0.127)
		(layer "F.Cu")
		(net "PCIE_TX2_N")
	)
	(segment
		(start 130.988595 151.32721)
		(end 130.988595 150.2786)
		(width 0.127)
		(layer "B.Cu")
		(net "PCIE_TX2_N")
	)
	(arc
		(start 131.001594 151.358591)
		(mid 130.991974 151.344193)
		(end 130.988596 151.32721)
		(width 0.127)
		(layer "B.Cu")
		(net "PCIE_TX2_N")
	)
	(segment
		(start 131.448895 148.0657)
		(end 131.448895 141.00702)
		(width 0.127)
		(layer "In3.Cu")
		(net "PCIE_TX2_N")
	)
	(segment
		(start 129.912215 149.65497)
		(end 131.411555 148.15566)
		(width 0.127)
		(layer "In3.Cu")
		(net "PCIE_TX2_N")
	)
	(segment
		(start 131.411555 148.15566)
		(end 131.411555 148.15565)
		(width 0.127)
		(layer "In3.Cu")
		(net "PCIE_TX2_N")
	)
	(segment
		(start 129.911655 149.65553)
		(end 129.912215 149.65497)
		(width 0.127)
		(layer "In3.Cu")
		(net "PCIE_TX2_N")
	)
	(segment
		(start 130.828195 150.33206)
		(end 130.859535 150.33206)
		(width 0.127)
		(layer "In3.Cu")
		(net "PCIE_TX2_N")
	)
	(segment
		(start 130.678295 150.50319)
		(end 130.678295 150.48196)
		(width 0.127)
		(layer "In3.Cu")
		(net "PCIE_TX2_N")
	)
	(segment
		(start 129.694105 150.22666)
		(end 129.694155 150.22751)
		(width 0.127)
		(layer "In3.Cu")
		(net "PCIE_TX2_N")
	)
	(segment
		(start 129.854845 150.58482)
		(end 129.855525 150.58549)
		(width 0.127)
		(layer "In3.Cu")
		(net "PCIE_TX2_N")
	)
	(arc
		(start 130.988596 150.278601)
		(mid 130.929382 150.318166)
		(end 130.859535 150.33206)
		(width 0.127)
		(layer "In3.Cu")
		(net "PCIE_TX2_N")
	)
	(arc
		(start 130.7222 150.375965)
		(mid 130.770831 150.343471)
		(end 130.828195 150.33206)
		(width 0.127)
		(layer "In3.Cu")
		(net "PCIE_TX2_N")
	)
	(arc
		(start 130.678295 150.48196)
		(mid 130.689705 150.424597)
		(end 130.722198 150.375966)
		(width 0.127)
		(layer "In3.Cu")
		(net "PCIE_TX2_N")
	)
	(arc
		(start 130.637641 150.596325)
		(mid 130.244404 150.747996)
		(end 129.85552 150.585491)
		(width 0.127)
		(layer "In3.Cu")
		(net "PCIE_TX2_N")
	)
	(arc
		(start 131.448895 148.0657)
		(mid 131.439189 148.114395)
		(end 131.411553 148.155647)
		(width 0.127)
		(layer "In3.Cu")
		(net "PCIE_TX2_N")
	)
	(arc
		(start 131.188602 140.378593)
		(mid 131.381254 140.666918)
		(end 131.448905 141.00702)
		(width 0.127)
		(layer "In3.Cu")
		(net "PCIE_TX2_N")
	)
	(arc
		(start 129.694098 150.226667)
		(mid 129.74261 149.918146)
		(end 129.911646 149.655534)
		(width 0.127)
		(layer "In3.Cu")
		(net "PCIE_TX2_N")
	)
	(arc
		(start 130.678295 150.50319)
		(mid 130.667688 150.553999)
		(end 130.63764 150.596322)
		(width 0.127)
		(layer "In3.Cu")
		(net "PCIE_TX2_N")
	)
	(arc
		(start 129.854837 150.584826)
		(mid 129.741837 150.420854)
		(end 129.694154 150.227509)
		(width 0.127)
		(layer "In3.Cu")
		(net "PCIE_TX2_N")
	)
	(segment
		(start 131.698315 139.6778)
		(end 131.698315 138.25523)
		(width 0.127)
		(layer "F.Cu")
		(net "PCIE_TX2_P")
	)
	(via
		(at 131.988595 140.3786)
		(size 0.4064)
		(drill 0.2032)
		(layers "F.Cu" "B.Cu")
		(tenting
			(front yes)
			(back yes)
		)
		(net "PCIE_TX2_P")
	)
	(via
		(at 130.166965 150.21916)
		(size 0.4064)
		(drill 0.2032)
		(layers "F.Cu" "B.Cu")
		(tenting
			(front yes)
			(back yes)
		)
		(net "PCIE_TX2_P")
	)
	(arc
		(start 131.988596 140.378599)
		(mid 131.773757 140.05707)
		(end 131.698316 139.6778)
		(width 0.127)
		(layer "F.Cu")
		(net "PCIE_TX2_P")
	)
	(segment
		(start 130.088595 151.30066)
		(end 130.088595 150.33546)
		(width 0.127)
		(layer "B.Cu")
		(net "PCIE_TX2_P")
	)
	(arc
		(start 130.112595 151.3586)
		(mid 130.094833 151.332017)
		(end 130.088595 151.30066)
		(width 0.127)
		(layer "B.Cu")
		(net "PCIE_TX2_P")
	)
	(arc
		(start 130.088599 150.335451)
		(mid 130.110278 150.265506)
		(end 130.16697 150.219157)
		(width 0.127)
		(layer "B.Cu")
		(net "PCIE_TX2_P")
	)
	(segment
		(start 131.034475 149.16134)
		(end 131.186625 149.31349)
		(width 0.127)
		(layer "In3.Cu")
		(net "PCIE_TX2_P")
	)
	(segment
		(start 130.078635 150.25308)
		(end 130.110135 150.22158)
		(width 0.127)
		(layer "In3.Cu")
		(net "PCIE_TX2_P")
	)
	(segment
		(start 130.051615 149.97478)
		(end 130.545665 149.48074)
		(width 0.127)
		(layer "In3.Cu")
		(net "PCIE_TX2_P")
	)
	(segment
		(start 131.623295 148.40311)
		(end 131.623305 148.40311)
		(width 0.127)
		(layer "In3.Cu")
		(net "PCIE_TX2_P")
	)
	(segment
		(start 131.988595 140.3786)
		(end 131.988595 140.3786)
		(width 0.127)
		(layer "In3.Cu")
		(net "PCIE_TX2_P")
	)
	(segment
		(start 131.623295 148.67252)
		(end 131.725445 148.77468)
		(width 0.127)
		(layer "In3.Cu")
		(net "PCIE_TX2_P")
	)
	(segment
		(start 130.161785 150.21916)
		(end 130.166965 150.21916)
		(width 0.127)
		(layer "In3.Cu")
		(net "PCIE_TX2_P")
	)
	(segment
		(start 131.728295 147.64552)
		(end 131.728295 141.00702)
		(width 0.127)
		(layer "In3.Cu")
		(net "PCIE_TX2_P")
	)
	(segment
		(start 131.303885 148.89193)
		(end 131.456035 149.04408)
		(width 0.127)
		(layer "In3.Cu")
		(net "PCIE_TX2_P")
	)
	(segment
		(start 131.728295 148.24551)
		(end 131.728295 147.64552)
		(width 0.127)
		(layer "In3.Cu")
		(net "PCIE_TX2_P")
	)
	(segment
		(start 130.031145 150.13135)
		(end 130.078635 150.25308)
		(width 0.127)
		(layer "In3.Cu")
		(net "PCIE_TX2_P")
	)
	(segment
		(start 130.815065 149.48075)
		(end 130.917215 149.5829)
		(width 0.127)
		(layer "In3.Cu")
		(net "PCIE_TX2_P")
	)
	(segment
		(start 131.623305 148.40311)
		(end 131.668205 148.35821)
		(width 0.127)
		(layer "In3.Cu")
		(net "PCIE_TX2_P")
	)
	(segment
		(start 130.023105 150.11074)
		(end 130.031145 150.13135)
		(width 0.127)
		(layer "In3.Cu")
		(net "PCIE_TX2_P")
	)
	(segment
		(start 131.668205 148.35821)
		(end 131.690545 148.33587)
		(width 0.127)
		(layer "In3.Cu")
		(net "PCIE_TX2_P")
	)
	(segment
		(start 130.023105 150.11074)
		(end 130.051615 149.97478)
		(width 0.127)
		(layer "In3.Cu")
		(net "PCIE_TX2_P")
	)
	(segment
		(start 130.110135 150.22158)
		(end 130.159365 150.22158)
		(width 0.127)
		(layer "In3.Cu")
		(net "PCIE_TX2_P")
	)
	(segment
		(start 130.159365 150.22158)
		(end 130.161785 150.21916)
		(width 0.127)
		(layer "In3.Cu")
		(net "PCIE_TX2_P")
	)
	(segment
		(start 131.668205 148.35821)
		(end 131.668205 148.35821)
		(width 0.127)
		(layer "In3.Cu")
		(net "PCIE_TX2_P")
	)
	(arc
		(start 131.728295 141.00702)
		(mid 131.795945 140.666922)
		(end 131.988594 140.378601)
		(width 0.127)
		(layer "In3.Cu")
		(net "PCIE_TX2_P")
	)
	(arc
		(start 131.690544 148.335872)
		(mid 131.690823 148.335594)
		(end 131.691102 148.335317)
		(width 0.127)
		(layer "In3.Cu")
		(net "PCIE_TX2_P")
	)
	(arc
		(start 131.186626 149.582896)
		(mid 131.051924 149.63869)
		(end 130.917222 149.582894)
		(width 0.127)
		(layer "In3.Cu")
		(net "PCIE_TX2_P")
	)
	(arc
		(start 131.728295 148.24551)
		(mid 131.718627 148.294112)
		(end 131.691095 148.335315)
		(width 0.127)
		(layer "In3.Cu")
		(net "PCIE_TX2_P")
	)
	(arc
		(start 130.545662 149.480745)
		(mid 130.680366 149.42495)
		(end 130.815069 149.480746)
		(width 0.127)
		(layer "In3.Cu")
		(net "PCIE_TX2_P")
	)
	(arc
		(start 131.034481 149.161334)
		(mid 130.978685 149.026632)
		(end 131.034478 148.891929)
		(width 0.127)
		(layer "In3.Cu")
		(net "PCIE_TX2_P")
	)
	(arc
		(start 131.725449 148.774676)
		(mid 131.781245 148.90938)
		(end 131.725449 149.044084)
		(width 0.127)
		(layer "In3.Cu")
		(net "PCIE_TX2_P")
	)
	(arc
		(start 131.725446 149.044086)
		(mid 131.590744 149.09988)
		(end 131.456042 149.044084)
		(width 0.127)
		(layer "In3.Cu")
		(net "PCIE_TX2_P")
	)
	(arc
		(start 131.623292 148.672525)
		(mid 131.567495 148.537821)
		(end 131.623291 148.403116)
		(width 0.127)
		(layer "In3.Cu")
		(net "PCIE_TX2_P")
	)
	(arc
		(start 131.034481 148.891936)
		(mid 131.169185 148.83614)
		(end 131.303889 148.891936)
		(width 0.127)
		(layer "In3.Cu")
		(net "PCIE_TX2_P")
	)
	(arc
		(start 131.186629 149.313486)
		(mid 131.242425 149.44819)
		(end 131.186629 149.582894)
		(width 0.127)
		(layer "In3.Cu")
		(net "PCIE_TX2_P")
	)
	(segment
		(start 128.198455 139.51772)
		(end 128.198455 138.25523)
		(width 0.127)
		(layer "F.Cu")
		(net "PCIE_TX1_N")
	)
	(segment
		(start 127.888595 140.3786)
		(end 127.888595 140.26658)
		(width 0.127)
		(layer "F.Cu")
		(net "PCIE_TX1_N")
	)
	(segment
		(start 127.888595 140.26578)
		(end 127.888595 140.26658)
		(width 0.127)
		(layer "F.Cu")
		(net "PCIE_TX1_N")
	)
	(via
		(at 127.888595 140.3786)
		(size 0.4064)
		(drill 0.2032)
		(layers "F.Cu" "B.Cu")
		(tenting
			(front yes)
			(back yes)
		)
		(net "PCIE_TX1_N")
	)
	(via
		(at 127.188595 150.2786)
		(size 0.4064)
		(drill 0.2032)
		(layers "F.Cu" "B.Cu")
		(tenting
			(front yes)
			(back yes)
		)
		(net "PCIE_TX1_N")
	)
	(arc
		(start 127.888595 140.26578)
		(mid 127.94137 140.000465)
		(end 128.091659 139.775542)
		(width 0.127)
		(layer "F.Cu")
		(net "PCIE_TX1_N")
	)
	(arc
		(start 128.198455 139.51772)
		(mid 128.170701 139.65725)
		(end 128.091663 139.775538)
		(width 0.127)
		(layer "F.Cu")
		(net "PCIE_TX1_N")
	)
	(segment
		(start 127.188595 151.3556)
		(end 127.188595 150.2786)
		(width 0.127)
		(layer "B.Cu")
		(net "PCIE_TX1_N")
	)
	(segment
		(start 127.188595 151.3556)
		(end 127.191595 151.3586)
		(width 0.127)
		(layer "B.Cu")
		(net "PCIE_TX1_N")
	)
	(segment
		(start 127.888595 140.3824)
		(end 127.888595 140.3786)
		(width 0.127)
		(layer "In3.Cu")
		(net "PCIE_TX1_N")
	)
	(segment
		(start 127.966695 150.2242)
		(end 127.967105 150.22366)
		(width 0.127)
		(layer "In3.Cu")
		(net "PCIE_TX1_N")
	)
	(segment
		(start 127.984215 150.19983)
		(end 128.098895 149.82947)
		(width 0.127)
		(layer "In3.Cu")
		(net "PCIE_TX1_N")
	)
	(segment
		(start 128.098895 147.21946)
		(end 128.098895 146.77495)
		(width 0.127)
		(layer "In3.Cu")
		(net "PCIE_TX1_N")
	)
	(segment
		(start 127.188595 150.27861)
		(end 127.188595 150.2786)
		(width 0.127)
		(layer "In3.Cu")
		(net "PCIE_TX1_N")
	)
	(segment
		(start 127.908375 149.31496)
		(end 127.908395 149.31496)
		(width 0.127)
		(layer "In3.Cu")
		(net "PCIE_TX1_N")
	)
	(segment
		(start 127.886855 148.55296)
		(end 127.933795 148.55296)
		(width 0.127)
		(layer "In3.Cu")
		(net "PCIE_TX1_N")
	)
	(segment
		(start 127.857135 147.40996)
		(end 127.908395 147.40996)
		(width 0.127)
		(layer "In3.Cu")
		(net "PCIE_TX1_N")
	)
	(segment
		(start 128.098895 149.82947)
		(end 128.098895 149.50546)
		(width 0.127)
		(layer "In3.Cu")
		(net "PCIE_TX1_N")
	)
	(segment
		(start 127.857135 147.79096)
		(end 127.933795 147.79096)
		(width 0.127)
		(layer "In3.Cu")
		(net "PCIE_TX1_N")
	)
	(segment
		(start 127.908375 148.93396)
		(end 127.933795 148.93396)
		(width 0.127)
		(layer "In3.Cu")
		(net "PCIE_TX1_N")
	)
	(segment
		(start 128.098895 146.77495)
		(end 128.098895 140.8901)
		(width 0.127)
		(layer "In3.Cu")
		(net "PCIE_TX1_N")
	)
	(segment
		(start 127.886855 148.17196)
		(end 127.933795 148.17196)
		(width 0.127)
		(layer "In3.Cu")
		(net "PCIE_TX1_N")
	)
	(arc
		(start 127.933795 147.79096)
		(mid 128.124295 147.98146)
		(end 127.933795 148.17196)
		(width 0.127)
		(layer "In3.Cu")
		(net "PCIE_TX1_N")
	)
	(arc
		(start 127.886855 148.55296)
		(mid 127.696355 148.36246)
		(end 127.886855 148.17196)
		(width 0.127)
		(layer "In3.Cu")
		(net "PCIE_TX1_N")
	)
	(arc
		(start 127.933653 150.263333)
		(mid 127.564351 150.42845)
		(end 127.188592 150.278605)
		(width 0.127)
		(layer "In3.Cu")
		(net "PCIE_TX1_N")
	)
	(arc
		(start 127.857135 147.79096)
		(mid 127.666635 147.60046)
		(end 127.857135 147.40996)
		(width 0.127)
		(layer "In3.Cu")
		(net "PCIE_TX1_N")
	)
	(arc
		(start 127.933795 148.55296)
		(mid 128.124295 148.74346)
		(end 127.933795 148.93396)
		(width 0.127)
		(layer "In3.Cu")
		(net "PCIE_TX1_N")
	)
	(arc
		(start 127.96669 150.224197)
		(mid 127.950654 150.244173)
		(end 127.933653 150.263334)
		(width 0.127)
		(layer "In3.Cu")
		(net "PCIE_TX1_N")
	)
	(arc
		(start 127.984214 150.199831)
		(mid 127.97579 150.211839)
		(end 127.967099 150.223656)
		(width 0.127)
		(layer "In3.Cu")
		(net "PCIE_TX1_N")
	)
	(arc
		(start 127.908375 149.31496)
		(mid 127.717875 149.12446)
		(end 127.908375 148.93396)
		(width 0.127)
		(layer "In3.Cu")
		(net "PCIE_TX1_N")
	)
	(arc
		(start 128.098895 147.21946)
		(mid 128.043099 147.354164)
		(end 127.908395 147.40996)
		(width 0.127)
		(layer "In3.Cu")
		(net "PCIE_TX1_N")
	)
	(arc
		(start 127.888595 140.38239)
		(mid 128.04424 140.615329)
		(end 128.098895 140.8901)
		(width 0.127)
		(layer "In3.Cu")
		(net "PCIE_TX1_N")
	)
	(arc
		(start 127.908395 149.31496)
		(mid 128.043099 149.370756)
		(end 128.098895 149.50546)
		(width 0.127)
		(layer "In3.Cu")
		(net "PCIE_TX1_N")
	)
	(segment
		(start 128.698325 140.11369)
		(end 128.698325 138.25523)
		(width 0.127)
		(layer "F.Cu")
		(net "PCIE_TX1_P")
	)
	(via
		(at 128.588595 140.3786)
		(size 0.4064)
		(drill 0.2032)
		(layers "F.Cu" "B.Cu")
		(tenting
			(front yes)
			(back yes)
		)
		(net "PCIE_TX1_P")
	)
	(via
		(at 126.188595 150.2786)
		(size 0.4064)
		(drill 0.2032)
		(layers "F.Cu" "B.Cu")
		(tenting
			(front yes)
			(back yes)
		)
		(net "PCIE_TX1_P")
	)
	(arc
		(start 128.698325 140.11369)
		(mid 128.669807 140.257059)
		(end 128.588595 140.3786)
		(width 0.127)
		(layer "F.Cu")
		(net "PCIE_TX1_P")
	)
	(segment
		(start 126.188595 151.32721)
		(end 126.188595 150.2786)
		(width 0.127)
		(layer "B.Cu")
		(net "PCIE_TX1_P")
	)
	(arc
		(start 126.188595 151.32721)
		(mid 126.185217 151.344193)
		(end 126.175596 151.358591)
		(width 0.127)
		(layer "B.Cu")
		(net "PCIE_TX1_P")
	)
	(segment
		(start 128.378295 149.84976)
		(end 128.378295 140.8901)
		(width 0.127)
		(layer "In3.Cu")
		(net "PCIE_TX1_P")
	)
	(segment
		(start 128.588595 140.3824)
		(end 128.588595 140.3824)
		(width 0.127)
		(layer "In3.Cu")
		(net "PCIE_TX1_P")
	)
	(segment
		(start 128.378295 149.8509)
		(end 128.378295 149.84976)
		(width 0.127)
		(layer "In3.Cu")
		(net "PCIE_TX1_P")
	)
	(segment
		(start 128.588595 140.3824)
		(end 128.588595 140.3786)
		(width 0.127)
		(layer "In3.Cu")
		(net "PCIE_TX1_P")
	)
	(segment
		(start 126.188595 150.2786)
		(end 126.344785 150.4348)
		(width 0.127)
		(layer "In3.Cu")
		(net "PCIE_TX1_P")
	)
	(segment
		(start 126.344785 150.4348)
		(end 126.344785 150.4348)
		(width 0.127)
		(layer "In3.Cu")
		(net "PCIE_TX1_P")
	)
	(arc
		(start 128.378295 140.8901)
		(mid 128.43295 140.615331)
		(end 128.588593 140.382393)
		(width 0.127)
		(layer "In3.Cu")
		(net "PCIE_TX1_P")
	)
	(arc
		(start 128.378285 149.850895)
		(mid 128.266811 150.285644)
		(end 127.959901 150.613118)
		(width 0.127)
		(layer "In3.Cu")
		(net "PCIE_TX1_P")
	)
	(arc
		(start 127.959908 150.613118)
		(mid 127.12098 150.808083)
		(end 126.344792 150.434794)
		(width 0.127)
		(layer "In3.Cu")
		(net "PCIE_TX1_P")
	)
	(segment
		(start 126.698325 135.66887)
		(end 126.698325 134.20545)
		(width 0.127)
		(layer "F.Cu")
		(net "PCIE_TX0_N")
	)
	(via
		(at 122.288595 150.2786)
		(size 0.4064)
		(drill 0.2032)
		(layers "F.Cu" "B.Cu")
		(tenting
			(front yes)
			(back yes)
		)
		(net "PCIE_TX0_N")
	)
	(via
		(at 126.588595 135.7786)
		(size 0.4064)
		(drill 0.2032)
		(layers "F.Cu" "B.Cu")
		(tenting
			(front yes)
			(back yes)
		)
		(net "PCIE_TX0_N")
	)
	(arc
		(start 126.698325 135.66887)
		(mid 126.666186 135.746461)
		(end 126.588595 135.7786)
		(width 0.127)
		(layer "F.Cu")
		(net "PCIE_TX0_N")
	)
	(segment
		(start 122.288595 151.3578)
		(end 122.288595 150.2786)
		(width 0.127)
		(layer "B.Cu")
		(net "PCIE_TX0_N")
	)
	(segment
		(start 122.288595 151.3578)
		(end 122.289395 151.3586)
		(width 0.127)
		(layer "B.Cu")
		(net "PCIE_TX0_N")
	)
	(segment
		(start 121.435795 150.66721)
		(end 121.436935 150.66721)
		(width 0.127)
		(layer "In3.Cu")
		(net "PCIE_TX0_N")
	)
	(segment
		(start 121.270595 150.66721)
		(end 121.435795 150.66721)
		(width 0.127)
		(layer "In3.Cu")
		(net "PCIE_TX0_N")
	)
	(segment
		(start 121.134975 142.03222)
		(end 121.388595 141.7786)
		(width 0.127)
		(layer "In3.Cu")
		(net "PCIE_TX0_N")
	)
	(segment
		(start 121.134005 142.03319)
		(end 121.134975 142.03222)
		(width 0.127)
		(layer "In3.Cu")
		(net "PCIE_TX0_N")
	)
	(segment
		(start 121.436935 150.66721)
		(end 121.899985 150.66721)
		(width 0.127)
		(layer "In3.Cu")
		(net "PCIE_TX0_N")
	)
	(segment
		(start 121.388595 141.7786)
		(end 126.666095 136.5011)
		(width 0.127)
		(layer "In3.Cu")
		(net "PCIE_TX0_N")
	)
	(segment
		(start 120.088595 144.55621)
		(end 120.088595 149.48522)
		(width 0.127)
		(layer "In3.Cu")
		(net "PCIE_TX0_N")
	)
	(segment
		(start 126.588595 135.7824)
		(end 126.588595 135.7786)
		(width 0.127)
		(layer "In3.Cu")
		(net "PCIE_TX0_N")
	)
	(segment
		(start 126.798895 136.1805)
		(end 126.798895 136.1805)
		(width 0.127)
		(layer "In3.Cu")
		(net "PCIE_TX0_N")
	)
	(segment
		(start 126.588595 135.7824)
		(end 126.666095 135.8599)
		(width 0.127)
		(layer "In3.Cu")
		(net "PCIE_TX0_N")
	)
	(arc
		(start 122.288595 150.2786)
		(mid 122.174774 150.553389)
		(end 121.899985 150.66721)
		(width 0.127)
		(layer "In3.Cu")
		(net "PCIE_TX0_N")
	)
	(arc
		(start 126.666107 135.859898)
		(mid 126.764392 136.006991)
		(end 126.798905 136.1805)
		(width 0.127)
		(layer "In3.Cu")
		(net "PCIE_TX0_N")
	)
	(arc
		(start 120.088595 144.556205)
		(mid 120.360443 143.190758)
		(end 121.133999 142.033192)
		(width 0.127)
		(layer "In3.Cu")
		(net "PCIE_TX0_N")
	)
	(arc
		(start 126.798895 136.1805)
		(mid 126.764383 136.354005)
		(end 126.6661 136.501095)
		(width 0.127)
		(layer "In3.Cu")
		(net "PCIE_TX0_N")
	)
	(arc
		(start 121.270598 150.66722)
		(mid 120.434799 150.321024)
		(end 120.088595 149.485228)
		(width 0.127)
		(layer "In3.Cu")
		(net "PCIE_TX0_N")
	)
	(segment
		(start 127.198455 135.68846)
		(end 127.198455 134.20545)
		(width 0.127)
		(layer "F.Cu")
		(net "PCIE_TX0_P")
	)
	(via
		(at 121.223615 150.1395)
		(size 0.4064)
		(drill 0.2032)
		(layers "F.Cu" "B.Cu")
		(tenting
			(front yes)
			(back yes)
		)
		(net "PCIE_TX0_P")
	)
	(via
		(at 127.288595 135.7786)
		(size 0.4064)
		(drill 0.2032)
		(layers "F.Cu" "B.Cu")
		(tenting
			(front yes)
			(back yes)
		)
		(net "PCIE_TX0_P")
	)
	(arc
		(start 127.288595 135.7786)
		(mid 127.224856 135.752199)
		(end 127.198455 135.68846)
		(width 0.127)
		(layer "F.Cu")
		(net "PCIE_TX0_P")
	)
	(segment
		(start 121.188595 150.29143)
		(end 121.189285 150.22501)
		(width 0.127)
		(layer "B.Cu")
		(net "PCIE_TX0_P")
	)
	(segment
		(start 121.223315 150.1398)
		(end 121.223615 150.1395)
		(width 0.127)
		(layer "B.Cu")
		(net "PCIE_TX0_P")
	)
	(segment
		(start 121.188595 151.35)
		(end 121.188595 150.29143)
		(width 0.127)
		(layer "B.Cu")
		(net "PCIE_TX0_P")
	)
	(segment
		(start 121.221995 150.14126)
		(end 121.223315 150.1398)
		(width 0.127)
		(layer "B.Cu")
		(net "PCIE_TX0_P")
	)
	(segment
		(start 121.188595 151.35)
		(end 121.197195 151.3586)
		(width 0.127)
		(layer "B.Cu")
		(net "PCIE_TX0_P")
	)
	(arc
		(start 121.189292 150.225012)
		(mid 121.197984 150.180146)
		(end 121.221995 150.141261)
		(width 0.127)
		(layer "B.Cu")
		(net "PCIE_TX0_P")
	)
	(segment
		(start 120.637315 149.92019)
		(end 120.797825 150.05714)
		(width 0.127)
		(layer "In3.Cu")
		(net "PCIE_TX0_P")
	)
	(segment
		(start 120.798565 150.05777)
		(end 120.798975 150.05813)
		(width 0.127)
		(layer "In3.Cu")
		(net "PCIE_TX0_P")
	)
	(segment
		(start 120.533095 148.68758)
		(end 120.942805 148.68758)
		(width 0.127)
		(layer "In3.Cu")
		(net "PCIE_TX0_P")
	)
	(segment
		(start 121.332545 142.22978)
		(end 121.586165 141.97617)
		(width 0.127)
		(layer "In3.Cu")
		(net "PCIE_TX0_P")
	)
	(segment
		(start 121.217365 150.1417)
		(end 121.223315 150.13979)
		(width 0.127)
		(layer "In3.Cu")
		(net "PCIE_TX0_P")
	)
	(segment
		(start 120.588595 149.7036)
		(end 120.588595 149.25908)
		(width 0.127)
		(layer "In3.Cu")
		(net "PCIE_TX0_P")
	)
	(segment
		(start 120.588595 149.8152)
		(end 120.588595 149.7036)
		(width 0.127)
		(layer "In3.Cu")
		(net "PCIE_TX0_P")
	)
	(segment
		(start 121.223315 150.13979)
		(end 121.223615 150.1395)
		(width 0.127)
		(layer "In3.Cu")
		(net "PCIE_TX0_P")
	)
	(segment
		(start 127.252005 135.81898)
		(end 127.288595 135.7824)
		(width 0.127)
		(layer "In3.Cu")
		(net "PCIE_TX0_P")
	)
	(segment
		(start 120.588595 146.3036)
		(end 120.588595 144.02583)
		(width 0.127)
		(layer "In3.Cu")
		(net "PCIE_TX0_P")
	)
	(segment
		(start 120.588595 147.73508)
		(end 120.588595 146.3036)
		(width 0.127)
		(layer "In3.Cu")
		(net "PCIE_TX0_P")
	)
	(segment
		(start 121.586165 141.97617)
		(end 126.904585 136.65774)
		(width 0.127)
		(layer "In3.Cu")
		(net "PCIE_TX0_P")
	)
	(segment
		(start 120.779095 147.92558)
		(end 120.889415 147.92558)
		(width 0.127)
		(layer "In3.Cu")
		(net "PCIE_TX0_P")
	)
	(segment
		(start 120.533095 148.30658)
		(end 120.889415 148.30658)
		(width 0.127)
		(layer "In3.Cu")
		(net "PCIE_TX0_P")
	)
	(segment
		(start 120.637165 149.92007)
		(end 120.637315 149.92019)
		(width 0.127)
		(layer "In3.Cu")
		(net "PCIE_TX0_P")
	)
	(segment
		(start 120.779095 149.06858)
		(end 120.942805 149.06858)
		(width 0.127)
		(layer "In3.Cu")
		(net "PCIE_TX0_P")
	)
	(segment
		(start 127.288595 135.7824)
		(end 127.288595 135.7786)
		(width 0.127)
		(layer "In3.Cu")
		(net "PCIE_TX0_P")
	)
	(arc
		(start 121.217369 150.141701)
		(mid 120.997298 150.154352)
		(end 120.798974 150.058129)
		(width 0.127)
		(layer "In3.Cu")
		(net "PCIE_TX0_P")
	)
	(arc
		(start 120.889415 147.92558)
		(mid 121.079915 148.11608)
		(end 120.889415 148.30658)
		(width 0.127)
		(layer "In3.Cu")
		(net "PCIE_TX0_P")
	)
	(arc
		(start 127.078295 136.23836)
		(mid 127.123441 136.011394)
		(end 127.252007 135.818982)
		(width 0.127)
		(layer "In3.Cu")
		(net "PCIE_TX0_P")
	)
	(arc
		(start 120.588595 144.02583)
		(mid 120.781941 143.053814)
		(end 121.332544 142.229779)
		(width 0.127)
		(layer "In3.Cu")
		(net "PCIE_TX0_P")
	)
	(arc
		(start 120.942805 148.68758)
		(mid 121.133305 148.87808)
		(end 120.942805 149.06858)
		(width 0.127)
		(layer "In3.Cu")
		(net "PCIE_TX0_P")
	)
	(arc
		(start 120.797822 150.057141)
		(mid 120.798193 150.057457)
		(end 120.798563 150.057774)
		(width 0.127)
		(layer "In3.Cu")
		(net "PCIE_TX0_P")
	)
	(arc
		(start 120.779095 147.92558)
		(mid 120.644391 147.869784)
		(end 120.588595 147.73508)
		(width 0.127)
		(layer "In3.Cu")
		(net "PCIE_TX0_P")
	)
	(arc
		(start 120.637171 149.920074)
		(mid 120.6011 149.873096)
		(end 120.5886 149.815202)
		(width 0.127)
		(layer "In3.Cu")
		(net "PCIE_TX0_P")
	)
	(arc
		(start 127.078295 136.23836)
		(mid 127.033148 136.46533)
		(end 126.90458 136.657745)
		(width 0.127)
		(layer "In3.Cu")
		(net "PCIE_TX0_P")
	)
	(arc
		(start 120.588595 149.25908)
		(mid 120.644391 149.124376)
		(end 120.779095 149.06858)
		(width 0.127)
		(layer "In3.Cu")
		(net "PCIE_TX0_P")
	)
	(arc
		(start 120.533095 148.68758)
		(mid 120.342595 148.49708)
		(end 120.533095 148.30658)
		(width 0.127)
		(layer "In3.Cu")
		(net "PCIE_TX0_P")
	)
	(segment
		(start 125.188595 140.3786)
		(end 125.188595 140.02002)
		(width 0.127)
		(layer "F.Cu")
		(net "PCIE_CLK_P")
	)
	(segment
		(start 125.698325 138.78942)
		(end 125.698325 138.25523)
		(width 0.127)
		(layer "F.Cu")
		(net "PCIE_CLK_P")
	)
	(via
		(at 118.188595 150.2786)
		(size 0.4064)
		(drill 0.2032)
		(layers "F.Cu" "B.Cu")
		(tenting
			(front yes)
			(back yes)
		)
		(net "PCIE_CLK_P")
	)
	(via
		(at 125.188595 140.3786)
		(size 0.4064)
		(drill 0.2032)
		(layers "F.Cu" "B.Cu")
		(tenting
			(front yes)
			(back yes)
		)
		(net "PCIE_CLK_P")
	)
	(arc
		(start 125.698335 138.78942)
		(mid 125.591849 139.324764)
		(end 125.288601 139.778606)
		(width 0.127)
		(layer "F.Cu")
		(net "PCIE_CLK_P")
	)
	(arc
		(start 125.188595 140.02002)
		(mid 125.214584 139.889364)
		(end 125.288595 139.7786)
		(width 0.127)
		(layer "F.Cu")
		(net "PCIE_CLK_P")
	)
	(segment
		(start 118.188595 151.3248)
		(end 118.188595 150.2786)
		(width 0.127)
		(layer "B.Cu")
		(net "PCIE_CLK_P")
	)
	(arc
		(start 118.188595 151.3248)
		(mid 118.184956 151.343092)
		(end 118.174595 151.3586)
		(width 0.127)
		(layer "B.Cu")
		(net "PCIE_CLK_P")
	)
	(segment
		(start 125.188595 140.3824)
		(end 125.188595 140.3824)
		(width 0.127)
		(layer "In3.Cu")
		(net "PCIE_CLK_P")
	)
	(segment
		(start 125.188595 140.3824)
		(end 125.188595 140.3786)
		(width 0.127)
		(layer "In3.Cu")
		(net "PCIE_CLK_P")
	)
	(segment
		(start 118.548895 150.48033)
		(end 118.548895 150.42247)
		(width 0.127)
		(layer "In3.Cu")
		(net "PCIE_CLK_P")
	)
	(segment
		(start 124.978295 148.71758)
		(end 124.978295 140.8901)
		(width 0.127)
		(layer "In3.Cu")
		(net "PCIE_CLK_P")
	)
	(segment
		(start 125.188595 140.3824)
		(end 125.188595 140.3824)
		(width 0.127)
		(layer "In3.Cu")
		(net "PCIE_CLK_P")
	)
	(segment
		(start 120.708165 151.858)
		(end 122.889815 151.858)
		(width 0.127)
		(layer "In3.Cu")
		(net "PCIE_CLK_P")
	)
	(segment
		(start 123.085295 151.77703)
		(end 124.153495 150.70883)
		(width 0.127)
		(layer "In3.Cu")
		(net "PCIE_CLK_P")
	)
	(segment
		(start 118.627005 150.66891)
		(end 119.185295 151.2272)
		(width 0.127)
		(layer "In3.Cu")
		(net "PCIE_CLK_P")
	)
	(segment
		(start 118.229315 150.29547)
		(end 118.421895 150.29547)
		(width 0.127)
		(layer "In3.Cu")
		(net "PCIE_CLK_P")
	)
	(arc
		(start 118.511698 150.332667)
		(mid 118.539228 150.373869)
		(end 118.548896 150.42247)
		(width 0.127)
		(layer "In3.Cu")
		(net "PCIE_CLK_P")
	)
	(arc
		(start 124.978295 140.8901)
		(mid 125.03295 140.615331)
		(end 125.188593 140.382393)
		(width 0.127)
		(layer "In3.Cu")
		(net "PCIE_CLK_P")
	)
	(arc
		(start 118.229315 150.29547)
		(mid 118.207276 150.291086)
		(end 118.188593 150.278602)
		(width 0.127)
		(layer "In3.Cu")
		(net "PCIE_CLK_P")
	)
	(arc
		(start 120.708165 151.858)
		(mid 119.883991 151.694062)
		(end 119.18529 151.227205)
		(width 0.127)
		(layer "In3.Cu")
		(net "PCIE_CLK_P")
	)
	(arc
		(start 118.627007 150.668908)
		(mid 118.569196 150.582388)
		(end 118.548895 150.48033)
		(width 0.127)
		(layer "In3.Cu")
		(net "PCIE_CLK_P")
	)
	(arc
		(start 124.978305 148.71758)
		(mid 124.763945 149.79524)
		(end 124.1535 150.708835)
		(width 0.127)
		(layer "In3.Cu")
		(net "PCIE_CLK_P")
	)
	(arc
		(start 118.421895 150.29547)
		(mid 118.470496 150.305137)
		(end 118.511698 150.332667)
		(width 0.127)
		(layer "In3.Cu")
		(net "PCIE_CLK_P")
	)
	(arc
		(start 123.085295 151.77703)
		(mid 122.995608 151.836957)
		(end 122.889815 151.858)
		(width 0.127)
		(layer "In3.Cu")
		(net "PCIE_CLK_P")
	)
	(segment
		(start 124.700725 139.86646)
		(end 124.988595 139.5786)
		(width 0.127)
		(layer "F.Cu")
		(net "PCIE_CLK_N")
	)
	(segment
		(start 125.198455 139.07194)
		(end 125.198455 138.25523)
		(width 0.127)
		(layer "F.Cu")
		(net "PCIE_CLK_N")
	)
	(via
		(at 119.188595 150.2786)
		(size 0.4064)
		(drill 0.2032)
		(layers "F.Cu" "B.Cu")
		(tenting
			(front yes)
			(back yes)
		)
		(net "PCIE_CLK_N")
	)
	(via
		(at 124.488595 140.3786)
		(size 0.4064)
		(drill 0.2032)
		(layers "F.Cu" "B.Cu")
		(tenting
			(front yes)
			(back yes)
		)
		(net "PCIE_CLK_N")
	)
	(arc
		(start 125.198465 139.07194)
		(mid 125.143923 139.34614)
		(end 124.988601 139.578596)
		(width 0.127)
		(layer "F.Cu")
		(net "PCIE_CLK_N")
	)
	(arc
		(start 124.488595 140.3786)
		(mid 124.543727 140.101434)
		(end 124.700729 139.866464)
		(width 0.127)
		(layer "F.Cu")
		(net "PCIE_CLK_N")
	)
	(segment
		(start 119.188595 151.3566)
		(end 119.188595 150.2786)
		(width 0.127)
		(layer "B.Cu")
		(net "PCIE_CLK_N")
	)
	(segment
		(start 119.188595 151.3566)
		(end 119.190595 151.3586)
		(width 0.127)
		(layer "B.Cu")
		(net "PCIE_CLK_N")
	)
	(segment
		(start 120.694975 151.5739)
		(end 120.712125 151.5786)
		(width 0.127)
		(layer "In3.Cu")
		(net "PCIE_CLK_N")
	)
	(segment
		(start 120.712125 151.5786)
		(end 120.988595 151.5786)
		(width 0.127)
		(layer "In3.Cu")
		(net "PCIE_CLK_N")
	)
	(segment
		(start 124.488595 140.38239)
		(end 124.488595 140.3786)
		(width 0.127)
		(layer "In3.Cu")
		(net "PCIE_CLK_N")
	)
	(segment
		(start 120.694975 151.5739)
		(end 120.694975 151.5739)
		(width 0.127)
		(layer "In3.Cu")
		(net "PCIE_CLK_N")
	)
	(segment
		(start 120.988595 151.5786)
		(end 121.189815 151.5786)
		(width 0.127)
		(layer "In3.Cu")
		(net "PCIE_CLK_N")
	)
	(segment
		(start 121.189815 151.5786)
		(end 122.888595 151.5786)
		(width 0.127)
		(layer "In3.Cu")
		(net "PCIE_CLK_N")
	)
	(segment
		(start 120.554805 151.39017)
		(end 120.554805 151.12411)
		(width 0.127)
		(layer "In3.Cu")
		(net "PCIE_CLK_N")
	)
	(segment
		(start 118.865495 150.51227)
		(end 119.380055 151.02684)
		(width 0.127)
		(layer "In3.Cu")
		(net "PCIE_CLK_N")
	)
	(segment
		(start 119.752095 151.31562)
		(end 119.932975 151.36517)
		(width 0.127)
		(layer "In3.Cu")
		(net "PCIE_CLK_N")
	)
	(segment
		(start 118.955305 150.29547)
		(end 119.147875 150.29547)
		(width 0.127)
		(layer "In3.Cu")
		(net "PCIE_CLK_N")
	)
	(segment
		(start 120.173805 151.18144)
		(end 120.173805 151.12411)
		(width 0.127)
		(layer "In3.Cu")
		(net "PCIE_CLK_N")
	)
	(segment
		(start 118.828295 150.42247)
		(end 118.828295 150.42247)
		(width 0.127)
		(layer "In3.Cu")
		(net "PCIE_CLK_N")
	)
	(segment
		(start 122.888595 151.5786)
		(end 123.954945 150.51224)
		(width 0.127)
		(layer "In3.Cu")
		(net "PCIE_CLK_N")
	)
	(segment
		(start 124.698895 148.71619)
		(end 124.698895 140.89011)
		(width 0.127)
		(layer "In3.Cu")
		(net "PCIE_CLK_N")
	)
	(segment
		(start 119.932975 151.36517)
		(end 119.932975 151.36517)
		(width 0.127)
		(layer "In3.Cu")
		(net "PCIE_CLK_N")
	)
	(arc
		(start 118.828295 150.42247)
		(mid 118.837962 150.373873)
		(end 118.86549 150.332675)
		(width 0.127)
		(layer "In3.Cu")
		(net "PCIE_CLK_N")
	)
	(arc
		(start 119.752094 151.31562)
		(mid 119.720149 151.296269)
		(end 119.688594 151.276288)
		(width 0.127)
		(layer "In3.Cu")
		(net "PCIE_CLK_N")
	)
	(arc
		(start 120.173805 151.12411)
		(mid 120.364305 150.93361)
		(end 120.554805 151.12411)
		(width 0.127)
		(layer "In3.Cu")
		(net "PCIE_CLK_N")
	)
	(arc
		(start 120.173805 151.18144)
		(mid 120.098852 151.332897)
		(end 119.932973 151.365171)
		(width 0.127)
		(layer "In3.Cu")
		(net "PCIE_CLK_N")
	)
	(arc
		(start 119.688593 151.276288)
		(mid 119.527739 151.159709)
		(end 119.380056 151.026839)
		(width 0.127)
		(layer "In3.Cu")
		(net "PCIE_CLK_N")
	)
	(arc
		(start 120.694975 151.573901)
		(mid 120.593848 151.505717)
		(end 120.554805 151.390169)
		(width 0.127)
		(layer "In3.Cu")
		(net "PCIE_CLK_N")
	)
	(arc
		(start 124.488602 140.382393)
		(mid 124.644249 140.615336)
		(end 124.698905 140.89011)
		(width 0.127)
		(layer "In3.Cu")
		(net "PCIE_CLK_N")
	)
	(arc
		(start 118.865482 150.512273)
		(mid 118.837952 150.471071)
		(end 118.828284 150.42247)
		(width 0.127)
		(layer "In3.Cu")
		(net "PCIE_CLK_N")
	)
	(arc
		(start 118.865495 150.33267)
		(mid 118.9067 150.305138)
		(end 118.955305 150.295469)
		(width 0.127)
		(layer "In3.Cu")
		(net "PCIE_CLK_N")
	)
	(arc
		(start 124.698895 148.71619)
		(mid 124.505549 149.688206)
		(end 123.954946 150.512241)
		(width 0.127)
		(layer "In3.Cu")
		(net "PCIE_CLK_N")
	)
	(arc
		(start 119.188597 150.278602)
		(mid 119.169914 150.291086)
		(end 119.147875 150.29547)
		(width 0.127)
		(layer "In3.Cu")
		(net "PCIE_CLK_N")
	)
	(segment
		(start 95.238595 122.0786)
		(end 96.488595 122.0786)
		(width 0.2032)
		(layer "F.Cu")
		(net "PCIE_PERST")
	)
	(segment
		(start 106.476455 122.06646)
		(end 106.480505 122.07051)
		(width 0.2032)
		(layer "F.Cu")
		(net "PCIE_PERST")
	)
	(segment
		(start 103.613025 122.05892)
		(end 103.620575 122.06646)
		(width 0.2032)
		(layer "F.Cu")
		(net "PCIE_PERST")
	)
	(segment
		(start 103.620575 122.06646)
		(end 106.476455 122.06646)
		(width 0.2032)
		(layer "F.Cu")
		(net "PCIE_PERST")
	)
	(via
		(at 96.488595 122.0786)
		(size 0.4064)
		(drill 0.2032)
		(layers "F.Cu" "B.Cu")
		(tenting
			(front yes)
			(back yes)
		)
		(net "PCIE_PERST")
	)
	(via
		(at 106.480505 122.07051)
		(size 0.4064)
		(drill 0.2032)
		(layers "F.Cu" "B.Cu")
		(tenting
			(front yes)
			(back yes)
		)
		(net "PCIE_PERST")
	)
	(segment
		(start 114.138605 157.0786)
		(end 114.138605 151.22861)
		(width 0.2032)
		(layer "B.Cu")
		(net "PCIE_PERST")
	)
	(segment
		(start 114.138605 157.0786)
		(end 114.238595 156.9786)
		(width 0.2032)
		(layer "B.Cu")
		(net "PCIE_PERST")
	)
	(segment
		(start 106.480415 122.0706)
		(end 106.480505 122.07051)
		(width 0.2032)
		(layer "B.Cu")
		(net "PCIE_PERST")
	)
	(segment
		(start 110.738595 147.8286)
		(end 114.138605 151.22861)
		(width 0.2032)
		(layer "B.Cu")
		(net "PCIE_PERST")
	)
	(segment
		(start 106.480505 132.57051)
		(end 110.738595 136.8286)
		(width 0.2032)
		(layer "B.Cu")
		(net "PCIE_PERST")
	)
	(segment
		(start 110.738595 147.8286)
		(end 110.738595 136.8286)
		(width 0.2032)
		(layer "B.Cu")
		(net "PCIE_PERST")
	)
	(segment
		(start 96.488595 122.0786)
		(end 96.496595 122.0706)
		(width 0.2032)
		(layer "B.Cu")
		(net "PCIE_PERST")
	)
	(segment
		(start 106.480505 132.57051)
		(end 106.480505 122.07051)
		(width 0.2032)
		(layer "B.Cu")
		(net "PCIE_PERST")
	)
	(segment
		(start 96.496595 122.0706)
		(end 106.480415 122.0706)
		(width 0.2032)
		(layer "B.Cu")
		(net "PCIE_PERST")
	)
	(segment
		(start 133.138565 157.0786)
		(end 133.138565 153.59923)
		(width 0.127)
		(layer "F.Cu")
		(net "PCIE_RX3_N")
	)
	(segment
		(start 132.957395 157.55643)
		(end 133.158565 157.7576)
		(width 0.127)
		(layer "F.Cu")
		(net "PCIE_RX3_N")
	)
	(segment
		(start 128.198455 135.66874)
		(end 128.198455 134.20545)
		(width 0.127)
		(layer "F.Cu")
		(net "PCIE_RX3_N")
	)
	(via
		(at 133.088595 153.4786)
		(size 0.4064)
		(drill 0.2032)
		(layers "F.Cu" "B.Cu")
		(tenting
			(front yes)
			(back yes)
		)
		(net "PCIE_RX3_N")
	)
	(via
		(at 128.088595 135.7786)
		(size 0.4064)
		(drill 0.2032)
		(layers "F.Cu" "B.Cu")
		(tenting
			(front yes)
			(back yes)
		)
		(net "PCIE_RX3_N")
	)
	(arc
		(start 128.198455 135.66874)
		(mid 128.166278 135.746423)
		(end 128.088595 135.7786)
		(width 0.127)
		(layer "F.Cu")
		(net "PCIE_RX3_N")
	)
	(arc
		(start 133.088597 153.478598)
		(mid 133.125578 153.533944)
		(end 133.138564 153.59923)
		(width 0.127)
		(layer "F.Cu")
		(net "PCIE_RX3_N")
	)
	(arc
		(start 133.138565 157.0786)
		(mid 132.950578 156.797257)
		(end 132.884565 156.46539)
		(width 0.2032)
		(layer "F.Cu")
		(net "PCIE_RX3_N")
	)
	(segment
		(start 132.872285 153.4786)
		(end 133.088595 153.4786)
		(width 0.127)
		(layer "In2.Cu")
		(net "PCIE_RX3_N")
	)
	(segment
		(start 128.088595 135.7824)
		(end 128.088595 135.7786)
		(width 0.127)
		(layer "In2.Cu")
		(net "PCIE_RX3_N")
	)
	(segment
		(start 132.588595 149.93083)
		(end 132.588595 139.73544)
		(width 0.127)
		(layer "In2.Cu")
		(net "PCIE_RX3_N")
	)
	(segment
		(start 132.431465 150.40958)
		(end 132.432865 150.40863)
		(width 0.127)
		(layer "In2.Cu")
		(net "PCIE_RX3_N")
	)
	(segment
		(start 128.655315 137.54045)
		(end 129.147755 138.03289)
		(width 0.127)
		(layer "In2.Cu")
		(net "PCIE_RX3_N")
	)
	(segment
		(start 128.298895 136.67998)
		(end 128.298895 136.2901)
		(width 0.127)
		(layer "In2.Cu")
		(net "PCIE_RX3_N")
	)
	(segment
		(start 131.688595 138.858)
		(end 131.688595 138.858)
		(width 0.127)
		(layer "In2.Cu")
		(net "PCIE_RX3_N")
	)
	(segment
		(start 132.471385 150.3671)
		(end 132.471385 150.3671)
		(width 0.127)
		(layer "In2.Cu")
		(net "PCIE_RX3_N")
	)
	(segment
		(start 131.139745 138.858)
		(end 131.688595 138.858)
		(width 0.127)
		(layer "In2.Cu")
		(net "PCIE_RX3_N")
	)
	(segment
		(start 131.788595 153.56468)
		(end 131.788595 151.62382)
		(width 0.127)
		(layer "In2.Cu")
		(net "PCIE_RX3_N")
	)
	(segment
		(start 132.747365 153.57867)
		(end 132.747375 153.57867)
		(width 0.127)
		(layer "In2.Cu")
		(net "PCIE_RX3_N")
	)
	(segment
		(start 132.588595 149.93259)
		(end 132.588595 149.93083)
		(width 0.127)
		(layer "In2.Cu")
		(net "PCIE_RX3_N")
	)
	(segment
		(start 131.788595 151.62268)
		(end 131.788595 151.62382)
		(width 0.127)
		(layer "In2.Cu")
		(net "PCIE_RX3_N")
	)
	(arc
		(start 132.747362 153.578677)
		(mid 132.276863 153.965198)
		(end 131.79255 153.596132)
		(width 0.127)
		(layer "In2.Cu")
		(net "PCIE_RX3_N")
	)
	(arc
		(start 128.655314 137.540451)
		(mid 128.391525 137.145664)
		(end 128.298895 136.67998)
		(width 0.127)
		(layer "In2.Cu")
		(net "PCIE_RX3_N")
	)
	(arc
		(start 132.336273 139.126278)
		(mid 132.523018 139.405764)
		(end 132.588594 139.73544)
		(width 0.127)
		(layer "In2.Cu")
		(net "PCIE_RX3_N")
	)
	(arc
		(start 132.47139 150.367102)
		(mid 132.454472 150.390037)
		(end 132.432866 150.408623)
		(width 0.127)
		(layer "In2.Cu")
		(net "PCIE_RX3_N")
	)
	(arc
		(start 131.688595 138.858)
		(mid 132.039114 138.927723)
		(end 132.336269 139.126276)
		(width 0.127)
		(layer "In2.Cu")
		(net "PCIE_RX3_N")
	)
	(arc
		(start 131.139745 138.858)
		(mid 130.061688 138.643561)
		(end 129.147754 138.032891)
		(width 0.127)
		(layer "In2.Cu")
		(net "PCIE_RX3_N")
	)
	(arc
		(start 132.747372 153.578674)
		(mid 132.792081 153.506483)
		(end 132.872288 153.478602)
		(width 0.127)
		(layer "In2.Cu")
		(net "PCIE_RX3_N")
	)
	(arc
		(start 131.79255 153.596127)
		(mid 131.789588 153.580527)
		(end 131.788595 153.56468)
		(width 0.127)
		(layer "In2.Cu")
		(net "PCIE_RX3_N")
	)
	(arc
		(start 132.588592 149.932586)
		(mid 132.558489 150.157532)
		(end 132.471382 150.367101)
		(width 0.127)
		(layer "In2.Cu")
		(net "PCIE_RX3_N")
	)
	(arc
		(start 131.788586 151.622678)
		(mid 131.959608 150.936415)
		(end 132.431462 150.409576)
		(width 0.127)
		(layer "In2.Cu")
		(net "PCIE_RX3_N")
	)
	(arc
		(start 128.088595 135.78239)
		(mid 128.24424 136.015329)
		(end 128.298895 136.2901)
		(width 0.127)
		(layer "In2.Cu")
		(net "PCIE_RX3_N")
	)
	(segment
		(start 128.698325 135.68833)
		(end 128.698325 134.20545)
		(width 0.127)
		(layer "F.Cu")
		(net "PCIE_RX3_P")
	)
	(segment
		(start 132.158565 157.7576)
		(end 132.347795 157.56837)
		(width 0.127)
		(layer "F.Cu")
		(net "PCIE_RX3_P")
	)
	(segment
		(start 132.288155 153.47904)
		(end 132.288595 153.4786)
		(width 0.127)
		(layer "F.Cu")
		(net "PCIE_RX3_P")
	)
	(segment
		(start 132.138565 157.0786)
		(end 132.138565 157.0786)
		(width 0.127)
		(layer "F.Cu")
		(net "PCIE_RX3_P")
	)
	(segment
		(start 132.138565 157.0786)
		(end 132.138565 153.8408)
		(width 0.127)
		(layer "F.Cu")
		(net "PCIE_RX3_P")
	)
	(via
		(at 132.288155 153.47904)
		(size 0.4064)
		(drill 0.2032)
		(layers "F.Cu" "B.Cu")
		(tenting
			(front yes)
			(back yes)
		)
		(net "PCIE_RX3_P")
	)
	(via
		(at 128.788595 135.7786)
		(size 0.4064)
		(drill 0.2032)
		(layers "F.Cu" "B.Cu")
		(tenting
			(front yes)
			(back yes)
		)
		(net "PCIE_RX3_P")
	)
	(arc
		(start 132.138565 153.8408)
		(mid 132.177438 153.645064)
		(end 132.288157 153.479036)
		(width 0.127)
		(layer "F.Cu")
		(net "PCIE_RX3_P")
	)
	(arc
		(start 128.788595 135.7786)
		(mid 128.724764 135.752161)
		(end 128.698325 135.68833)
		(width 0.127)
		(layer "F.Cu")
		(net "PCIE_RX3_P")
	)
	(segment
		(start 128.788595 135.7824)
		(end 128.788595 135.7786)
		(width 0.127)
		(layer "In2.Cu")
		(net "PCIE_RX3_P")
	)
	(segment
		(start 132.125795 153.31667)
		(end 132.288155 153.47904)
		(width 0.127)
		(layer "In2.Cu")
		(net "PCIE_RX3_P")
	)
	(segment
		(start 128.578295 136.6786)
		(end 128.578295 136.2901)
		(width 0.127)
		(layer "In2.Cu")
		(net "PCIE_RX3_P")
	)
	(segment
		(start 128.853855 137.34386)
		(end 129.344645 137.83465)
		(width 0.127)
		(layer "In2.Cu")
		(net "PCIE_RX3_P")
	)
	(segment
		(start 132.830655 150.39436)
		(end 132.830655 150.39435)
		(width 0.127)
		(layer "In2.Cu")
		(net "PCIE_RX3_P")
	)
	(segment
		(start 132.088595 153.16337)
		(end 132.088595 152.78236)
		(width 0.127)
		(layer "In2.Cu")
		(net "PCIE_RX3_P")
	)
	(segment
		(start 132.756435 150.46857)
		(end 132.819935 150.40507)
		(width 0.127)
		(layer "In2.Cu")
		(net "PCIE_RX3_P")
	)
	(segment
		(start 131.140695 138.5786)
		(end 131.689815 138.5786)
		(width 0.127)
		(layer "In2.Cu")
		(net "PCIE_RX3_P")
	)
	(segment
		(start 132.819935 150.40507)
		(end 132.830655 150.39436)
		(width 0.127)
		(layer "In2.Cu")
		(net "PCIE_RX3_P")
	)
	(segment
		(start 132.417445 150.80755)
		(end 132.756435 150.46857)
		(width 0.127)
		(layer "In2.Cu")
		(net "PCIE_RX3_P")
	)
	(segment
		(start 132.867995 150.3044)
		(end 132.867995 139.3786)
		(width 0.127)
		(layer "In2.Cu")
		(net "PCIE_RX3_P")
	)
	(segment
		(start 132.233095 151.82986)
		(end 132.570775 151.82986)
		(width 0.127)
		(layer "In2.Cu")
		(net "PCIE_RX3_P")
	)
	(segment
		(start 132.279095 152.59186)
		(end 132.529805 152.59186)
		(width 0.127)
		(layer "In2.Cu")
		(net "PCIE_RX3_P")
	)
	(segment
		(start 132.532975 138.92785)
		(end 132.786165 139.18103)
		(width 0.127)
		(layer "In2.Cu")
		(net "PCIE_RX3_P")
	)
	(segment
		(start 132.380255 150.89735)
		(end 132.417445 150.80755)
		(width 0.127)
		(layer "In2.Cu")
		(net "PCIE_RX3_P")
	)
	(segment
		(start 132.380255 151.25836)
		(end 132.380255 150.89735)
		(width 0.127)
		(layer "In2.Cu")
		(net "PCIE_RX3_P")
	)
	(segment
		(start 132.233095 152.21086)
		(end 132.529805 152.21086)
		(width 0.127)
		(layer "In2.Cu")
		(net "PCIE_RX3_P")
	)
	(segment
		(start 132.088595 153.16337)
		(end 132.088595 153.22687)
		(width 0.127)
		(layer "In2.Cu")
		(net "PCIE_RX3_P")
	)
	(segment
		(start 132.125795 153.31667)
		(end 132.125795 153.31667)
		(width 0.127)
		(layer "In2.Cu")
		(net "PCIE_RX3_P")
	)
	(segment
		(start 132.570755 151.44886)
		(end 132.570775 151.44886)
		(width 0.127)
		(layer "In2.Cu")
		(net "PCIE_RX3_P")
	)
	(arc
		(start 132.088595 152.78236)
		(mid 132.144391 152.647656)
		(end 132.279095 152.59186)
		(width 0.127)
		(layer "In2.Cu")
		(net "PCIE_RX3_P")
	)
	(arc
		(start 128.578295 136.2901)
		(mid 128.63295 136.015331)
		(end 128.788593 135.782392)
		(width 0.127)
		(layer "In2.Cu")
		(net "PCIE_RX3_P")
	)
	(arc
		(start 132.786168 139.181027)
		(mid 132.846737 139.271674)
		(end 132.868005 139.3786)
		(width 0.127)
		(layer "In2.Cu")
		(net "PCIE_RX3_P")
	)
	(arc
		(start 132.125792 153.316673)
		(mid 132.098263 153.275473)
		(end 132.088594 153.226875)
		(width 0.127)
		(layer "In2.Cu")
		(net "PCIE_RX3_P")
	)
	(arc
		(start 132.233095 152.21086)
		(mid 132.042595 152.02036)
		(end 132.233095 151.82986)
		(width 0.127)
		(layer "In2.Cu")
		(net "PCIE_RX3_P")
	)
	(arc
		(start 131.689815 138.5786)
		(mid 132.146127 138.669366)
		(end 132.532969 138.927846)
		(width 0.127)
		(layer "In2.Cu")
		(net "PCIE_RX3_P")
	)
	(arc
		(start 132.529805 152.21086)
		(mid 132.720305 152.40136)
		(end 132.529805 152.59186)
		(width 0.127)
		(layer "In2.Cu")
		(net "PCIE_RX3_P")
	)
	(arc
		(start 132.867995 150.3044)
		(mid 132.858289 150.353095)
		(end 132.830653 150.394347)
		(width 0.127)
		(layer "In2.Cu")
		(net "PCIE_RX3_P")
	)
	(arc
		(start 132.570755 151.44886)
		(mid 132.436051 151.393064)
		(end 132.380255 151.25836)
		(width 0.127)
		(layer "In2.Cu")
		(net "PCIE_RX3_P")
	)
	(arc
		(start 131.140695 138.5786)
		(mid 130.168679 138.385254)
		(end 129.344644 137.834651)
		(width 0.127)
		(layer "In2.Cu")
		(net "PCIE_RX3_P")
	)
	(arc
		(start 128.853855 137.34386)
		(mid 128.649911 137.038636)
		(end 128.578295 136.6786)
		(width 0.127)
		(layer "In2.Cu")
		(net "PCIE_RX3_P")
	)
	(arc
		(start 132.570775 151.44886)
		(mid 132.761275 151.63936)
		(end 132.570775 151.82986)
		(width 0.127)
		(layer "In2.Cu")
		(net "PCIE_RX3_P")
	)
	(segment
		(start 129.698325 140.1137)
		(end 129.698325 138.25523)
		(width 0.127)
		(layer "F.Cu")
		(net "PCIE_RX2_N")
	)
	(segment
		(start 129.138575 157.0786)
		(end 129.138575 153.59925)
		(width 0.127)
		(layer "F.Cu")
		(net "PCIE_RX2_N")
	)
	(via
		(at 129.088595 153.4786)
		(size 0.4064)
		(drill 0.2032)
		(layers "F.Cu" "B.Cu")
		(tenting
			(front yes)
			(back yes)
		)
		(net "PCIE_RX2_N")
	)
	(via
		(at 129.588595 140.3786)
		(size 0.4064)
		(drill 0.2032)
		(layers "F.Cu" "B.Cu")
		(tenting
			(front yes)
			(back yes)
		)
		(net "PCIE_RX2_N")
	)
	(arc
		(start 129.088599 153.478596)
		(mid 129.125587 153.533953)
		(end 129.138576 153.59925)
		(width 0.127)
		(layer "F.Cu")
		(net "PCIE_RX2_N")
	)
	(arc
		(start 129.698325 140.1137)
		(mid 129.669808 140.257065)
		(end 129.588598 140.378603)
		(width 0.127)
		(layer "F.Cu")
		(net "PCIE_RX2_N")
	)
	(arc
		(start 129.158572 157.757603)
		(mid 128.981111 157.492014)
		(end 128.918795 157.17873)
		(width 0.127)
		(layer "F.Cu")
		(net "PCIE_RX2_N")
	)
	(arc
		(start 129.158571 157.757603)
		(mid 129.150299 157.745223)
		(end 129.147395 157.73062)
		(width 0.127)
		(layer "F.Cu")
		(net "PCIE_RX2_N")
	)
	(segment
		(start 128.018975 153.78627)
		(end 128.019665 153.78697)
		(width 0.127)
		(layer "In2.Cu")
		(net "PCIE_RX2_N")
	)
	(segment
		(start 129.798895 148.24663)
		(end 129.798895 140.89011)
		(width 0.127)
		(layer "In2.Cu")
		(net "PCIE_RX2_N")
	)
	(segment
		(start 128.872635 153.4786)
		(end 129.088595 153.4786)
		(width 0.127)
		(layer "In2.Cu")
		(net "PCIE_RX2_N")
	)
	(segment
		(start 128.031345 150.73585)
		(end 129.288595 149.47859)
		(width 0.127)
		(layer "In2.Cu")
		(net "PCIE_RX2_N")
	)
	(segment
		(start 129.588595 140.38239)
		(end 129.588595 140.3786)
		(width 0.127)
		(layer "In2.Cu")
		(net "PCIE_RX2_N")
	)
	(arc
		(start 129.798895 148.24663)
		(mid 129.666273 148.913368)
		(end 129.288596 149.478601)
		(width 0.127)
		(layer "In2.Cu")
		(net "PCIE_RX2_N")
	)
	(arc
		(start 129.588602 140.382393)
		(mid 129.744249 140.615336)
		(end 129.798905 140.89011)
		(width 0.127)
		(layer "In2.Cu")
		(net "PCIE_RX2_N")
	)
	(arc
		(start 128.018985 153.786265)
		(mid 127.560717 153.082774)
		(end 127.399766 152.258758)
		(width 0.127)
		(layer "In2.Cu")
		(net "PCIE_RX2_N")
	)
	(arc
		(start 128.747733 153.57858)
		(mid 128.792459 153.506454)
		(end 128.872628 153.478603)
		(width 0.127)
		(layer "In2.Cu")
		(net "PCIE_RX2_N")
	)
	(arc
		(start 127.399755 152.258762)
		(mid 127.564098 151.434496)
		(end 128.03134 150.735849)
		(width 0.127)
		(layer "In2.Cu")
		(net "PCIE_RX2_N")
	)
	(arc
		(start 128.747737 153.57858)
		(mid 128.445994 153.900415)
		(end 128.019664 153.786972)
		(width 0.127)
		(layer "In2.Cu")
		(net "PCIE_RX2_N")
	)
	(segment
		(start 128.305885 153.41236)
		(end 128.308325 153.40817)
		(width 0.127)
		(layer "F.Cu")
		(net "PCIE_RX2_P")
	)
	(segment
		(start 130.198445 140.16096)
		(end 130.198445 138.25523)
		(width 0.127)
		(layer "F.Cu")
		(net "PCIE_RX2_P")
	)
	(segment
		(start 128.138575 157.0786)
		(end 128.138575 153.84078)
		(width 0.127)
		(layer "F.Cu")
		(net "PCIE_RX2_P")
	)
	(segment
		(start 128.280195 153.47477)
		(end 128.296995 153.43091)
		(width 0.127)
		(layer "F.Cu")
		(net "PCIE_RX2_P")
	)
	(segment
		(start 128.308325 153.40817)
		(end 128.308625 153.40787)
		(width 0.127)
		(layer "F.Cu")
		(net "PCIE_RX2_P")
	)
	(segment
		(start 128.258785 153.51109)
		(end 128.259265 153.51052)
		(width 0.127)
		(layer "F.Cu")
		(net "PCIE_RX2_P")
	)
	(segment
		(start 128.158575 157.7576)
		(end 128.232995 157.68318)
		(width 0.127)
		(layer "F.Cu")
		(net "PCIE_RX2_P")
	)
	(segment
		(start 128.105995 157.70502)
		(end 128.158575 157.7576)
		(width 0.127)
		(layer "F.Cu")
		(net "PCIE_RX2_P")
	)
	(via
		(at 128.308625 153.40787)
		(size 0.4064)
		(drill 0.2032)
		(layers "F.Cu" "B.Cu")
		(tenting
			(front yes)
			(back yes)
		)
		(net "PCIE_RX2_P")
	)
	(via
		(at 130.288595 140.3786)
		(size 0.4064)
		(drill 0.2032)
		(layers "F.Cu" "B.Cu")
		(tenting
			(front yes)
			(back yes)
		)
		(net "PCIE_RX2_P")
	)
	(arc
		(start 130.288595 140.3786)
		(mid 130.221875 140.278746)
		(end 130.198446 140.16096)
		(width 0.127)
		(layer "F.Cu")
		(net "PCIE_RX2_P")
	)
	(arc
		(start 128.296997 153.430905)
		(mid 128.301064 153.421452)
		(end 128.305883 153.41236)
		(width 0.127)
		(layer "F.Cu")
		(net "PCIE_RX2_P")
	)
	(arc
		(start 128.138575 153.84078)
		(mid 128.169566 153.665316)
		(end 128.258789 153.511085)
		(width 0.127)
		(layer "F.Cu")
		(net "PCIE_RX2_P")
	)
	(arc
		(start 128.280193 153.474767)
		(mid 128.271197 153.4935)
		(end 128.259267 153.510515)
		(width 0.127)
		(layer "F.Cu")
		(net "PCIE_RX2_P")
	)
	(segment
		(start 128.289585 150.98878)
		(end 128.289605 150.92528)
		(width 0.127)
		(layer "In2.Cu")
		(net "PCIE_RX2_P")
	)
	(segment
		(start 128.288715 153.16517)
		(end 128.288755 153.06998)
		(width 0.127)
		(layer "In2.Cu")
		(net "PCIE_RX2_P")
	)
	(segment
		(start 128.326805 150.83552)
		(end 129.487025 149.6753)
		(width 0.127)
		(layer "In2.Cu")
		(net "PCIE_RX2_P")
	)
	(segment
		(start 127.930335 152.11741)
		(end 128.352485 152.11741)
		(width 0.127)
		(layer "In2.Cu")
		(net "PCIE_RX2_P")
	)
	(segment
		(start 128.289355 151.54598)
		(end 128.289585 150.98878)
		(width 0.127)
		(layer "In2.Cu")
		(net "PCIE_RX2_P")
	)
	(segment
		(start 127.930035 152.49841)
		(end 128.352485 152.49841)
		(width 0.127)
		(layer "In2.Cu")
		(net "PCIE_RX2_P")
	)
	(segment
		(start 130.288595 140.3824)
		(end 130.288595 140.3786)
		(width 0.127)
		(layer "In2.Cu")
		(net "PCIE_RX2_P")
	)
	(segment
		(start 128.289355 151.54598)
		(end 128.289355 151.54598)
		(width 0.127)
		(layer "In2.Cu")
		(net "PCIE_RX2_P")
	)
	(segment
		(start 128.288695 153.22867)
		(end 128.288715 153.16517)
		(width 0.127)
		(layer "In2.Cu")
		(net "PCIE_RX2_P")
	)
	(segment
		(start 127.930035 152.87941)
		(end 128.098255 152.87941)
		(width 0.127)
		(layer "In2.Cu")
		(net "PCIE_RX2_P")
	)
	(segment
		(start 128.288755 153.06998)
		(end 128.288755 153.06998)
		(width 0.127)
		(layer "In2.Cu")
		(net "PCIE_RX2_P")
	)
	(segment
		(start 128.289605 150.92528)
		(end 128.289605 150.92527)
		(width 0.127)
		(layer "In2.Cu")
		(net "PCIE_RX2_P")
	)
	(segment
		(start 128.308615 153.40787)
		(end 128.308625 153.40787)
		(width 0.127)
		(layer "In2.Cu")
		(net "PCIE_RX2_P")
	)
	(segment
		(start 128.288645 153.33945)
		(end 128.288645 153.33945)
		(width 0.127)
		(layer "In2.Cu")
		(net "PCIE_RX2_P")
	)
	(segment
		(start 128.288645 153.33945)
		(end 128.288695 153.22867)
		(width 0.127)
		(layer "In2.Cu")
		(net "PCIE_RX2_P")
	)
	(segment
		(start 130.078295 148.24785)
		(end 130.078295 140.8901)
		(width 0.127)
		(layer "In2.Cu")
		(net "PCIE_RX2_P")
	)
	(segment
		(start 127.930335 151.73641)
		(end 128.098855 151.73641)
		(width 0.127)
		(layer "In2.Cu")
		(net "PCIE_RX2_P")
	)
	(arc
		(start 128.289355 151.545986)
		(mid 128.233532 151.680641)
		(end 128.098855 151.73641)
		(width 0.127)
		(layer "In2.Cu")
		(net "PCIE_RX2_P")
	)
	(arc
		(start 127.930035 152.87941)
		(mid 127.739535 152.68891)
		(end 127.930035 152.49841)
		(width 0.127)
		(layer "In2.Cu")
		(net "PCIE_RX2_P")
	)
	(arc
		(start 127.930335 152.11741)
		(mid 127.739835 151.92691)
		(end 127.930335 151.73641)
		(width 0.127)
		(layer "In2.Cu")
		(net "PCIE_RX2_P")
	)
	(arc
		(start 130.078295 148.24785)
		(mid 129.92463 149.020377)
		(end 129.487029 149.675294)
		(width 0.127)
		(layer "In2.Cu")
		(net "PCIE_RX2_P")
	)
	(arc
		(start 130.078295 140.8901)
		(mid 130.13295 140.615331)
		(end 130.288593 140.382392)
		(width 0.127)
		(layer "In2.Cu")
		(net "PCIE_RX2_P")
	)
	(arc
		(start 128.098255 152.87941)
		(mid 128.232985 152.935232)
		(end 128.288755 153.069984)
		(width 0.127)
		(layer "In2.Cu")
		(net "PCIE_RX2_P")
	)
	(arc
		(start 128.352485 152.11741)
		(mid 128.542985 152.30791)
		(end 128.352485 152.49841)
		(width 0.127)
		(layer "In2.Cu")
		(net "PCIE_RX2_P")
	)
	(arc
		(start 128.289605 150.925272)
		(mid 128.299281 150.876697)
		(end 128.326802 150.835518)
		(width 0.127)
		(layer "In2.Cu")
		(net "PCIE_RX2_P")
	)
	(arc
		(start 128.308616 153.407864)
		(mid 128.293734 153.375088)
		(end 128.288646 153.339452)
		(width 0.127)
		(layer "In2.Cu")
		(net "PCIE_RX2_P")
	)
	(segment
		(start 126.698325 139.21369)
		(end 126.698325 138.25523)
		(width 0.127)
		(layer "F.Cu")
		(net "PCIE_RX1_N")
	)
	(segment
		(start 125.138575 157.0786)
		(end 125.138575 154.84069)
		(width 0.127)
		(layer "F.Cu")
		(net "PCIE_RX1_N")
	)
	(segment
		(start 126.542145 139.52505)
		(end 126.588595 139.4786)
		(width 0.127)
		(layer "F.Cu")
		(net "PCIE_RX1_N")
	)
	(segment
		(start 124.788595 153.99576)
		(end 124.788595 153.4786)
		(width 0.127)
		(layer "F.Cu")
		(net "PCIE_RX1_N")
	)
	(segment
		(start 126.541915 139.52528)
		(end 126.542145 139.52505)
		(width 0.127)
		(layer "F.Cu")
		(net "PCIE_RX1_N")
	)
	(via
		(at 126.188595 140.3786)
		(size 0.4064)
		(drill 0.2032)
		(layers "F.Cu" "B.Cu")
		(tenting
			(front yes)
			(back yes)
		)
		(net "PCIE_RX1_N")
	)
	(via
		(at 124.788595 153.4786)
		(size 0.4064)
		(drill 0.2032)
		(layers "F.Cu" "B.Cu")
		(tenting
			(front yes)
			(back yes)
		)
		(net "PCIE_RX1_N")
	)
	(arc
		(start 126.188585 140.3786)
		(mid 126.280408 139.916812)
		(end 126.541906 139.525278)
		(width 0.127)
		(layer "F.Cu")
		(net "PCIE_RX1_N")
	)
	(arc
		(start 124.9886 154.478595)
		(mid 125.099605 154.644726)
		(end 125.138585 154.84069)
		(width 0.127)
		(layer "F.Cu")
		(net "PCIE_RX1_N")
	)
	(arc
		(start 126.698325 139.21369)
		(mid 126.669807 139.357059)
		(end 126.588595 139.4786)
		(width 0.127)
		(layer "F.Cu")
		(net "PCIE_RX1_N")
	)
	(arc
		(start 124.988594 154.478601)
		(mid 124.840573 154.257072)
		(end 124.788595 153.99576)
		(width 0.127)
		(layer "F.Cu")
		(net "PCIE_RX1_N")
	)
	(arc
		(start 125.158578 157.757597)
		(mid 124.933746 157.421112)
		(end 124.854795 157.0242)
		(width 0.127)
		(layer "F.Cu")
		(net "PCIE_RX1_N")
	)
	(segment
		(start 124.646455 153.4786)
		(end 124.788595 153.4786)
		(width 0.127)
		(layer "In2.Cu")
		(net "PCIE_RX1_N")
	)
	(segment
		(start 124.276555 150.29604)
		(end 124.276555 150.29604)
		(width 0.127)
		(layer "In2.Cu")
		(net "PCIE_RX1_N")
	)
	(segment
		(start 124.124125 152.81799)
		(end 124.221915 152.43171)
		(width 0.127)
		(layer "In2.Cu")
		(net "PCIE_RX1_N")
	)
	(segment
		(start 124.445395 153.58878)
		(end 124.445895 153.58675)
		(width 0.127)
		(layer "In2.Cu")
		(net "PCIE_RX1_N")
	)
	(segment
		(start 123.950245 153.01027)
		(end 123.950245 153.01027)
		(width 0.127)
		(layer "In2.Cu")
		(net "PCIE_RX1_N")
	)
	(segment
		(start 124.530235 153.49702)
		(end 124.530235 153.49702)
		(width 0.127)
		(layer "In2.Cu")
		(net "PCIE_RX1_N")
	)
	(segment
		(start 124.221915 152.43171)
		(end 124.221965 152.43151)
		(width 0.127)
		(layer "In2.Cu")
		(net "PCIE_RX1_N")
	)
	(segment
		(start 124.744655 148.96642)
		(end 124.744655 148.96642)
		(width 0.127)
		(layer "In2.Cu")
		(net "PCIE_RX1_N")
	)
	(segment
		(start 126.398895 146.1162)
		(end 126.398895 140.89011)
		(width 0.127)
		(layer "In2.Cu")
		(net "PCIE_RX1_N")
	)
	(segment
		(start 126.188595 140.38239)
		(end 126.188595 140.3786)
		(width 0.127)
		(layer "In2.Cu")
		(net "PCIE_RX1_N")
	)
	(segment
		(start 125.186355 148.38084)
		(end 125.654945 147.91225)
		(width 0.127)
		(layer "In2.Cu")
		(net "PCIE_RX1_N")
	)
	(segment
		(start 124.276145 152.26971)
		(end 124.276155 150.30604)
		(width 0.127)
		(layer "In2.Cu")
		(net "PCIE_RX1_N")
	)
	(arc
		(start 126.398895 146.1162)
		(mid 126.205549 147.088216)
		(end 125.654946 147.912251)
		(width 0.127)
		(layer "In2.Cu")
		(net "PCIE_RX1_N")
	)
	(arc
		(start 124.050071 152.946823)
		(mid 124.007992 152.990877)
		(end 123.950238 153.010266)
		(width 0.127)
		(layer "In2.Cu")
		(net "PCIE_RX1_N")
	)
	(arc
		(start 124.050075 152.946824)
		(mid 124.076589 152.902833)
		(end 124.105026 152.86006)
		(width 0.127)
		(layer "In2.Cu")
		(net "PCIE_RX1_N")
	)
	(arc
		(start 124.221966 152.431508)
		(mid 124.238429 152.379301)
		(end 124.261184 152.329514)
		(width 0.127)
		(layer "In2.Cu")
		(net "PCIE_RX1_N")
	)
	(arc
		(start 124.276555 150.29604)
		(mid 124.423806 149.600674)
		(end 124.744652 148.966423)
		(width 0.127)
		(layer "In2.Cu")
		(net "PCIE_RX1_N")
	)
	(arc
		(start 126.188602 140.382393)
		(mid 126.344249 140.615336)
		(end 126.398905 140.89011)
		(width 0.127)
		(layer "In2.Cu")
		(net "PCIE_RX1_N")
	)
	(arc
		(start 124.276155 150.306039)
		(mid 124.276254 150.301034)
		(end 124.27655 150.296037)
		(width 0.127)
		(layer "In2.Cu")
		(net "PCIE_RX1_N")
	)
	(arc
		(start 124.445889 153.586754)
		(mid 124.476455 153.530982)
		(end 124.530228 153.497022)
		(width 0.127)
		(layer "In2.Cu")
		(net "PCIE_RX1_N")
	)
	(arc
		(start 124.445394 153.588785)
		(mid 123.631602 153.784152)
		(end 123.950238 153.010268)
		(width 0.127)
		(layer "In2.Cu")
		(net "PCIE_RX1_N")
	)
	(arc
		(start 124.124122 152.817986)
		(mid 124.116505 152.839899)
		(end 124.10503 152.860061)
		(width 0.127)
		(layer "In2.Cu")
		(net "PCIE_RX1_N")
	)
	(arc
		(start 124.530234 153.497017)
		(mid 124.587619 153.483233)
		(end 124.646455 153.4786)
		(width 0.127)
		(layer "In2.Cu")
		(net "PCIE_RX1_N")
	)
	(arc
		(start 124.276145 152.269713)
		(mid 124.272347 152.300537)
		(end 124.261181 152.329517)
		(width 0.127)
		(layer "In2.Cu")
		(net "PCIE_RX1_N")
	)
	(arc
		(start 124.744662 148.96641)
		(mid 124.945103 148.658233)
		(end 125.186353 148.380838)
		(width 0.127)
		(layer "In2.Cu")
		(net "PCIE_RX1_N")
	)
	(segment
		(start 124.138585 157.0786)
		(end 124.138585 153.84069)
		(width 0.127)
		(layer "F.Cu")
		(net "PCIE_RX1_P")
	)
	(segment
		(start 126.888595 140.3786)
		(end 126.888595 139.96144)
		(width 0.127)
		(layer "F.Cu")
		(net "PCIE_RX1_P")
	)
	(segment
		(start 127.198455 139.21338)
		(end 127.198455 138.25523)
		(width 0.127)
		(layer "F.Cu")
		(net "PCIE_RX1_P")
	)
	(via
		(at 123.988595 153.4786)
		(size 0.4064)
		(drill 0.2032)
		(layers "F.Cu" "B.Cu")
		(tenting
			(front yes)
			(back yes)
		)
		(net "PCIE_RX1_P")
	)
	(via
		(at 126.888595 140.3786)
		(size 0.4064)
		(drill 0.2032)
		(layers "F.Cu" "B.Cu")
		(tenting
			(front yes)
			(back yes)
		)
		(net "PCIE_RX1_P")
	)
	(arc
		(start 124.15858 157.757595)
		(mid 123.978301 157.487788)
		(end 123.914996 157.16953)
		(width 0.127)
		(layer "F.Cu")
		(net "PCIE_RX1_P")
	)
	(arc
		(start 123.9886 153.478595)
		(mid 124.099605 153.644726)
		(end 124.138585 153.84069)
		(width 0.127)
		(layer "F.Cu")
		(net "PCIE_RX1_P")
	)
	(arc
		(start 127.198455 139.21338)
		(mid 127.169904 139.356917)
		(end 127.088597 139.478602)
		(width 0.127)
		(layer "F.Cu")
		(net "PCIE_RX1_P")
	)
	(arc
		(start 126.888595 139.96144)
		(mid 126.940573 139.700128)
		(end 127.088594 139.478599)
		(width 0.127)
		(layer "F.Cu")
		(net "PCIE_RX1_P")
	)
	(segment
		(start 126.678295 146.11758)
		(end 126.678295 140.8901)
		(width 0.127)
		(layer "In2.Cu")
		(net "PCIE_RX1_P")
	)
	(segment
		(start 124.588585 151.01483)
		(end 124.588585 150.7421)
		(width 0.127)
		(layer "In2.Cu")
		(net "PCIE_RX1_P")
	)
	(segment
		(start 124.779085 151.20533)
		(end 124.937295 151.20533)
		(width 0.127)
		(layer "In2.Cu")
		(net "PCIE_RX1_P")
	)
	(segment
		(start 124.336235 153.0151)
		(end 124.468645 152.49208)
		(width 0.127)
		(layer "In2.Cu")
		(net "PCIE_RX1_P")
	)
	(segment
		(start 124.653315 152.34833)
		(end 125.029685 152.34833)
		(width 0.127)
		(layer "In2.Cu")
		(net "PCIE_RX1_P")
	)
	(segment
		(start 125.386165 148.57616)
		(end 125.386165 148.57616)
		(width 0.127)
		(layer "In2.Cu")
		(net "PCIE_RX1_P")
	)
	(segment
		(start 124.588585 150.7421)
		(end 124.588595 150.6786)
		(width 0.127)
		(layer "In2.Cu")
		(net "PCIE_RX1_P")
	)
	(segment
		(start 124.588595 150.6786)
		(end 124.588595 150.49941)
		(width 0.127)
		(layer "In2.Cu")
		(net "PCIE_RX1_P")
	)
	(segment
		(start 126.888595 140.3824)
		(end 126.888595 140.3786)
		(width 0.127)
		(layer "In2.Cu")
		(net "PCIE_RX1_P")
	)
	(segment
		(start 124.588595 150.6786)
		(end 124.588595 150.6786)
		(width 0.127)
		(layer "In2.Cu")
		(net "PCIE_RX1_P")
	)
	(segment
		(start 125.386165 148.57616)
		(end 125.853495 148.10884)
		(width 0.127)
		(layer "In2.Cu")
		(net "PCIE_RX1_P")
	)
	(segment
		(start 124.720665 151.58633)
		(end 124.937295 151.58633)
		(width 0.127)
		(layer "In2.Cu")
		(net "PCIE_RX1_P")
	)
	(segment
		(start 124.468635 152.49208)
		(end 124.468645 152.49208)
		(width 0.127)
		(layer "In2.Cu")
		(net "PCIE_RX1_P")
	)
	(segment
		(start 124.720665 151.96733)
		(end 125.029685 151.96733)
		(width 0.127)
		(layer "In2.Cu")
		(net "PCIE_RX1_P")
	)
	(arc
		(start 124.779085 151.20533)
		(mid 124.64438 151.149533)
		(end 124.588585 151.014827)
		(width 0.127)
		(layer "In2.Cu")
		(net "PCIE_RX1_P")
	)
	(arc
		(start 124.937295 151.20533)
		(mid 125.127795 151.39583)
		(end 124.937295 151.58633)
		(width 0.127)
		(layer "In2.Cu")
		(net "PCIE_RX1_P")
	)
	(arc
		(start 124.299917 153.078598)
		(mid 124.156675 153.288265)
		(end 123.988595 153.478599)
		(width 0.127)
		(layer "In2.Cu")
		(net "PCIE_RX1_P")
	)
	(arc
		(start 125.029685 151.96733)
		(mid 125.220185 152.15783)
		(end 125.029685 152.34833)
		(width 0.127)
		(layer "In2.Cu")
		(net "PCIE_RX1_P")
	)
	(arc
		(start 126.678295 140.8901)
		(mid 126.73295 140.615331)
		(end 126.888593 140.382392)
		(width 0.127)
		(layer "In2.Cu")
		(net "PCIE_RX1_P")
	)
	(arc
		(start 124.720665 151.96733)
		(mid 124.530165 151.77683)
		(end 124.720665 151.58633)
		(width 0.127)
		(layer "In2.Cu")
		(net "PCIE_RX1_P")
	)
	(arc
		(start 124.468641 152.492079)
		(mid 124.536302 152.388503)
		(end 124.653315 152.34833)
		(width 0.127)
		(layer "In2.Cu")
		(net "PCIE_RX1_P")
	)
	(arc
		(start 124.588596 150.499412)
		(mid 124.796304 149.458548)
		(end 125.386162 148.576159)
		(width 0.127)
		(layer "In2.Cu")
		(net "PCIE_RX1_P")
	)
	(arc
		(start 126.678295 146.11758)
		(mid 126.463935 147.19524)
		(end 125.85349 148.108835)
		(width 0.127)
		(layer "In2.Cu")
		(net "PCIE_RX1_P")
	)
	(arc
		(start 124.336231 153.015098)
		(mid 124.318358 153.04701)
		(end 124.299917 153.078598)
		(width 0.127)
		(layer "In2.Cu")
		(net "PCIE_RX1_P")
	)
	(segment
		(start 125.198455 135.66874)
		(end 125.198455 134.20545)
		(width 0.127)
		(layer "F.Cu")
		(net "PCIE_RX0_N")
	)
	(segment
		(start 120.138585 157.0786)
		(end 120.138585 154.56501)
		(width 0.127)
		(layer "F.Cu")
		(net "PCIE_RX0_N")
	)
	(via
		(at 120.588595 153.4786)
		(size 0.4064)
		(drill 0.2032)
		(layers "F.Cu" "B.Cu")
		(tenting
			(front yes)
			(back yes)
		)
		(net "PCIE_RX0_N")
	)
	(via
		(at 125.088595 135.7786)
		(size 0.4064)
		(drill 0.2032)
		(layers "F.Cu" "B.Cu")
		(tenting
			(front yes)
			(back yes)
		)
		(net "PCIE_RX0_N")
	)
	(arc
		(start 125.198455 135.66874)
		(mid 125.166278 135.746423)
		(end 125.088595 135.7786)
		(width 0.127)
		(layer "F.Cu")
		(net "PCIE_RX0_N")
	)
	(arc
		(start 120.138585 154.56501)
		(mid 120.255538 153.977048)
		(end 120.588592 153.478597)
		(width 0.127)
		(layer "F.Cu")
		(net "PCIE_RX0_N")
	)
	(arc
		(start 120.158589 157.757596)
		(mid 119.987332 157.501292)
		(end 119.927194 157.19896)
		(width 0.127)
		(layer "F.Cu")
		(net "PCIE_RX0_N")
	)
	(segment
		(start 123.095825 150.97137)
		(end 123.353055 150.71414)
		(width 0.127)
		(layer "In2.Cu")
		(net "PCIE_RX0_N")
	)
	(segment
		(start 122.649955 151.41724)
		(end 123.095825 150.97137)
		(width 0.127)
		(layer "In2.Cu")
		(net "PCIE_RX0_N")
	)
	(segment
		(start 123.409195 150.5786)
		(end 123.409195 140.19385)
		(width 0.127)
		(layer "In2.Cu")
		(net "PCIE_RX0_N")
	)
	(segment
		(start 120.988595 153.0786)
		(end 121.033505 153.03369)
		(width 0.127)
		(layer "In2.Cu")
		(net "PCIE_RX0_N")
	)
	(segment
		(start 121.779035 151.89337)
		(end 121.841725 151.95605)
		(width 0.127)
		(layer "In2.Cu")
		(net "PCIE_RX0_N")
	)
	(segment
		(start 121.219215 152.41117)
		(end 121.302905 152.49487)
		(width 0.127)
		(layer "In2.Cu")
		(net "PCIE_RX0_N")
	)
	(segment
		(start 120.588595 153.4786)
		(end 120.988595 153.0786)
		(width 0.127)
		(layer "In2.Cu")
		(net "PCIE_RX0_N")
	)
	(segment
		(start 120.949805 152.68058)
		(end 121.033505 152.76428)
		(width 0.127)
		(layer "In2.Cu")
		(net "PCIE_RX0_N")
	)
	(segment
		(start 125.298895 136.71619)
		(end 125.298895 136.29011)
		(width 0.127)
		(layer "In2.Cu")
		(net "PCIE_RX0_N")
	)
	(segment
		(start 122.111115 151.68663)
		(end 122.111135 151.68665)
		(width 0.127)
		(layer "In2.Cu")
		(net "PCIE_RX0_N")
	)
	(segment
		(start 121.509625 152.16277)
		(end 121.572315 152.22546)
		(width 0.127)
		(layer "In2.Cu")
		(net "PCIE_RX0_N")
	)
	(segment
		(start 122.380515 151.41722)
		(end 122.380545 151.41724)
		(width 0.127)
		(layer "In2.Cu")
		(net "PCIE_RX0_N")
	)
	(segment
		(start 123.788095 139.27909)
		(end 124.554945 138.51224)
		(width 0.127)
		(layer "In2.Cu")
		(net "PCIE_RX0_N")
	)
	(segment
		(start 123.409195 150.5786)
		(end 123.409195 150.5786)
		(width 0.127)
		(layer "In2.Cu")
		(net "PCIE_RX0_N")
	)
	(segment
		(start 125.088595 135.78239)
		(end 125.088595 135.7786)
		(width 0.127)
		(layer "In2.Cu")
		(net "PCIE_RX0_N")
	)
	(segment
		(start 122.380545 151.41725)
		(end 122.380545 151.41724)
		(width 0.127)
		(layer "In2.Cu")
		(net "PCIE_RX0_N")
	)
	(arc
		(start 125.088602 135.782393)
		(mid 125.244249 136.015336)
		(end 125.298905 136.29011)
		(width 0.127)
		(layer "In2.Cu")
		(net "PCIE_RX0_N")
	)
	(arc
		(start 122.111129 151.686646)
		(mid 122.166925 151.82135)
		(end 122.111129 151.956054)
		(width 0.127)
		(layer "In2.Cu")
		(net "PCIE_RX0_N")
	)
	(arc
		(start 122.111111 151.686624)
		(mid 122.055315 151.551922)
		(end 122.111108 151.417219)
		(width 0.127)
		(layer "In2.Cu")
		(net "PCIE_RX0_N")
	)
	(arc
		(start 122.111111 151.417216)
		(mid 122.245815 151.36142)
		(end 122.380519 151.417216)
		(width 0.127)
		(layer "In2.Cu")
		(net "PCIE_RX0_N")
	)
	(arc
		(start 125.298895 136.71619)
		(mid 125.105549 137.688206)
		(end 124.554946 138.512241)
		(width 0.127)
		(layer "In2.Cu")
		(net "PCIE_RX0_N")
	)
	(arc
		(start 121.509631 152.162774)
		(mid 121.453835 152.028072)
		(end 121.509628 151.893369)
		(width 0.127)
		(layer "In2.Cu")
		(net "PCIE_RX0_N")
	)
	(arc
		(start 120.949811 152.680584)
		(mid 120.894015 152.545882)
		(end 120.949808 152.411179)
		(width 0.127)
		(layer "In2.Cu")
		(net "PCIE_RX0_N")
	)
	(arc
		(start 120.949801 152.411176)
		(mid 121.084505 152.35538)
		(end 121.219209 152.411176)
		(width 0.127)
		(layer "In2.Cu")
		(net "PCIE_RX0_N")
	)
	(arc
		(start 123.409195 150.5786)
		(mid 123.394603 150.651957)
		(end 123.35305 150.714145)
		(width 0.127)
		(layer "In2.Cu")
		(net "PCIE_RX0_N")
	)
	(arc
		(start 121.033509 152.764286)
		(mid 121.089305 152.89899)
		(end 121.033509 153.033694)
		(width 0.127)
		(layer "In2.Cu")
		(net "PCIE_RX0_N")
	)
	(arc
		(start 123.409195 140.19385)
		(mid 123.507669 139.698788)
		(end 123.788099 139.279094)
		(width 0.127)
		(layer "In2.Cu")
		(net "PCIE_RX0_N")
	)
	(arc
		(start 121.572316 152.494866)
		(mid 121.437614 152.55066)
		(end 121.302912 152.494864)
		(width 0.127)
		(layer "In2.Cu")
		(net "PCIE_RX0_N")
	)
	(arc
		(start 121.572319 152.225466)
		(mid 121.628115 152.36017)
		(end 121.572319 152.494874)
		(width 0.127)
		(layer "In2.Cu")
		(net "PCIE_RX0_N")
	)
	(arc
		(start 122.649949 151.417244)
		(mid 122.515245 151.47304)
		(end 122.380541 151.417244)
		(width 0.127)
		(layer "In2.Cu")
		(net "PCIE_RX0_N")
	)
	(arc
		(start 121.509631 151.893366)
		(mid 121.644335 151.83757)
		(end 121.779039 151.893366)
		(width 0.127)
		(layer "In2.Cu")
		(net "PCIE_RX0_N")
	)
	(arc
		(start 122.111126 151.956056)
		(mid 121.976424 152.01185)
		(end 121.841722 151.956054)
		(width 0.127)
		(layer "In2.Cu")
		(net "PCIE_RX0_N")
	)
	(segment
		(start 119.138595 157.0786)
		(end 119.138595 155.04785)
		(width 0.127)
		(layer "F.Cu")
		(net "PCIE_RX0_P")
	)
	(segment
		(start 125.698325 135.68833)
		(end 125.698325 134.20545)
		(width 0.127)
		(layer "F.Cu")
		(net "PCIE_RX0_P")
	)
	(via
		(at 125.788595 135.7786)
		(size 0.4064)
		(drill 0.2032)
		(layers "F.Cu" "B.Cu")
		(tenting
			(front yes)
			(back yes)
		)
		(net "PCIE_RX0_P")
	)
	(via
		(at 119.788595 153.4786)
		(size 0.4064)
		(drill 0.2032)
		(layers "F.Cu" "B.Cu")
		(tenting
			(front yes)
			(back yes)
		)
		(net "PCIE_RX0_P")
	)
	(arc
		(start 125.788595 135.7786)
		(mid 125.724764 135.752161)
		(end 125.698325 135.68833)
		(width 0.127)
		(layer "F.Cu")
		(net "PCIE_RX0_P")
	)
	(arc
		(start 119.138595 155.04785)
		(mid 119.307525 154.19858)
		(end 119.788598 153.478603)
		(width 0.127)
		(layer "F.Cu")
		(net "PCIE_RX0_P")
	)
	(segment
		(start 121.056455 153.43491)
		(end 121.056455 153.43491)
		(width 0.127)
		(layer "In2.Cu")
		(net "PCIE_RX0_P")
	)
	(segment
		(start 120.004555 153.4786)
		(end 120.004555 153.4786)
		(width 0.127)
		(layer "In2.Cu")
		(net "PCIE_RX0_P")
	)
	(segment
		(start 119.788595 153.4786)
		(end 120.004555 153.4786)
		(width 0.127)
		(layer "In2.Cu")
		(net "PCIE_RX0_P")
	)
	(segment
		(start 121.092775 153.33362)
		(end 123.598685 150.82771)
		(width 0.127)
		(layer "In2.Cu")
		(net "PCIE_RX0_P")
	)
	(segment
		(start 125.788595 135.7824)
		(end 125.788595 135.7786)
		(width 0.127)
		(layer "In2.Cu")
		(net "PCIE_RX0_P")
	)
	(segment
		(start 125.788595 135.7824)
		(end 125.788595 135.7824)
		(width 0.127)
		(layer "In2.Cu")
		(net "PCIE_RX0_P")
	)
	(segment
		(start 125.578295 136.71758)
		(end 125.578295 136.2901)
		(width 0.127)
		(layer "In2.Cu")
		(net "PCIE_RX0_P")
	)
	(segment
		(start 123.986165 139.47616)
		(end 123.986165 139.47616)
		(width 0.127)
		(layer "In2.Cu")
		(net "PCIE_RX0_P")
	)
	(segment
		(start 123.986165 139.47616)
		(end 124.753495 138.70883)
		(width 0.127)
		(layer "In2.Cu")
		(net "PCIE_RX0_P")
	)
	(segment
		(start 123.688595 150.64871)
		(end 123.688595 150.64871)
		(width 0.127)
		(layer "In2.Cu")
		(net "PCIE_RX0_P")
	)
	(segment
		(start 123.688595 150.64871)
		(end 123.688595 140.19379)
		(width 0.127)
		(layer "In2.Cu")
		(net "PCIE_RX0_P")
	)
	(arc
		(start 123.688596 150.648709)
		(mid 123.658023 150.745434)
		(end 123.598687 150.827712)
		(width 0.127)
		(layer "In2.Cu")
		(net "PCIE_RX0_P")
	)
	(arc
		(start 120.004562 153.478603)
		(mid 120.084731 153.506454)
		(end 120.129457 153.57858)
		(width 0.127)
		(layer "In2.Cu")
		(net "PCIE_RX0_P")
	)
	(arc
		(start 123.688595 140.193796)
		(mid 123.766074 139.805415)
		(end 123.986159 139.476165)
		(width 0.127)
		(layer "In2.Cu")
		(net "PCIE_RX0_P")
	)
	(arc
		(start 121.056455 153.434911)
		(mid 121.063359 153.38023)
		(end 121.092778 153.333623)
		(width 0.127)
		(layer "In2.Cu")
		(net "PCIE_RX0_P")
	)
	(arc
		(start 125.578295 136.71758)
		(mid 125.363935 137.79524)
		(end 124.75349 138.708835)
		(width 0.127)
		(layer "In2.Cu")
		(net "PCIE_RX0_P")
	)
	(arc
		(start 125.578295 136.2901)
		(mid 125.63295 136.015331)
		(end 125.788593 135.782393)
		(width 0.127)
		(layer "In2.Cu")
		(net "PCIE_RX0_P")
	)
	(arc
		(start 121.05646 153.434914)
		(mid 120.660561 153.942957)
		(end 120.129455 153.578581)
		(width 0.127)
		(layer "In2.Cu")
		(net "PCIE_RX0_P")
	)
	(segment
		(start 145.203545 126.56365)
		(end 145.203725 126.56347)
		(width 0.2032)
		(layer "F.Cu")
		(net "LED1")
	)
	(segment
		(start 147.175945 126.56347)
		(end 147.176125 126.5633)
		(width 0.2032)
		(layer "F.Cu")
		(net "LED1")
	)
	(segment
		(start 74.718395 58.65)
		(end 74.718395 57.9906)
		(width 0.2032)
		(layer "F.Cu")
		(net "LED1")
	)
	(segment
		(start 145.203725 126.56347)
		(end 147.175945 126.56347)
		(width 0.2032)
		(layer "F.Cu")
		(net "LED1")
	)
	(via
		(at 145.203545 126.56365)
		(size 0.4064)
		(drill 0.2032)
		(layers "F.Cu" "B.Cu")
		(tenting
			(front yes)
			(back yes)
		)
		(net "LED1")
	)
	(via
		(at 74.718395 58.65)
		(size 0.4064)
		(drill 0.2032)
		(layers "F.Cu" "B.Cu")
		(tenting
			(front yes)
			(back yes)
		)
		(net "LED1")
	)
	(segment
		(start 74.718395 64.82537)
		(end 74.718395 58.65)
		(width 0.2032)
		(layer "B.Cu")
		(net "LED1")
	)
	(segment
		(start 129.456675 126.56365)
		(end 145.203545 126.56365)
		(width 0.2032)
		(layer "B.Cu")
		(net "LED1")
	)
	(segment
		(start 104.363595 101.47057)
		(end 129.456675 126.56365)
		(width 0.2032)
		(layer "B.Cu")
		(net "LED1")
	)
	(segment
		(start 74.718395 64.82537)
		(end 104.363595 94.47057)
		(width 0.2032)
		(layer "B.Cu")
		(net "LED1")
	)
	(segment
		(start 104.363595 101.47057)
		(end 104.363595 94.47057)
		(width 0.2032)
		(layer "B.Cu")
		(net "LED1")
	)
	(segment
		(start 145.338175 126.06342)
		(end 147.176125 126.06342)
		(width 0.2032)
		(layer "F.Cu")
		(net "LED2")
	)
	(segment
		(start 145.174515 125.95475)
		(end 145.229495 125.95475)
		(width 0.2032)
		(layer "F.Cu")
		(net "LED2")
	)
	(segment
		(start 79.840725 58.64153)
		(end 79.840725 57.9906)
		(width 0.2032)
		(layer "F.Cu")
		(net "LED2")
	)
	(segment
		(start 145.229495 125.95475)
		(end 145.338175 126.06342)
		(width 0.2032)
		(layer "F.Cu")
		(net "LED2")
	)
	(via
		(at 145.174515 125.95475)
		(size 0.4064)
		(drill 0.2032)
		(layers "F.Cu" "B.Cu")
		(tenting
			(front yes)
			(back yes)
		)
		(net "LED2")
	)
	(via
		(at 79.840725 58.64153)
		(size 0.4064)
		(drill 0.2032)
		(layers "F.Cu" "B.Cu")
		(tenting
			(front yes)
			(back yes)
		)
		(net "LED2")
	)
	(segment
		(start 104.788595 101.4286)
		(end 104.788595 94.4286)
		(width 0.2032)
		(layer "B.Cu")
		(net "LED2")
	)
	(segment
		(start 104.788595 101.4286)
		(end 129.314745 125.95475)
		(width 0.2032)
		(layer "B.Cu")
		(net "LED2")
	)
	(segment
		(start 79.840725 69.48073)
		(end 104.788595 94.4286)
		(width 0.2032)
		(layer "B.Cu")
		(net "LED2")
	)
	(segment
		(start 129.314745 125.95475)
		(end 145.174515 125.95475)
		(width 0.2032)
		(layer "B.Cu")
		(net "LED2")
	)
	(segment
		(start 79.840725 69.48073)
		(end 79.840725 58.64153)
		(width 0.2032)
		(layer "B.Cu")
		(net "LED2")
	)
	(segment
		(start 86.488595 97.8286)
		(end 86.488595 96.5786)
		(width 0.2032)
		(layer "F.Cu")
		(net "GND")
	)
	(segment
		(start 137.488595 88.0786)
		(end 139.476095 88.0786)
		(width 0.2032)
		(layer "F.Cu")
		(net "GND")
	)
	(segment
		(start 86.488595 111.3286)
		(end 86.488595 109.8286)
		(width 0.2032)
		(layer "F.Cu")
		(net "GND")
	)
	(segment
		(start 124.188365 100.66825)
		(end 124.188365 99.19182)
		(width 0.2032)
		(layer "F.Cu")
		(net "GND")
	)
	(segment
		(start 71.896995 136.0452)
		(end 71.896995 134.4658)
		(width 0.3048)
		(layer "F.Cu")
		(net "GND")
	)
	(segment
		(start 125.465195 154.2818)
		(end 126.834635 154.2818)
		(width 0.508)
		(layer "F.Cu")
		(net "GND")
	)
	(segment
		(start 131.655595 99.14385)
		(end 131.671905 99.16016)
		(width 0.2032)
		(layer "F.Cu")
		(net "GND")
	)
	(segment
		(start 132.288595 136.83358)
		(end 132.288595 136.7786)
		(width 0.2032)
		(layer "F.Cu")
		(net "GND")
	)
	(segment
		(start 116.688245 99.42389)
		(end 116.913595 99.19854)
		(width 0.2032)
		(layer "F.Cu")
		(net "GND")
	)
	(segment
		(start 131.044715 156.98475)
		(end 131.044715 154.65972)
		(width 0.508)
		(layer "F.Cu")
		(net "GND")
	)
	(segment
		(start 126.188605 132.47861)
		(end 126.188615 132.47861)
		(width 0.2032)
		(layer "F.Cu")
		(net "GND")
	)
	(segment
		(start 71.871595 109.4706)
		(end 71.871595 107.9228)
		(width 0.3048)
		(layer "F.Cu")
		(net "GND")
	)
	(segment
		(start 149.996245 124.57095)
		(end 151.218245 124.57095)
		(width 0.2032)
		(layer "F.Cu")
		(net "GND")
	)
	(segment
		(start 129.164985 100.64488)
		(end 129.164985 99.91327)
		(width 0.2032)
		(layer "F.Cu")
		(net "GND")
	)
	(segment
		(start 220.178595 98.0786)
		(end 220.229395 98.0278)
		(width 0.254)
		(layer "F.Cu")
		(net "GND")
	)
	(segment
		(start 131.238595 77.3286)
		(end 131.238595 76.0286)
		(width 0.2032)
		(layer "F.Cu")
		(net "GND")
	)
	(segment
		(start 139.476095 89.0786)
		(end 140.369645 89.0786)
		(width 0.2032)
		(layer "F.Cu")
		(net "GND")
	)
	(segment
		(start 185.488595 88.5286)
		(end 185.538595 88.5786)
		(width 0.2032)
		(layer "F.Cu")
		(net "GND")
	)
	(segment
		(start 124.188365 99.19182)
		(end 124.246595 99.13359)
		(width 0.2032)
		(layer "F.Cu")
		(net "GND")
	)
	(segment
		(start 87.688595 109.6286)
		(end 87.738595 109.5786)
		(width 0.2032)
		(layer "F.Cu")
		(net "GND")
	)
	(segment
		(start 85.088595 121.8286)
		(end 85.738595 121.8286)
		(width 0.2032)
		(layer "F.Cu")
		(net "GND")
	)
	(segment
		(start 229.365595 114.0738)
		(end 229.598595 114.3068)
		(width 0.254)
		(layer "F.Cu")
		(net "GND")
	)
	(segment
		(start 85.438595 133.5286)
		(end 85.438595 132.5786)
		(width 0.2032)
		(layer "F.Cu")
		(net "GND")
	)
	(segment
		(start 124.988595 82.0786)
		(end 124.988595 80.7286)
		(width 0.2032)
		(layer "F.Cu")
		(net "GND")
	)
	(segment
		(start 151.218245 124.57095)
		(end 151.225895 124.5633)
		(width 0.2032)
		(layer "F.Cu")
		(net "GND")
	)
	(segment
		(start 86.488595 111.3286)
		(end 86.688595 111.5286)
		(width 0.2032)
		(layer "F.Cu")
		(net "GND")
	)
	(segment
		(start 147.286995 88.4302)
		(end 147.636995 88.4302)
		(width 0.2032)
		(layer "F.Cu")
		(net "GND")
	)
	(segment
		(start 149.988595 124.5786)
		(end 149.996245 124.57095)
		(width 0.2032)
		(layer "F.Cu")
		(net "GND")
	)
	(segment
		(start 107.142105 157.74109)
		(end 107.142105 154.36162)
		(width 0.508)
		(layer "F.Cu")
		(net "GND")
	)
	(segment
		(start 140.988595 92.0786)
		(end 141.238595 91.8286)
		(width 0.2032)
		(layer "F.Cu")
		(net "GND")
	)
	(segment
		(start 87.738595 96.0786)
		(end 88.988595 96.0786)
		(width 0.2032)
		(layer "F.Cu")
		(net "GND")
	)
	(segment
		(start 129.588595 154.1786)
		(end 129.608475 154.1786)
		(width 0.508)
		(layer "F.Cu")
		(net "GND")
	)
	(segment
		(start 148.988595 86.5786)
		(end 148.988595 83.5866)
		(width 0.2032)
		(layer "F.Cu")
		(net "GND")
	)
	(segment
		(start 85.038595 123.7786)
		(end 86.038595 123.7786)
		(width 0.2032)
		(layer "F.Cu")
		(net "GND")
	)
	(segment
		(start 147.183765 119.57096)
		(end 148.480955 119.57096)
		(width 0.2032)
		(layer "F.Cu")
		(net "GND")
	)
	(segment
		(start 126.679915 100.65993)
		(end 126.679915 99.16192)
		(width 0.2032)
		(layer "F.Cu")
		(net "GND")
	)
	(segment
		(start 87.738595 109.5786)
		(end 88.988595 109.5786)
		(width 0.2032)
		(layer "F.Cu")
		(net "GND")
	)
	(segment
		(start 225.988595 115.4786)
		(end 227.206595 115.4786)
		(width 0.254)
		(layer "F.Cu")
		(net "GND")
	)
	(segment
		(start 85.488595 120.5786)
		(end 85.488595 119.6786)
		(width 0.2032)
		(layer "F.Cu")
		(net "GND")
	)
	(segment
		(start 84.238595 119.5786)
		(end 85.588595 119.5786)
		(width 0.2032)
		(layer "F.Cu")
		(net "GND")
	)
	(segment
		(start 129.608475 154.1786)
		(end 130.563595 154.1786)
		(width 0.508)
		(layer "F.Cu")
		(net "GND")
	)
	(segment
		(start 127.132225 157.07224)
		(end 127.138575 157.0786)
		(width 0.508)
		(layer "F.Cu")
		(net "GND")
	)
	(segment
		(start 126.188615 134.22882)
		(end 126.188615 132.47861)
		(width 0.2032)
		(layer "F.Cu")
		(net "GND")
	)
	(segment
		(start 159.316325 118.69588)
		(end 159.499975 118.51224)
		(width 0.2032)
		(layer "F.Cu")
		(net "GND")
	)
	(segment
		(start 130.563595 154.1786)
		(end 131.044715 154.65972)
		(width 0.508)
		(layer "F.Cu")
		(net "GND")
	)
	(segment
		(start 100.709355 117.5842)
		(end 100.886755 117.7616)
		(width 0.254)
		(layer "F.Cu")
		(net "GND")
	)
	(segment
		(start 140.988595 92.0786)
		(end 142.738595 92.0786)
		(width 0.2032)
		(layer "F.Cu")
		(net "GND")
	)
	(segment
		(start 84.988605 135.0786)
		(end 84.988605 133.9786)
		(width 0.2032)
		(layer "F.Cu")
		(net "GND")
	)
	(segment
		(start 71.738595 105.0786)
		(end 71.788595 105.0286)
		(width 0.2032)
		(layer "F.Cu")
		(net "GND")
	)
	(segment
		(start 108.238595 69.7286)
		(end 109.083615 69.7286)
		(width 0.2032)
		(layer "F.Cu")
		(net "GND")
	)
	(segment
		(start 147.351195 142.691)
		(end 147.905595 142.1366)
		(width 0.254)
		(layer "F.Cu")
		(net "GND")
	)
	(segment
		(start 130.888595 132.53359)
		(end 130.888595 132.4786)
		(width 0.2032)
		(layer "F.Cu")
		(net "GND")
	)
	(segment
		(start 102.167005 122.55879)
		(end 103.613025 122.55879)
		(width 0.254)
		(layer "F.Cu")
		(net "GND")
	)
	(segment
		(start 71.846195 122.696)
		(end 71.846195 121.1816)
		(width 0.3048)
		(layer "F.Cu")
		(net "GND")
	)
	(segment
		(start 122.288595 132.54356)
		(end 122.288595 132.48857)
		(width 0.2032)
		(layer "F.Cu")
		(net "GND")
	)
	(segment
		(start 124.698335 136.90826)
		(end 124.753195 136.8534)
		(width 0.254)
		(layer "F.Cu")
		(net "GND")
	)
	(segment
		(start 219.393595 106.9686)
		(end 220.931995 106.9686)
		(width 0.254)
		(layer "F.Cu")
		(net "GND")
	)
	(segment
		(start 147.636995 88.4302)
		(end 148.238595 87.8286)
		(width 0.2032)
		(layer "F.Cu")
		(net "GND")
	)
	(segment
		(start 102.112905 125.05891)
		(end 103.613025 125.05891)
		(width 0.254)
		(layer "F.Cu")
		(net "GND")
	)
	(segment
		(start 225.988595 119.6786)
		(end 226.927595 119.6786)
		(width 0.2032)
		(layer "F.Cu")
		(net "GND")
	)
	(segment
		(start 84.188595 132.5286)
		(end 85.488605 132.5286)
		(width 0.2032)
		(layer "F.Cu")
		(net "GND")
	)
	(segment
		(start 121.688235 97.77326)
		(end 121.688235 96.61847)
		(width 0.2032)
		(layer "F.Cu")
		(net "GND")
	)
	(segment
		(start 147.176125 124.5633)
		(end 147.183775 124.57095)
		(width 0.2032)
		(layer "F.Cu")
		(net "GND")
	)
	(segment
		(start 131.188595 88.5786)
		(end 131.988595 88.5786)
		(width 0.2032)
		(layer "F.Cu")
		(net "GND")
	)
	(segment
		(start 119.211735 97.95174)
		(end 119.238595 97.9786)
		(width 0.2032)
		(layer "F.Cu")
		(net "GND")
	)
	(segment
		(start 214.188595 90.2786)
		(end 214.188595 89.2686)
		(width 0.2032)
		(layer "F.Cu")
		(net "GND")
	)
	(segment
		(start 102.444065 117.58217)
		(end 102.955235 117.58217)
		(width 0.254)
		(layer "F.Cu")
		(net "GND")
	)
	(segment
		(start 121.158585 155.05901)
		(end 121.158585 155.05901)
		(width 0.508)
		(layer "F.Cu")
		(net "GND")
	)
	(segment
		(start 137.488595 89.0786)
		(end 139.476095 89.0786)
		(width 0.2032)
		(layer "F.Cu")
		(net "GND")
	)
	(segment
		(start 86.238595 123.5786)
		(end 86.238595 122.3286)
		(width 0.2032)
		(layer "F.Cu")
		(net "GND")
	)
	(segment
		(start 127.238595 82.0706)
		(end 127.238595 80.7786)
		(width 0.2032)
		(layer "F.Cu")
		(net "GND")
	)
	(segment
		(start 100.927995 122.5532)
		(end 100.953395 122.5786)
		(width 0.254)
		(layer "F.Cu")
		(net "GND")
	)
	(segment
		(start 119.211735 97.95174)
		(end 119.211735 96.64184)
		(width 0.2032)
		(layer "F.Cu")
		(net "GND")
	)
	(segment
		(start 102.264635 117.7616)
		(end 102.444065 117.58217)
		(width 0.254)
		(layer "F.Cu")
		(net "GND")
	)
	(segment
		(start 130.688475 132.73371)
		(end 130.888595 132.53359)
		(width 0.2032)
		(layer "F.Cu")
		(net "GND")
	)
	(segment
		(start 190.488595 86.2786)
		(end 190.488595 84.8286)
		(width 0.2032)
		(layer "F.Cu")
		(net "GND")
	)
	(segment
		(start 148.480955 114.57096)
		(end 148.488595 114.5786)
		(width 0.2032)
		(layer "F.Cu")
		(net "GND")
	)
	(segment
		(start 102.096395 125.0424)
		(end 102.112905 125.05891)
		(width 0.254)
		(layer "F.Cu")
		(net "GND")
	)
	(segment
		(start 131.044715 156.98475)
		(end 131.138565 157.0786)
		(width 0.508)
		(layer "F.Cu")
		(net "GND")
	)
	(segment
		(start 104.556115 69.7286)
		(end 104.606115 69.7786)
		(width 0.254)
		(layer "F.Cu")
		(net "GND")
	)
	(segment
		(start 188.738595 88.8286)
		(end 189.488595 88.0786)
		(width 0.2032)
		(layer "F.Cu")
		(net "GND")
	)
	(segment
		(start 84.988605 135.0786)
		(end 85.988595 135.0786)
		(width 0.2032)
		(layer "F.Cu")
		(net "GND")
	)
	(segment
		(start 102.050675 120.05892)
		(end 103.613025 120.05892)
		(width 0.254)
		(layer "F.Cu")
		(net "GND")
	)
	(segment
		(start 148.481025 112.07103)
		(end 148.488595 112.0786)
		(width 0.2032)
		(layer "F.Cu")
		(net "GND")
	)
	(segment
		(start 69.988595 132.0786)
		(end 71.588595 132.0786)
		(width 0.2032)
		(layer "F.Cu")
		(net "GND")
	)
	(segment
		(start 71.871595 100.506)
		(end 71.871595 99.0866)
		(width 0.3048)
		(layer "F.Cu")
		(net "GND")
	)
	(segment
		(start 86.188595 136.7786)
		(end 86.188595 135.2786)
		(width 0.2032)
		(layer "F.Cu")
		(net "GND")
	)
	(segment
		(start 71.871595 127.2014)
		(end 71.871595 125.6866)
		(width 0.3048)
		(layer "F.Cu")
		(net "GND")
	)
	(segment
		(start 147.179705 117.06702)
		(end 148.485015 117.06702)
		(width 0.2032)
		(layer "F.Cu")
		(net "GND")
	)
	(segment
		(start 149.996235 109.57096)
		(end 151.218265 109.57096)
		(width 0.2032)
		(layer "F.Cu")
		(net "GND")
	)
	(segment
		(start 125.840995 154.3036)
		(end 126.138575 154.60118)
		(width 0.508)
		(layer "F.Cu")
		(net "GND")
	)
	(segment
		(start 122.388595 136.93358)
		(end 122.388595 136.8786)
		(width 0.2032)
		(layer "F.Cu")
		(net "GND")
	)
	(segment
		(start 189.238595 90.0786)
		(end 190.088595 90.0786)
		(width 0.2032)
		(layer "F.Cu")
		(net "GND")
	)
	(segment
		(start 110.158605 154.34359)
		(end 110.173595 154.3286)
		(width 0.508)
		(layer "F.Cu")
		(net "GND")
	)
	(segment
		(start 100.108615 69.7536)
		(end 100.133615 69.7786)
		(width 0.2032)
		(layer "F.Cu")
		(net "GND")
	)
	(segment
		(start 191.988595 91.5786)
		(end 191.988595 91.5786)
		(width 0.2032)
		(layer "F.Cu")
		(net "GND")
	)
	(segment
		(start 191.988595 91.5786)
		(end 192.948595 90.6186)
		(width 0.2032)
		(layer "F.Cu")
		(net "GND")
	)
	(segment
		(start 137.163595 157.75256)
		(end 137.163595 154.1786)
		(width 0.508)
		(layer "F.Cu")
		(net "GND")
	)
	(segment
		(start 147.905595 142.1366)
		(end 148.762595 142.1366)
		(width 0.254)
		(layer "F.Cu")
		(net "GND")
	)
	(segment
		(start 124.698335 138.25523)
		(end 124.698335 136.90826)
		(width 0.254)
		(layer "F.Cu")
		(net "GND")
	)
	(segment
		(start 220.018595 90.9786)
		(end 220.288595 90.9786)
		(width 0.254)
		(layer "F.Cu")
		(net "GND")
	)
	(segment
		(start 132.188595 136.93358)
		(end 132.288595 136.83358)
		(width 0.2032)
		(layer "F.Cu")
		(net "GND")
	)
	(segment
		(start 149.238595 87.8286)
		(end 149.263595 87.8536)
		(width 0.2032)
		(layer "F.Cu")
		(net "GND")
	)
	(segment
		(start 132.890595 76.55381)
		(end 132.890595 76.5266)
		(width 0.254)
		(layer "F.Cu")
		(net "GND")
	)
	(segment
		(start 102.223395 110.0564)
		(end 102.225935 110.05894)
		(width 0.254)
		(layer "F.Cu")
		(net "GND")
	)
	(segment
		(start 119.188375 96.61847)
		(end 119.211735 96.64184)
		(width 0.2032)
		(layer "F.Cu")
		(net "GND")
	)
	(segment
		(start 134.044715 156.98475)
		(end 134.138565 157.0786)
		(width 0.508)
		(layer "F.Cu")
		(net "GND")
	)
	(segment
		(start 113.728335 69.72635)
		(end 113.730595 69.72409)
		(width 0.2032)
		(layer "F.Cu")
		(net "GND")
	)
	(segment
		(start 121.838595 97.9786)
		(end 121.838595 97.92361)
		(width 0.2032)
		(layer "F.Cu")
		(net "GND")
	)
	(segment
		(start 122.188615 132.64353)
		(end 122.288595 132.54356)
		(width 0.2032)
		(layer "F.Cu")
		(net "GND")
	)
	(segment
		(start 147.813595 144.1786)
		(end 148.913595 144.1786)
		(width 0.2032)
		(layer "F.Cu")
		(net "GND")
	)
	(segment
		(start 125.488595 68.5786)
		(end 127.488595 68.5786)
		(width 0.2032)
		(layer "F.Cu")
		(net "GND")
	)
	(segment
		(start 129.488595 88.3286)
		(end 130.938595 88.3286)
		(width 0.2032)
		(layer "F.Cu")
		(net "GND")
	)
	(segment
		(start 188.738595 89.5786)
		(end 189.238595 90.0786)
		(width 0.2032)
		(layer "F.Cu")
		(net "GND")
	)
	(segment
		(start 86.488595 96.5786)
		(end 86.938595 96.1286)
		(width 0.2032)
		(layer "F.Cu")
		(net "GND")
	)
	(segment
		(start 121.688235 97.77326)
		(end 121.838595 97.92361)
		(width 0.2032)
		(layer "F.Cu")
		(net "GND")
	)
	(segment
		(start 148.481015 122.07102)
		(end 148.488595 122.0786)
		(width 0.2032)
		(layer "F.Cu")
		(net "GND")
	)
	(segment
		(start 126.711595 97.9516)
		(end 126.711595 96.64184)
		(width 0.2032)
		(layer "F.Cu")
		(net "GND")
	)
	(segment
		(start 85.038595 121.8786)
		(end 85.088595 121.8286)
		(width 0.2032)
		(layer "F.Cu")
		(net "GND")
	)
	(segment
		(start 124.211725 97.94373)
		(end 124.246595 97.9786)
		(width 0.2032)
		(layer "F.Cu")
		(net "GND")
	)
	(segment
		(start 119.688495 137.03368)
		(end 119.788595 136.93358)
		(width 0.2032)
		(layer "F.Cu")
		(net "GND")
	)
	(segment
		(start 99.563255 115.05893)
		(end 99.564525 115.0602)
		(width 0.254)
		(layer "F.Cu")
		(net "GND")
	)
	(segment
		(start 124.188365 96.61847)
		(end 124.211725 96.64184)
		(width 0.2032)
		(layer "F.Cu")
		(net "GND")
	)
	(segment
		(start 117.188625 137.03355)
		(end 117.288595 136.93358)
		(width 0.2032)
		(layer "F.Cu")
		(net "GND")
	)
	(segment
		(start 119.688545 134.22877)
		(end 119.688545 132.47865)
		(width 0.2032)
		(layer "F.Cu")
		(net "GND")
	)
	(segment
		(start 185.538595 88.5786)
		(end 186.988595 88.5786)
		(width 0.2032)
		(layer "F.Cu")
		(net "GND")
	)
	(segment
		(start 102.235585 112.55881)
		(end 103.613025 112.55881)
		(width 0.254)
		(layer "F.Cu")
		(net "GND")
	)
	(segment
		(start 117.888595 154.3286)
		(end 118.116725 154.55673)
		(width 0.508)
		(layer "F.Cu")
		(net "GND")
	)
	(segment
		(start 181.338595 90.7336)
		(end 182.643615 90.7336)
		(width 0.2032)
		(layer "F.Cu")
		(net "GND")
	)
	(segment
		(start 111.988595 143.1786)
		(end 112.088595 143.0786)
		(width 0.2032)
		(layer "F.Cu")
		(net "GND")
	)
	(segment
		(start 220.018595 92.6786)
		(end 220.288595 92.6786)
		(width 0.254)
		(layer "F.Cu")
		(net "GND")
	)
	(segment
		(start 99.563255 110.05894)
		(end 101.027055 110.05894)
		(width 0.254)
		(layer "F.Cu")
		(net "GND")
	)
	(segment
		(start 71.871595 140.511)
		(end 71.871595 139.0866)
		(width 0.3048)
		(layer "F.Cu")
		(net "GND")
	)
	(segment
		(start 85.038595 121.8786)
		(end 85.038595 121.0286)
		(width 0.2032)
		(layer "F.Cu")
		(net "GND")
	)
	(segment
		(start 99.238595 56.5786)
		(end 99.238595 56.52361)
		(width 0.2032)
		(layer "F.Cu")
		(net "GND")
	)
	(segment
		(start 84.988605 133.9786)
		(end 85.438595 133.5286)
		(width 0.2032)
		(layer "F.Cu")
		(net "GND")
	)
	(segment
		(start 190.488595 86.2786)
		(end 190.538595 86.3286)
		(width 0.2032)
		(layer "F.Cu")
		(net "GND")
	)
	(segment
		(start 102.045595 120.064)
		(end 102.050675 120.05892)
		(width 0.254)
		(layer "F.Cu")
		(net "GND")
	)
	(segment
		(start 225.988595 116.8786)
		(end 227.203595 116.8786)
		(width 0.254)
		(layer "F.Cu")
		(net "GND")
	)
	(segment
		(start 148.480955 119.57096)
		(end 148.488595 119.5786)
		(width 0.2032)
		(layer "F.Cu")
		(net "GND")
	)
	(segment
		(start 117.188625 134.22882)
		(end 117.188625 132.47863)
		(width 0.2032)
		(layer "F.Cu")
		(net "GND")
	)
	(segment
		(start 87.188595 113.8286)
		(end 88.488595 113.8286)
		(width 0.2032)
		(layer "F.Cu")
		(net "GND")
	)
	(segment
		(start 99.138595 69.7536)
		(end 100.108615 69.7536)
		(width 0.2032)
		(layer "F.Cu")
		(net "GND")
	)
	(segment
		(start 149.988595 119.5786)
		(end 149.996245 119.57096)
		(width 0.2032)
		(layer "F.Cu")
		(net "GND")
	)
	(segment
		(start 87.688595 112.3786)
		(end 87.688595 111.5286)
		(width 0.2032)
		(layer "F.Cu")
		(net "GND")
	)
	(segment
		(start 225.988595 118.0786)
		(end 226.893595 118.0786)
		(width 0.2032)
		(layer "F.Cu")
		(net "GND")
	)
	(segment
		(start 71.838595 122.7036)
		(end 71.846195 122.696)
		(width 0.3048)
		(layer "F.Cu")
		(net "GND")
	)
	(segment
		(start 220.288595 90.9786)
		(end 222.339995 90.9786)
		(width 0.254)
		(layer "F.Cu")
		(net "GND")
	)
	(segment
		(start 71.838595 109.5036)
		(end 71.871595 109.4706)
		(width 0.3048)
		(layer "F.Cu")
		(net "GND")
	)
	(segment
		(start 151.218265 109.57096)
		(end 151.225895 109.56333)
		(width 0.2032)
		(layer "F.Cu")
		(net "GND")
	)
	(segment
		(start 147.176125 119.56331)
		(end 147.183765 119.57096)
		(width 0.2032)
		(layer "F.Cu")
		(net "GND")
	)
	(segment
		(start 192.948595 90.6186)
		(end 194.488595 90.6186)
		(width 0.2032)
		(layer "F.Cu")
		(net "GND")
	)
	(segment
		(start 131.671905 96.63478)
		(end 131.688215 96.61847)
		(width 0.2032)
		(layer "F.Cu")
		(net "GND")
	)
	(segment
		(start 87.688595 96.1286)
		(end 87.738595 96.0786)
		(width 0.2032)
		(layer "F.Cu")
		(net "GND")
	)
	(segment
		(start 87.238595 100.2786)
		(end 87.238595 99.3286)
		(width 0.2032)
		(layer "F.Cu")
		(net "GND")
	)
	(segment
		(start 123.143085 157.74211)
		(end 123.143085 154.37508)
		(width 0.508)
		(layer "F.Cu")
		(net "GND")
	)
	(segment
		(start 86.688595 98.0286)
		(end 87.688595 98.0286)
		(width 0.2032)
		(layer "F.Cu")
		(net "GND")
	)
	(segment
		(start 226.831095 121.7341)
		(end 226.875595 121.6896)
		(width 0.254)
		(layer "F.Cu")
		(net "GND")
	)
	(segment
		(start 84.988605 136.9786)
		(end 85.988595 136.9786)
		(width 0.2032)
		(layer "F.Cu")
		(net "GND")
	)
	(segment
		(start 104.606115 69.7786)
		(end 104.647355 69.7786)
		(width 0.254)
		(layer "F.Cu")
		(net "GND")
	)
	(segment
		(start 71.838595 99.0536)
		(end 71.871595 99.0866)
		(width 0.3048)
		(layer "F.Cu")
		(net "GND")
	)
	(segment
		(start 160.678245 116.66388)
		(end 162.071115 116.66388)
		(width 0.2032)
		(layer "F.Cu")
		(net "GND")
	)
	(segment
		(start 129.288595 132.53359)
		(end 129.288595 132.4786)
		(width 0.2032)
		(layer "F.Cu")
		(net "GND")
	)
	(segment
		(start 151.218325 112.07103)
		(end 151.225895 112.06345)
		(width 0.2032)
		(layer "F.Cu")
		(net "GND")
	)
	(segment
		(start 147.213595 89.8036)
		(end 147.713595 89.8036)
		(width 0.2032)
		(layer "F.Cu")
		(net "GND")
	)
	(segment
		(start 129.188605 134.22882)
		(end 129.188605 132.63358)
		(width 0.2032)
		(layer "F.Cu")
		(net "GND")
	)
	(segment
		(start 86.038595 123.7786)
		(end 86.238595 123.5786)
		(width 0.2032)
		(layer "F.Cu")
		(net "GND")
	)
	(segment
		(start 140.369645 89.0786)
		(end 140.715195 89.42415)
		(width 0.2032)
		(layer "F.Cu")
		(net "GND")
	)
	(segment
		(start 220.931995 106.9686)
		(end 220.942995 106.9576)
		(width 0.254)
		(layer "F.Cu")
		(net "GND")
	)
	(segment
		(start 85.988595 136.9786)
		(end 86.188595 136.7786)
		(width 0.2032)
		(layer "F.Cu")
		(net "GND")
	)
	(segment
		(start 117.158595 154.3286)
		(end 117.888595 154.3286)
		(width 0.508)
		(layer "F.Cu")
		(net "GND")
	)
	(segment
		(start 99.563255 120.05892)
		(end 100.922915 120.05892)
		(width 0.254)
		(layer "F.Cu")
		(net "GND")
	)
	(segment
		(start 147.183775 124.57095)
		(end 148.480945 124.57095)
		(width 0.2032)
		(layer "F.Cu")
		(net "GND")
	)
	(segment
		(start 124.688485 132.61995)
		(end 124.788595 132.51984)
		(width 0.254)
		(layer "F.Cu")
		(net "GND")
	)
	(segment
		(start 131.671905 100.65194)
		(end 131.688215 100.66825)
		(width 0.2032)
		(layer "F.Cu")
		(net "GND")
	)
	(segment
		(start 85.488595 119.6786)
		(end 85.588595 119.5786)
		(width 0.2032)
		(layer "F.Cu")
		(net "GND")
	)
	(segment
		(start 220.288595 94.3786)
		(end 222.388595 94.3786)
		(width 0.254)
		(layer "F.Cu")
		(net "GND")
	)
	(segment
		(start 109.988595 56.5786)
		(end 109.988595 53.6526)
		(width 0.2032)
		(layer "F.Cu")
		(net "GND")
	)
	(segment
		(start 148.762595 142.20201)
		(end 148.762595 142.1366)
		(width 0.254)
		(layer "F.Cu")
		(net "GND")
	)
	(segment
		(start 103.413595 69.7286)
		(end 104.556115 69.7286)
		(width 0.254)
		(layer "F.Cu")
		(net "GND")
	)
	(segment
		(start 134.044715 154.87014)
		(end 134.044715 154.87014)
		(width 0.508)
		(layer "F.Cu")
		(net "GND")
	)
	(segment
		(start 147.351195 143.2542)
		(end 147.351195 142.691)
		(width 0.254)
		(layer "F.Cu")
		(net "GND")
	)
	(segment
		(start 109.738595 142.7286)
		(end 109.738595 141.0786)
		(width 0.2032)
		(layer "F.Cu")
		(net "GND")
	)
	(segment
		(start 121.688415 100.66807)
		(end 121.688415 99.15378)
		(width 0.2032)
		(layer "F.Cu")
		(net "GND")
	)
	(segment
		(start 227.078595 112.7996)
		(end 228.664595 112.7996)
		(width 0.254)
		(layer "F.Cu")
		(net "GND")
	)
	(segment
		(start 140.715195 89.8177)
		(end 140.715195 89.42415)
		(width 0.2032)
		(layer "F.Cu")
		(net "GND")
	)
	(segment
		(start 109.738595 142.7286)
		(end 109.788595 142.7786)
		(width 0.2032)
		(layer "F.Cu")
		(net "GND")
	)
	(segment
		(start 99.565285 122.55676)
		(end 100.288475 122.55676)
		(width 0.254)
		(layer "F.Cu")
		(net "GND")
	)
	(segment
		(start 100.201365 117.5842)
		(end 100.709355 117.5842)
		(width 0.254)
		(layer "F.Cu")
		(net "GND")
	)
	(segment
		(start 225.818675 121.7341)
		(end 226.831095 121.7341)
		(width 0.254)
		(layer "F.Cu")
		(net "GND")
	)
	(segment
		(start 109.697595 53.3616)
		(end 109.988595 53.6526)
		(width 0.2032)
		(layer "F.Cu")
		(net "GND")
	)
	(segment
		(start 147.713595 144.2786)
		(end 147.813595 144.1786)
		(width 0.2032)
		(layer "F.Cu")
		(net "GND")
	)
	(segment
		(start 229.598595 114.3786)
		(end 229.598595 114.3068)
		(width 0.254)
		(layer "F.Cu")
		(net "GND")
	)
	(segment
		(start 112.738595 69.7286)
		(end 112.740855 69.72635)
		(width 0.2032)
		(layer "F.Cu")
		(net "GND")
	)
	(segment
		(start 126.834635 154.2818)
		(end 127.132225 154.57938)
		(width 0.508)
		(layer "F.Cu")
		(net "GND")
	)
	(segment
		(start 133.988595 89.0786)
		(end 134.238595 88.8286)
		(width 0.2032)
		(layer "F.Cu")
		(net "GND")
	)
	(segment
		(start 149.988595 109.5786)
		(end 149.996235 109.57096)
		(width 0.2032)
		(layer "F.Cu")
		(net "GND")
	)
	(segment
		(start 133.888595 76.0786)
		(end 135.238595 76.0786)
		(width 0.2032)
		(layer "F.Cu")
		(net "GND")
	)
	(segment
		(start 99.563255 112.55881)
		(end 101.041785 112.55881)
		(width 0.254)
		(layer "F.Cu")
		(net "GND")
	)
	(segment
		(start 71.838595 136.1036)
		(end 71.896995 136.0452)
		(width 0.3048)
		(layer "F.Cu")
		(net "GND")
	)
	(segment
		(start 122.188615 137.13356)
		(end 122.388595 136.93358)
		(width 0.2032)
		(layer "F.Cu")
		(net "GND")
	)
	(segment
		(start 148.988595 86.5786)
		(end 149.263595 86.8536)
		(width 0.2032)
		(layer "F.Cu")
		(net "GND")
	)
	(segment
		(start 160.532965 116.80916)
		(end 160.678245 116.66388)
		(width 0.2032)
		(layer "F.Cu")
		(net "GND")
	)
	(segment
		(start 212.129195 105.4336)
		(end 213.259595 105.4336)
		(width 0.254)
		(layer "F.Cu")
		(net "GND")
	)
	(segment
		(start 147.176125 117.06344)
		(end 147.179705 117.06702)
		(width 0.2032)
		(layer "F.Cu")
		(net "GND")
	)
	(segment
		(start 132.188595 138.2786)
		(end 132.188595 136.93358)
		(width 0.2032)
		(layer "F.Cu")
		(net "GND")
	)
	(segment
		(start 151.218255 114.57096)
		(end 151.225895 114.56332)
		(width 0.2032)
		(layer "F.Cu")
		(net "GND")
	)
	(segment
		(start 151.218315 122.07102)
		(end 151.225895 122.06343)
		(width 0.2032)
		(layer "F.Cu")
		(net "GND")
	)
	(segment
		(start 147.176125 112.06345)
		(end 147.183695 112.07103)
		(width 0.2032)
		(layer "F.Cu")
		(net "GND")
	)
	(segment
		(start 147.176125 109.56333)
		(end 147.183755 109.57096)
		(width 0.2032)
		(layer "F.Cu")
		(net "GND")
	)
	(segment
		(start 227.203595 116.8786)
		(end 227.218595 116.8636)
		(width 0.254)
		(layer "F.Cu")
		(net "GND")
	)
	(segment
		(start 124.211725 97.94373)
		(end 124.211725 96.64184)
		(width 0.2032)
		(layer "F.Cu")
		(net "GND")
	)
	(segment
		(start 226.927595 119.6786)
		(end 226.948595 119.6576)
		(width 0.2032)
		(layer "F.Cu")
		(net "GND")
	)
	(segment
		(start 235.751195 114.0786)
		(end 236.288595 113.5412)
		(width 0.2032)
		(layer "F.Cu")
		(net "GND")
	)
	(segment
		(start 87.188595 100.3286)
		(end 88.488595 100.3286)
		(width 0.2032)
		(layer "F.Cu")
		(net "GND")
	)
	(segment
		(start 99.113595 69.7286)
		(end 99.138595 69.7536)
		(width 0.2032)
		(layer "F.Cu")
		(net "GND")
	)
	(segment
		(start 99.564525 115.0602)
		(end 100.953395 115.0602)
		(width 0.254)
		(layer "F.Cu")
		(net "GND")
	)
	(segment
		(start 149.988595 114.5786)
		(end 149.996235 114.57096)
		(width 0.2032)
		(layer "F.Cu")
		(net "GND")
	)
	(segment
		(start 127.788595 132.53359)
		(end 127.788595 132.4786)
		(width 0.2032)
		(layer "F.Cu")
		(net "GND")
	)
	(segment
		(start 149.996245 119.57096)
		(end 151.218255 119.57096)
		(width 0.2032)
		(layer "F.Cu")
		(net "GND")
	)
	(segment
		(start 226.327795 105.3066)
		(end 227.405595 105.3066)
		(width 0.254)
		(layer "F.Cu")
		(net "GND")
	)
	(segment
		(start 87.238595 112.8286)
		(end 87.688595 112.3786)
		(width 0.2032)
		(layer "F.Cu")
		(net "GND")
	)
	(segment
		(start 120.643785 154.41678)
		(end 120.955925 154.65301)
		(width 0.508)
		(layer "F.Cu")
		(net "GND")
	)
	(segment
		(start 210.988595 99.8886)
		(end 210.988595 98.8514)
		(width 0.254)
		(layer "F.Cu")
		(net "GND")
	)
	(segment
		(start 148.480965 109.57096)
		(end 148.488595 109.5786)
		(width 0.2032)
		(layer "F.Cu")
		(net "GND")
	)
	(segment
		(start 127.688485 134.22882)
		(end 127.688485 132.6337)
		(width 0.2032)
		(layer "F.Cu")
		(net "GND")
	)
	(segment
		(start 148.485015 117.06702)
		(end 148.488595 117.0706)
		(width 0.2032)
		(layer "F.Cu")
		(net "GND")
	)
	(segment
		(start 87.238595 99.3286)
		(end 87.688595 98.8786)
		(width 0.2032)
		(layer "F.Cu")
		(net "GND")
	)
	(segment
		(start 119.688545 132.47865)
		(end 119.688595 132.4786)
		(width 0.2032)
		(layer "F.Cu")
		(net "GND")
	)
	(segment
		(start 133.688595 75.8786)
		(end 133.888595 76.0786)
		(width 0.2032)
		(layer "F.Cu")
		(net "GND")
	)
	(segment
		(start 137.158555 157.7576)
		(end 137.163595 157.75256)
		(width 0.508)
		(layer "F.Cu")
		(net "GND")
	)
	(segment
		(start 149.988595 117.0706)
		(end 149.992175 117.06702)
		(width 0.2032)
		(layer "F.Cu")
		(net "GND")
	)
	(segment
		(start 140.715195 89.8177)
		(end 140.738595 89.8411)
		(width 0.2032)
		(layer "F.Cu")
		(net "GND")
	)
	(segment
		(start 160.477985 116.80916)
		(end 160.532965 116.80916)
		(width 0.2032)
		(layer "F.Cu")
		(net "GND")
	)
	(segment
		(start 119.688495 138.2786)
		(end 119.688495 137.03368)
		(width 0.2032)
		(layer "F.Cu")
		(net "GND")
	)
	(segment
		(start 116.663595 97.9536)
		(end 116.688245 97.92895)
		(width 0.2032)
		(layer "F.Cu")
		(net "GND")
	)
	(segment
		(start 220.018595 96.1786)
		(end 220.288595 96.1786)
		(width 0.254)
		(layer "F.Cu")
		(net "GND")
	)
	(segment
		(start 151.222315 117.06702)
		(end 151.225895 117.06344)
		(width 0.2032)
		(layer "F.Cu")
		(net "GND")
	)
	(segment
		(start 122.188615 138.2786)
		(end 122.188615 137.13356)
		(width 0.2032)
		(layer "F.Cu")
		(net "GND")
	)
	(segment
		(start 122.188615 134.22882)
		(end 122.188615 132.64353)
		(width 0.2032)
		(layer "F.Cu")
		(net "GND")
	)
	(segment
		(start 130.688475 134.22882)
		(end 130.688475 132.73371)
		(width 0.2032)
		(layer "F.Cu")
		(net "GND")
	)
	(segment
		(start 126.688225 96.61847)
		(end 126.711595 96.64184)
		(width 0.2032)
		(layer "F.Cu")
		(net "GND")
	)
	(segment
		(start 125.465195 154.2818)
		(end 125.486995 154.3036)
		(width 0.508)
		(layer "F.Cu")
		(net "GND")
	)
	(segment
		(start 149.996185 122.07102)
		(end 151.218315 122.07102)
		(width 0.2032)
		(layer "F.Cu")
		(net "GND")
	)
	(segment
		(start 149.996175 112.07103)
		(end 151.218325 112.07103)
		(width 0.2032)
		(layer "F.Cu")
		(net "GND")
	)
	(segment
		(start 84.988595 123.8286)
		(end 85.038595 123.7786)
		(width 0.2032)
		(layer "F.Cu")
		(net "GND")
	)
	(segment
		(start 220.288595 92.6786)
		(end 222.364875 92.6786)
		(width 0.254)
		(layer "F.Cu")
		(net "GND")
	)
	(segment
		(start 189.488595 88.0786)
		(end 190.088595 88.0786)
		(width 0.2032)
		(layer "F.Cu")
		(net "GND")
	)
	(segment
		(start 147.213595 88.5036)
		(end 147.286995 88.4302)
		(width 0.2032)
		(layer "F.Cu")
		(net "GND")
	)
	(segment
		(start 127.132225 157.07224)
		(end 127.132225 155.99134)
		(width 0.508)
		(layer "F.Cu")
		(net "GND")
	)
	(segment
		(start 70.238595 105.0786)
		(end 71.738595 105.0786)
		(width 0.2032)
		(layer "F.Cu")
		(net "GND")
	)
	(segment
		(start 71.871595 113.8664)
		(end 71.871595 112.4866)
		(width 0.3048)
		(layer "F.Cu")
		(net "GND")
	)
	(segment
		(start 116.913595 99.19854)
		(end 116.913595 99.14356)
		(width 0.2032)
		(layer "F.Cu")
		(net "GND")
	)
	(segment
		(start 127.688485 132.6337)
		(end 127.788595 132.53359)
		(width 0.2032)
		(layer "F.Cu")
		(net "GND")
	)
	(segment
		(start 102.148465 115.05893)
		(end 103.613025 115.05893)
		(width 0.254)
		(layer "F.Cu")
		(net "GND")
	)
	(segment
		(start 102.147195 115.0602)
		(end 102.148465 115.05893)
		(width 0.254)
		(layer "F.Cu")
		(net "GND")
	)
	(segment
		(start 112.740855 69.72635)
		(end 113.728335 69.72635)
		(width 0.2032)
		(layer "F.Cu")
		(net "GND")
	)
	(segment
		(start 119.488595 99.13359)
		(end 119.488595 99.0786)
		(width 0.2032)
		(layer "F.Cu")
		(net "GND")
	)
	(segment
		(start 102.223395 112.571)
		(end 102.235585 112.55881)
		(width 0.254)
		(layer "F.Cu")
		(net "GND")
	)
	(segment
		(start 144.238595 92.0786)
		(end 145.738595 92.0786)
		(width 0.2032)
		(layer "F.Cu")
		(net "GND")
	)
	(segment
		(start 132.488595 89.0786)
		(end 133.988595 89.0786)
		(width 0.2032)
		(layer "F.Cu")
		(net "GND")
	)
	(segment
		(start 116.688245 97.92895)
		(end 116.688245 96.61847)
		(width 0.2032)
		(layer "F.Cu")
		(net "GND")
	)
	(segment
		(start 220.088595 87.0786)
		(end 220.088595 85.5786)
		(width 0.508)
		(layer "F.Cu")
		(net "GND")
	)
	(segment
		(start 131.655595 97.97841)
		(end 131.671905 97.9621)
		(width 0.2032)
		(layer "F.Cu")
		(net "GND")
	)
	(segment
		(start 129.164985 100.64488)
		(end 129.188355 100.66825)
		(width 0.2032)
		(layer "F.Cu")
		(net "GND")
	)
	(segment
		(start 85.438595 132.5786)
		(end 85.488605 132.5286)
		(width 0.2032)
		(layer "F.Cu")
		(net "GND")
	)
	(segment
		(start 129.188355 96.61847)
		(end 129.211715 96.64184)
		(width 0.2032)
		(layer "F.Cu")
		(net "GND")
	)
	(segment
		(start 130.938595 88.3286)
		(end 131.188595 88.5786)
		(width 0.2032)
		(layer "F.Cu")
		(net "GND")
	)
	(segment
		(start 86.938595 96.1286)
		(end 87.688595 96.1286)
		(width 0.2032)
		(layer "F.Cu")
		(net "GND")
	)
	(segment
		(start 159.499975 118.51224)
		(end 159.554955 118.51224)
		(width 0.2032)
		(layer "F.Cu")
		(net "GND")
	)
	(segment
		(start 228.535995 114.0738)
		(end 229.365595 114.0738)
		(width 0.254)
		(layer "F.Cu")
		(net "GND")
	)
	(segment
		(start 118.116725 157.71574)
		(end 118.116725 154.55673)
		(width 0.508)
		(layer "F.Cu")
		(net "GND")
	)
	(segment
		(start 149.996235 114.57096)
		(end 151.218255 114.57096)
		(width 0.2032)
		(layer "F.Cu")
		(net "GND")
	)
	(segment
		(start 116.688245 100.66825)
		(end 116.688245 99.42389)
		(width 0.2032)
		(layer "F.Cu")
		(net "GND")
	)
	(segment
		(start 149.263595 87.8536)
		(end 149.263595 86.8536)
		(width 0.2032)
		(layer "F.Cu")
		(net "GND")
	)
	(segment
		(start 127.132225 155.99134)
		(end 127.158575 156.0177)
		(width 0.508)
		(layer "F.Cu")
		(net "GND")
	)
	(segment
		(start 123.143085 154.37508)
		(end 123.158585 154.35959)
		(width 0.508)
		(layer "F.Cu")
		(net "GND")
	)
	(segment
		(start 119.188375 99.43381)
		(end 119.488595 99.13359)
		(width 0.2032)
		(layer "F.Cu")
		(net "GND")
	)
	(segment
		(start 99.563255 125.05891)
		(end 100.936885 125.05891)
		(width 0.254)
		(layer "F.Cu")
		(net "GND")
	)
	(segment
		(start 71.838595 112.4536)
		(end 71.871595 112.4866)
		(width 0.3048)
		(layer "F.Cu")
		(net "GND")
	)
	(segment
		(start 85.038595 121.0286)
		(end 85.488595 120.5786)
		(width 0.2032)
		(layer "F.Cu")
		(net "GND")
	)
	(segment
		(start 124.246595 99.13359)
		(end 124.246595 99.0786)
		(width 0.2032)
		(layer "F.Cu")
		(net "GND")
	)
	(segment
		(start 126.671595 99.1536)
		(end 126.679915 99.16192)
		(width 0.2032)
		(layer "F.Cu")
		(net "GND")
	)
	(segment
		(start 124.688485 133.58087)
		(end 124.688485 132.61995)
		(width 0.254)
		(layer "F.Cu")
		(net "GND")
	)
	(segment
		(start 109.083615 69.7286)
		(end 109.183615 69.8286)
		(width 0.2032)
		(layer "F.Cu")
		(net "GND")
	)
	(segment
		(start 71.588595 132.0786)
		(end 71.738595 131.9286)
		(width 0.2032)
		(layer "F.Cu")
		(net "GND")
	)
	(segment
		(start 147.183705 122.07102)
		(end 148.481015 122.07102)
		(width 0.2032)
		(layer "F.Cu")
		(net "GND")
	)
	(segment
		(start 86.488595 109.8286)
		(end 86.688595 109.6286)
		(width 0.2032)
		(layer "F.Cu")
		(net "GND")
	)
	(segment
		(start 86.688595 111.5286)
		(end 87.688595 111.5286)
		(width 0.2032)
		(layer "F.Cu")
		(net "GND")
	)
	(segment
		(start 129.588595 154.1786)
		(end 130.057215 154.64722)
		(width 0.508)
		(layer "F.Cu")
		(net "GND")
	)
	(segment
		(start 119.688495 134.22882)
		(end 119.688545 134.22877)
		(width 0.2032)
		(layer "F.Cu")
		(net "GND")
	)
	(segment
		(start 102.147195 122.5786)
		(end 102.167005 122.55879)
		(width 0.254)
		(layer "F.Cu")
		(net "GND")
	)
	(segment
		(start 226.893595 118.0786)
		(end 226.948595 118.1336)
		(width 0.2032)
		(layer "F.Cu")
		(net "GND")
	)
	(segment
		(start 149.988595 112.0786)
		(end 149.996175 112.07103)
		(width 0.2032)
		(layer "F.Cu")
		(net "GND")
	)
	(segment
		(start 125.486995 154.3036)
		(end 125.840995 154.3036)
		(width 0.508)
		(layer "F.Cu")
		(net "GND")
	)
	(segment
		(start 126.138575 157.0786)
		(end 126.138575 154.60118)
		(width 0.508)
		(layer "F.Cu")
		(net "GND")
	)
	(segment
		(start 130.057215 156.99725)
		(end 130.138565 157.0786)
		(width 0.508)
		(layer "F.Cu")
		(net "GND")
	)
	(segment
		(start 160.847875 118.18788)
		(end 162.071115 118.18788)
		(width 0.2032)
		(layer "F.Cu")
		(net "GND")
	)
	(segment
		(start 131.671905 97.9621)
		(end 131.671905 96.63478)
		(width 0.2032)
		(layer "F.Cu")
		(net "GND")
	)
	(segment
		(start 126.711595 97.9516)
		(end 126.738595 97.9786)
		(width 0.2032)
		(layer "F.Cu")
		(net "GND")
	)
	(segment
		(start 87.238595 113.7786)
		(end 87.238595 112.8286)
		(width 0.2032)
		(layer "F.Cu")
		(net "GND")
	)
	(segment
		(start 121.158585 157.7576)
		(end 121.158585 155.05901)
		(width 0.508)
		(layer "F.Cu")
		(net "GND")
	)
	(segment
		(start 147.183765 114.57096)
		(end 148.480955 114.57096)
		(width 0.2032)
		(layer "F.Cu")
		(net "GND")
	)
	(segment
		(start 121.688415 99.15378)
		(end 121.688595 99.1536)
		(width 0.2032)
		(layer "F.Cu")
		(net "GND")
	)
	(segment
		(start 87.188595 100.3286)
		(end 87.238595 100.2786)
		(width 0.2032)
		(layer "F.Cu")
		(net "GND")
	)
	(segment
		(start 118.116725 157.71574)
		(end 118.158595 157.7576)
		(width 0.508)
		(layer "F.Cu")
		(net "GND")
	)
	(segment
		(start 71.838595 125.6536)
		(end 71.871595 125.6866)
		(width 0.3048)
		(layer "F.Cu")
		(net "GND")
	)
	(segment
		(start 182.643615 90.7336)
		(end 182.988595 91.07858)
		(width 0.2032)
		(layer "F.Cu")
		(net "GND")
	)
	(segment
		(start 220.229395 98.0278)
		(end 222.339995 98.0278)
		(width 0.254)
		(layer "F.Cu")
		(net "GND")
	)
	(segment
		(start 71.838595 96.1036)
		(end 71.849355 96.09284)
		(width 0.3048)
		(layer "F.Cu")
		(net "GND")
	)
	(segment
		(start 100.288475 122.55676)
		(end 100.292035 122.5532)
		(width 0.254)
		(layer "F.Cu")
		(net "GND")
	)
	(segment
		(start 217.869595 99.8456)
		(end 219.836595 99.8456)
		(width 0.254)
		(layer "F.Cu")
		(net "GND")
	)
	(segment
		(start 119.788595 136.93358)
		(end 119.788595 136.8786)
		(width 0.2032)
		(layer "F.Cu")
		(net "GND")
	)
	(segment
		(start 100.922915 120.05892)
		(end 100.927995 120.064)
		(width 0.254)
		(layer "F.Cu")
		(net "GND")
	)
	(segment
		(start 86.688595 109.6286)
		(end 87.688595 109.6286)
		(width 0.2032)
		(layer "F.Cu")
		(net "GND")
	)
	(segment
		(start 107.142105 157.74109)
		(end 107.158615 157.7576)
		(width 0.508)
		(layer "F.Cu")
		(net "GND")
	)
	(segment
		(start 148.238595 87.8286)
		(end 149.238595 87.8286)
		(width 0.2032)
		(layer "F.Cu")
		(net "GND")
	)
	(segment
		(start 129.163595 99.91189)
		(end 129.163595 99.1536)
		(width 0.2032)
		(layer "F.Cu")
		(net "GND")
	)
	(segment
		(start 127.158575 157.7576)
		(end 127.158575 156.0177)
		(width 0.508)
		(layer "F.Cu")
		(net "GND")
	)
	(segment
		(start 110.158605 157.7576)
		(end 110.158605 154.34359)
		(width 0.508)
		(layer "F.Cu")
		(net "GND")
	)
	(segment
		(start 102.223395 117.7616)
		(end 102.264635 117.7616)
		(width 0.254)
		(layer "F.Cu")
		(net "GND")
	)
	(segment
		(start 100.936885 125.05891)
		(end 100.953395 125.0424)
		(width 0.254)
		(layer "F.Cu")
		(net "GND")
	)
	(segment
		(start 129.188605 132.63358)
		(end 129.288595 132.53359)
		(width 0.2032)
		(layer "F.Cu")
		(net "GND")
	)
	(segment
		(start 126.679915 100.65993)
		(end 126.688225 100.66825)
		(width 0.2032)
		(layer "F.Cu")
		(net "GND")
	)
	(segment
		(start 147.713595 89.8036)
		(end 149.238595 91.3286)
		(width 0.2032)
		(layer "F.Cu")
		(net "GND")
	)
	(segment
		(start 147.313595 144.2786)
		(end 147.713595 144.2786)
		(width 0.2032)
		(layer "F.Cu")
		(net "GND")
	)
	(segment
		(start 85.988595 135.0786)
		(end 86.188595 135.2786)
		(width 0.2032)
		(layer "F.Cu")
		(net "GND")
	)
	(segment
		(start 117.288595 136.93358)
		(end 117.288595 136.8786)
		(width 0.2032)
		(layer "F.Cu")
		(net "GND")
	)
	(segment
		(start 102.225935 110.05894)
		(end 103.613025 110.05894)
		(width 0.254)
		(layer "F.Cu")
		(net "GND")
	)
	(segment
		(start 147.183695 112.07103)
		(end 148.481025 112.07103)
		(width 0.2032)
		(layer "F.Cu")
		(net "GND")
	)
	(segment
		(start 85.738595 121.8286)
		(end 86.238595 122.3286)
		(width 0.2032)
		(layer "F.Cu")
		(net "GND")
	)
	(segment
		(start 100.886755 117.7616)
		(end 100.927995 117.7616)
		(width 0.254)
		(layer "F.Cu")
		(net "GND")
	)
	(segment
		(start 133.608465 154.1786)
		(end 133.919345 154.53599)
		(width 0.508)
		(layer "F.Cu")
		(net "GND")
	)
	(segment
		(start 134.238595 88.8286)
		(end 134.238595 88.01239)
		(width 0.2032)
		(layer "F.Cu")
		(net "GND")
	)
	(segment
		(start 99.238595 56.52361)
		(end 99.537595 56.22461)
		(width 0.2032)
		(layer "F.Cu")
		(net "GND")
	)
	(segment
		(start 160.488595 117.8286)
		(end 160.847875 118.18788)
		(width 0.2032)
		(layer "F.Cu")
		(net "GND")
	)
	(segment
		(start 112.088595 143.0786)
		(end 113.488595 143.0786)
		(width 0.2032)
		(layer "F.Cu")
		(net "GND")
	)
	(segment
		(start 132.188595 134.22882)
		(end 132.188595 132.4786)
		(width 0.2032)
		(layer "F.Cu")
		(net "GND")
	)
	(segment
		(start 147.176125 122.06343)
		(end 147.183705 122.07102)
		(width 0.2032)
		(layer "F.Cu")
		(net "GND")
	)
	(segment
		(start 182.988595 91.8366)
		(end 182.988595 91.07858)
		(width 0.2032)
		(layer "F.Cu")
		(net "GND")
	)
	(segment
		(start 87.188595 113.8286)
		(end 87.238595 113.7786)
		(width 0.2032)
		(layer "F.Cu")
		(net "GND")
	)
	(segment
		(start 129.211715 97.95172)
		(end 129.238595 97.9786)
		(width 0.2032)
		(layer "F.Cu")
		(net "GND")
	)
	(segment
		(start 71.838595 139.0536)
		(end 71.871595 139.0866)
		(width 0.3048)
		(layer "F.Cu")
		(net "GND")
	)
	(segment
		(start 147.176125 114.56332)
		(end 147.183765 114.57096)
		(width 0.2032)
		(layer "F.Cu")
		(net "GND")
	)
	(segment
		(start 121.688235 100.66825)
		(end 121.688415 100.66807)
		(width 0.2032)
		(layer "F.Cu")
		(net "GND")
	)
	(segment
		(start 226.861195 125.7282)
		(end 226.875595 125.7138)
		(width 0.254)
		(layer "F.Cu")
		(net "GND")
	)
	(segment
		(start 220.288595 96.1786)
		(end 222.339995 96.1786)
		(width 0.254)
		(layer "F.Cu")
		(net "GND")
	)
	(segment
		(start 130.057215 156.99725)
		(end 130.057215 154.64722)
		(width 0.508)
		(layer "F.Cu")
		(net "GND")
	)
	(segment
		(start 148.480945 124.57095)
		(end 148.488595 124.5786)
		(width 0.2032)
		(layer "F.Cu")
		(net "GND")
	)
	(segment
		(start 220.018595 94.3786)
		(end 220.288595 94.3786)
		(width 0.254)
		(layer "F.Cu")
		(net "GND")
	)
	(segment
		(start 99.537595 56.22461)
		(end 99.537595 53.3616)
		(width 0.2032)
		(layer "F.Cu")
		(net "GND")
	)
	(segment
		(start 233.909595 107.3386)
		(end 234.989195 107.3386)
		(width 0.254)
		(layer "F.Cu")
		(net "GND")
	)
	(segment
		(start 119.188375 100.66825)
		(end 119.188375 99.43381)
		(width 0.2032)
		(layer "F.Cu")
		(net "GND")
	)
	(segment
		(start 87.688595 98.8786)
		(end 87.688595 98.0286)
		(width 0.2032)
		(layer "F.Cu")
		(net "GND")
	)
	(segment
		(start 101.041785 112.55881)
		(end 101.054995 112.5456)
		(width 0.254)
		(layer "F.Cu")
		(net "GND")
	)
	(segment
		(start 226.875595 125.7138)
		(end 226.875595 124.4836)
		(width 0.254)
		(layer "F.Cu")
		(net "GND")
	)
	(segment
		(start 151.218255 119.57096)
		(end 151.225895 119.56331)
		(width 0.2032)
		(layer "F.Cu")
		(net "GND")
	)
	(segment
		(start 127.132225 155.99134)
		(end 127.132225 154.57938)
		(width 0.508)
		(layer "F.Cu")
		(net "GND")
	)
	(segment
		(start 236.288595 113.5412)
		(end 236.288595 112.8686)
		(width 0.2032)
		(layer "F.Cu")
		(net "GND")
	)
	(segment
		(start 147.183755 109.57096)
		(end 148.480965 109.57096)
		(width 0.2032)
		(layer "F.Cu")
		(net "GND")
	)
	(segment
		(start 217.888595 87.0786)
		(end 217.888595 85.5786)
		(width 0.508)
		(layer "F.Cu")
		(net "GND")
	)
	(segment
		(start 151.488595 85.5786)
		(end 151.488595 83.5866)
		(width 0.2032)
		(layer "F.Cu")
		(net "GND")
	)
	(segment
		(start 137.488595 88.5786)
		(end 139.476095 88.5786)
		(width 0.2032)
		(layer "F.Cu")
		(net "GND")
	)
	(segment
		(start 109.183615 69.8286)
		(end 109.238595 69.8286)
		(width 0.2032)
		(layer "F.Cu")
		(net "GND")
	)
	(segment
		(start 117.188625 138.2786)
		(end 117.188625 137.03355)
		(width 0.2032)
		(layer "F.Cu")
		(net "GND")
	)
	(segment
		(start 129.163595 99.91189)
		(end 129.164985 99.91327)
		(width 0.2032)
		(layer "F.Cu")
		(net "GND")
	)
	(segment
		(start 86.488595 97.8286)
		(end 86.688595 98.0286)
		(width 0.2032)
		(layer "F.Cu")
		(net "GND")
	)
	(segment
		(start 234.989195 107.3386)
		(end 235.014595 107.364)
		(width 0.254)
		(layer "F.Cu")
		(net "GND")
	)
	(segment
		(start 149.988595 122.0786)
		(end 149.996185 122.07102)
		(width 0.2032)
		(layer "F.Cu")
		(net "GND")
	)
	(segment
		(start 71.849355 96.09284)
		(end 71.849355 94.69379)
		(width 0.3048)
		(layer "F.Cu")
		(net "GND")
	)
	(segment
		(start 100.292035 122.5532)
		(end 100.927995 122.5532)
		(width 0.254)
		(layer "F.Cu")
		(net "GND")
	)
	(segment
		(start 134.044715 156.98475)
		(end 134.044715 154.87014)
		(width 0.508)
		(layer "F.Cu")
		(net "GND")
	)
	(segment
		(start 124.788595 132.51984)
		(end 124.788595 132.4786)
		(width 0.254)
		(layer "F.Cu")
		(net "GND")
	)
	(segment
		(start 121.158585 155.05901)
		(end 121.158585 155.05901)
		(width 0.508)
		(layer "F.Cu")
		(net "GND")
	)
	(segment
		(start 149.992175 117.06702)
		(end 151.222315 117.06702)
		(width 0.2032)
		(layer "F.Cu")
		(net "GND")
	)
	(segment
		(start 158.071115 118.69588)
		(end 159.316325 118.69588)
		(width 0.2032)
		(layer "F.Cu")
		(net "GND")
	)
	(segment
		(start 227.405595 105.3066)
		(end 227.648595 105.5496)
		(width 0.254)
		(layer "F.Cu")
		(net "GND")
	)
	(segment
		(start 129.211715 97.95172)
		(end 129.211715 96.64184)
		(width 0.2032)
		(layer "F.Cu")
		(net "GND")
	)
	(segment
		(start 131.671905 100.65194)
		(end 131.671905 99.16016)
		(width 0.2032)
		(layer "F.Cu")
		(net "GND")
	)
	(segment
		(start 134.044715 154.87014)
		(end 134.044715 154.87014)
		(width 0.508)
		(layer "F.Cu")
		(net "GND")
	)
	(segment
		(start 141.238595 91.8286)
		(end 141.238595 89.8411)
		(width 0.2032)
		(layer "F.Cu")
		(net "GND")
	)
	(segment
		(start 99.563255 122.55879)
		(end 99.565285 122.55676)
		(width 0.254)
		(layer "F.Cu")
		(net "GND")
	)
	(segment
		(start 131.988595 88.5786)
		(end 132.488595 89.0786)
		(width 0.2032)
		(layer "F.Cu")
		(net "GND")
	)
	(segment
		(start 101.027055 110.05894)
		(end 101.029595 110.0564)
		(width 0.254)
		(layer "F.Cu")
		(net "GND")
	)
	(via
		(at 149.988595 112.0786)
		(size 0.4064)
		(drill 0.2032)
		(layers "F.Cu" "B.Cu")
		(tenting
			(front yes)
			(back yes)
		)
		(net "GND")
	)
	(via
		(at 127.488595 68.5786)
		(size 0.4064)
		(drill 0.2032)
		(layers "F.Cu" "B.Cu")
		(tenting
			(front yes)
			(back yes)
		)
		(net "GND")
	)
	(via
		(at 125.465195 154.2818)
		(size 0.4064)
		(drill 0.2032)
		(layers "F.Cu" "B.Cu")
		(tenting
			(front yes)
			(back yes)
		)
		(net "GND")
	)
	(via
		(at 122.288595 132.48857)
		(size 0.4064)
		(drill 0.2032)
		(layers "F.Cu" "B.Cu")
		(tenting
			(front yes)
			(back yes)
		)
		(net "GND")
	)
	(via
		(at 190.488595 84.8286)
		(size 0.4064)
		(drill 0.2032)
		(layers "F.Cu" "B.Cu")
		(tenting
			(front yes)
			(back yes)
		)
		(net "GND")
	)
	(via
		(at 102.223395 110.0564)
		(size 0.4064)
		(drill 0.2032)
		(layers "F.Cu" "B.Cu")
		(tenting
			(front yes)
			(back yes)
		)
		(net "GND")
	)
	(via
		(at 88.988595 109.5786)
		(size 0.4064)
		(drill 0.2032)
		(layers "F.Cu" "B.Cu")
		(tenting
			(front yes)
			(back yes)
		)
		(net "GND")
	)
	(via
		(at 117.158595 154.3286)
		(size 0.4064)
		(drill 0.2032)
		(layers "F.Cu" "B.Cu")
		(tenting
			(front yes)
			(back yes)
		)
		(net "GND")
	)
	(via
		(at 151.488595 83.5866)
		(size 0.4064)
		(drill 0.2032)
		(layers "F.Cu" "B.Cu")
		(tenting
			(front yes)
			(back yes)
		)
		(net "GND")
	)
	(via
		(at 188.738595 89.5786)
		(size 0.4064)
		(drill 0.2032)
		(layers "F.Cu" "B.Cu")
		(tenting
			(front yes)
			(back yes)
		)
		(net "GND")
	)
	(via
		(at 217.888595 85.5786)
		(size 0.4064)
		(drill 0.2032)
		(layers "F.Cu" "B.Cu")
		(tenting
			(front yes)
			(back yes)
		)
		(net "GND")
	)
	(via
		(at 127.238595 82.0706)
		(size 0.4064)
		(drill 0.2032)
		(layers "F.Cu" "B.Cu")
		(tenting
			(front yes)
			(back yes)
		)
		(net "GND")
	)
	(via
		(at 129.608475 154.1786)
		(size 0.4064)
		(drill 0.2032)
		(layers "F.Cu" "B.Cu")
		(tenting
			(front yes)
			(back yes)
		)
		(net "GND")
	)
	(via
		(at 117.188625 132.47863)
		(size 0.4064)
		(drill 0.2032)
		(layers "F.Cu" "B.Cu")
		(tenting
			(front yes)
			(back yes)
		)
		(net "GND")
	)
	(via
		(at 149.988595 114.5786)
		(size 0.4064)
		(drill 0.2032)
		(layers "F.Cu" "B.Cu")
		(tenting
			(front yes)
			(back yes)
		)
		(net "GND")
	)
	(via
		(at 228.664595 112.7996)
		(size 0.4064)
		(drill 0.2032)
		(layers "F.Cu" "B.Cu")
		(tenting
			(front yes)
			(back yes)
		)
		(net "GND")
	)
	(via
		(at 132.188595 132.4786)
		(size 0.4064)
		(drill 0.2032)
		(layers "F.Cu" "B.Cu")
		(tenting
			(front yes)
			(back yes)
		)
		(net "GND")
	)
	(via
		(at 100.133615 69.7786)
		(size 0.4064)
		(drill 0.2032)
		(layers "F.Cu" "B.Cu")
		(tenting
			(front yes)
			(back yes)
		)
		(net "GND")
	)
	(via
		(at 104.647355 69.7786)
		(size 0.4064)
		(drill 0.2032)
		(layers "F.Cu" "B.Cu")
		(tenting
			(front yes)
			(back yes)
		)
		(net "GND")
	)
	(via
		(at 71.871595 140.511)
		(size 0.4064)
		(drill 0.2032)
		(layers "F.Cu" "B.Cu")
		(tenting
			(front yes)
			(back yes)
		)
		(net "GND")
	)
	(via
		(at 71.871595 113.8664)
		(size 0.4064)
		(drill 0.2032)
		(layers "F.Cu" "B.Cu")
		(tenting
			(front yes)
			(back yes)
		)
		(net "GND")
	)
	(via
		(at 88.988595 96.0786)
		(size 0.4064)
		(drill 0.2032)
		(layers "F.Cu" "B.Cu")
		(tenting
			(front yes)
			(back yes)
		)
		(net "GND")
	)
	(via
		(at 226.861195 125.7282)
		(size 0.4064)
		(drill 0.2032)
		(layers "F.Cu" "B.Cu")
		(tenting
			(front yes)
			(back yes)
		)
		(net "GND")
	)
	(via
		(at 148.488595 114.5786)
		(size 0.4064)
		(drill 0.2032)
		(layers "F.Cu" "B.Cu")
		(tenting
			(front yes)
			(back yes)
		)
		(net "GND")
	)
	(via
		(at 222.339995 90.9786)
		(size 0.4064)
		(drill 0.2032)
		(layers "F.Cu" "B.Cu")
		(tenting
			(front yes)
			(back yes)
		)
		(net "GND")
	)
	(via
		(at 235.751195 114.0786)
		(size 0.4064)
		(drill 0.2032)
		(layers "F.Cu" "B.Cu")
		(tenting
			(front yes)
			(back yes)
		)
		(net "GND")
	)
	(via
		(at 109.238595 69.8286)
		(size 0.4064)
		(drill 0.2032)
		(layers "F.Cu" "B.Cu")
		(tenting
			(front yes)
			(back yes)
		)
		(net "GND")
	)
	(via
		(at 109.738595 141.0786)
		(size 0.4064)
		(drill 0.2032)
		(layers "F.Cu" "B.Cu")
		(tenting
			(front yes)
			(back yes)
		)
		(net "GND")
	)
	(via
		(at 120.643785 154.41678)
		(size 0.4064)
		(drill 0.2032)
		(layers "F.Cu" "B.Cu")
		(tenting
			(front yes)
			(back yes)
		)
		(net "GND")
	)
	(via
		(at 124.698335 136.90826)
		(size 0.4064)
		(drill 0.2032)
		(layers "F.Cu" "B.Cu")
		(tenting
			(front yes)
			(back yes)
		)
		(net "GND")
	)
	(via
		(at 147.351195 143.2542)
		(size 0.4064)
		(drill 0.2032)
		(layers "F.Cu" "B.Cu")
		(tenting
			(front yes)
			(back yes)
		)
		(net "GND")
	)
	(via
		(at 129.163595 99.1536)
		(size 0.4064)
		(drill 0.2032)
		(layers "F.Cu" "B.Cu")
		(tenting
			(front yes)
			(back yes)
		)
		(net "GND")
	)
	(via
		(at 132.288595 136.7786)
		(size 0.4064)
		(drill 0.2032)
		(layers "F.Cu" "B.Cu")
		(tenting
			(front yes)
			(back yes)
		)
		(net "GND")
	)
	(via
		(at 149.988595 109.5786)
		(size 0.4064)
		(drill 0.2032)
		(layers "F.Cu" "B.Cu")
		(tenting
			(front yes)
			(back yes)
		)
		(net "GND")
	)
	(via
		(at 127.788595 132.4786)
		(size 0.4064)
		(drill 0.2032)
		(layers "F.Cu" "B.Cu")
		(tenting
			(front yes)
			(back yes)
		)
		(net "GND")
	)
	(via
		(at 100.927995 117.7616)
		(size 0.4064)
		(drill 0.2032)
		(layers "F.Cu" "B.Cu")
		(tenting
			(front yes)
			(back yes)
		)
		(net "GND")
	)
	(via
		(at 102.223395 117.7616)
		(size 0.4064)
		(drill 0.2032)
		(layers "F.Cu" "B.Cu")
		(tenting
			(front yes)
			(back yes)
		)
		(net "GND")
	)
	(via
		(at 131.655595 99.14385)
		(size 0.4064)
		(drill 0.2032)
		(layers "F.Cu" "B.Cu")
		(tenting
			(front yes)
			(back yes)
		)
		(net "GND")
	)
	(via
		(at 113.488595 143.0786)
		(size 0.4064)
		(drill 0.2032)
		(layers "F.Cu" "B.Cu")
		(tenting
			(front yes)
			(back yes)
		)
		(net "GND")
	)
	(via
		(at 69.988595 132.0786)
		(size 0.4064)
		(drill 0.2032)
		(layers "F.Cu" "B.Cu")
		(tenting
			(front yes)
			(back yes)
		)
		(net "GND")
	)
	(via
		(at 119.788595 136.8786)
		(size 0.4064)
		(drill 0.2032)
		(layers "F.Cu" "B.Cu")
		(tenting
			(front yes)
			(back yes)
		)
		(net "GND")
	)
	(via
		(at 119.488595 99.0786)
		(size 0.4064)
		(drill 0.2032)
		(layers "F.Cu" "B.Cu")
		(tenting
			(front yes)
			(back yes)
		)
		(net "GND")
	)
	(via
		(at 148.488595 109.5786)
		(size 0.4064)
		(drill 0.2032)
		(layers "F.Cu" "B.Cu")
		(tenting
			(front yes)
			(back yes)
		)
		(net "GND")
	)
	(via
		(at 131.238595 77.3286)
		(size 0.4064)
		(drill 0.2032)
		(layers "F.Cu" "B.Cu")
		(tenting
			(front yes)
			(back yes)
		)
		(net "GND")
	)
	(via
		(at 124.788595 132.4786)
		(size 0.4064)
		(drill 0.2032)
		(layers "F.Cu" "B.Cu")
		(tenting
			(front yes)
			(back yes)
		)
		(net "GND")
	)
	(via
		(at 102.223395 112.571)
		(size 0.4064)
		(drill 0.2032)
		(layers "F.Cu" "B.Cu")
		(tenting
			(front yes)
			(back yes)
		)
		(net "GND")
	)
	(via
		(at 100.927995 120.064)
		(size 0.4064)
		(drill 0.2032)
		(layers "F.Cu" "B.Cu")
		(tenting
			(front yes)
			(back yes)
		)
		(net "GND")
	)
	(via
		(at 191.988595 91.5786)
		(size 0.4064)
		(drill 0.2032)
		(layers "F.Cu" "B.Cu")
		(tenting
			(front yes)
			(back yes)
		)
		(net "GND")
	)
	(via
		(at 212.129195 105.4336)
		(size 0.4064)
		(drill 0.2032)
		(layers "F.Cu" "B.Cu")
		(tenting
			(front yes)
			(back yes)
		)
		(net "GND")
	)
	(via
		(at 123.158585 154.35959)
		(size 0.4064)
		(drill 0.2032)
		(layers "F.Cu" "B.Cu")
		(tenting
			(front yes)
			(back yes)
		)
		(net "GND")
	)
	(via
		(at 71.849355 94.69379)
		(size 0.4064)
		(drill 0.2032)
		(layers "F.Cu" "B.Cu")
		(tenting
			(front yes)
			(back yes)
		)
		(net "GND")
	)
	(via
		(at 222.339995 96.1786)
		(size 0.4064)
		(drill 0.2032)
		(layers "F.Cu" "B.Cu")
		(tenting
			(front yes)
			(back yes)
		)
		(net "GND")
	)
	(via
		(at 160.488595 117.8286)
		(size 0.4064)
		(drill 0.2032)
		(layers "F.Cu" "B.Cu")
		(tenting
			(front yes)
			(back yes)
		)
		(net "GND")
	)
	(via
		(at 109.988595 56.5786)
		(size 0.4064)
		(drill 0.2032)
		(layers "F.Cu" "B.Cu")
		(tenting
			(front yes)
			(back yes)
		)
		(net "GND")
	)
	(via
		(at 113.730595 69.72409)
		(size 0.4064)
		(drill 0.2032)
		(layers "F.Cu" "B.Cu")
		(tenting
			(front yes)
			(back yes)
		)
		(net "GND")
	)
	(via
		(at 119.238595 97.9786)
		(size 0.4064)
		(drill 0.2032)
		(layers "F.Cu" "B.Cu")
		(tenting
			(front yes)
			(back yes)
		)
		(net "GND")
	)
	(via
		(at 148.488595 117.0706)
		(size 0.4064)
		(drill 0.2032)
		(layers "F.Cu" "B.Cu")
		(tenting
			(front yes)
			(back yes)
		)
		(net "GND")
	)
	(via
		(at 100.953395 125.0424)
		(size 0.4064)
		(drill 0.2032)
		(layers "F.Cu" "B.Cu")
		(tenting
			(front yes)
			(back yes)
		)
		(net "GND")
	)
	(via
		(at 126.671595 99.1536)
		(size 0.4064)
		(drill 0.2032)
		(layers "F.Cu" "B.Cu")
		(tenting
			(front yes)
			(back yes)
		)
		(net "GND")
	)
	(via
		(at 142.738595 92.0786)
		(size 0.4064)
		(drill 0.2032)
		(layers "F.Cu" "B.Cu")
		(tenting
			(front yes)
			(back yes)
		)
		(net "GND")
	)
	(via
		(at 149.988595 124.5786)
		(size 0.4064)
		(drill 0.2032)
		(layers "F.Cu" "B.Cu")
		(tenting
			(front yes)
			(back yes)
		)
		(net "GND")
	)
	(via
		(at 117.288595 136.8786)
		(size 0.4064)
		(drill 0.2032)
		(layers "F.Cu" "B.Cu")
		(tenting
			(front yes)
			(back yes)
		)
		(net "GND")
	)
	(via
		(at 129.288595 132.4786)
		(size 0.4064)
		(drill 0.2032)
		(layers "F.Cu" "B.Cu")
		(tenting
			(front yes)
			(back yes)
		)
		(net "GND")
	)
	(via
		(at 220.942995 106.9576)
		(size 0.4064)
		(drill 0.2032)
		(layers "F.Cu" "B.Cu")
		(tenting
			(front yes)
			(back yes)
		)
		(net "GND")
	)
	(via
		(at 149.988595 117.0706)
		(size 0.4064)
		(drill 0.2032)
		(layers "F.Cu" "B.Cu")
		(tenting
			(front yes)
			(back yes)
		)
		(net "GND")
	)
	(via
		(at 159.554955 118.51224)
		(size 0.4064)
		(drill 0.2032)
		(layers "F.Cu" "B.Cu")
		(tenting
			(front yes)
			(back yes)
		)
		(net "GND")
	)
	(via
		(at 71.896995 134.4658)
		(size 0.4064)
		(drill 0.2032)
		(layers "F.Cu" "B.Cu")
		(tenting
			(front yes)
			(back yes)
		)
		(net "GND")
	)
	(via
		(at 226.327795 105.3066)
		(size 0.4064)
		(drill 0.2032)
		(layers "F.Cu" "B.Cu")
		(tenting
			(front yes)
			(back yes)
		)
		(net "GND")
	)
	(via
		(at 71.846195 121.1816)
		(size 0.4064)
		(drill 0.2032)
		(layers "F.Cu" "B.Cu")
		(tenting
			(front yes)
			(back yes)
		)
		(net "GND")
	)
	(via
		(at 160.477985 116.80916)
		(size 0.4064)
		(drill 0.2032)
		(layers "F.Cu" "B.Cu")
		(tenting
			(front yes)
			(back yes)
		)
		(net "GND")
	)
	(via
		(at 133.608465 154.1786)
		(size 0.4064)
		(drill 0.2032)
		(layers "F.Cu" "B.Cu")
		(tenting
			(front yes)
			(back yes)
		)
		(net "GND")
	)
	(via
		(at 71.871595 127.2014)
		(size 0.4064)
		(drill 0.2032)
		(layers "F.Cu" "B.Cu")
		(tenting
			(front yes)
			(back yes)
		)
		(net "GND")
	)
	(via
		(at 222.388595 94.3786)
		(size 0.4064)
		(drill 0.2032)
		(layers "F.Cu" "B.Cu")
		(tenting
			(front yes)
			(back yes)
		)
		(net "GND")
	)
	(via
		(at 119.688595 132.4786)
		(size 0.4064)
		(drill 0.2032)
		(layers "F.Cu" "B.Cu")
		(tenting
			(front yes)
			(back yes)
		)
		(net "GND")
	)
	(via
		(at 235.014595 107.364)
		(size 0.4064)
		(drill 0.2032)
		(layers "F.Cu" "B.Cu")
		(tenting
			(front yes)
			(back yes)
		)
		(net "GND")
	)
	(via
		(at 186.988595 88.5786)
		(size 0.4064)
		(drill 0.2032)
		(layers "F.Cu" "B.Cu")
		(tenting
			(front yes)
			(back yes)
		)
		(net "GND")
	)
	(via
		(at 217.869595 99.8456)
		(size 0.4064)
		(drill 0.2032)
		(layers "F.Cu" "B.Cu")
		(tenting
			(front yes)
			(back yes)
		)
		(net "GND")
	)
	(via
		(at 122.388595 136.8786)
		(size 0.4064)
		(drill 0.2032)
		(layers "F.Cu" "B.Cu")
		(tenting
			(front yes)
			(back yes)
		)
		(net "GND")
	)
	(via
		(at 188.738595 88.8286)
		(size 0.4064)
		(drill 0.2032)
		(layers "F.Cu" "B.Cu")
		(tenting
			(front yes)
			(back yes)
		)
		(net "GND")
	)
	(via
		(at 100.953395 115.0602)
		(size 0.4064)
		(drill 0.2032)
		(layers "F.Cu" "B.Cu")
		(tenting
			(front yes)
			(back yes)
		)
		(net "GND")
	)
	(via
		(at 225.818675 121.7341)
		(size 0.4064)
		(drill 0.2032)
		(layers "F.Cu" "B.Cu")
		(tenting
			(front yes)
			(back yes)
		)
		(net "GND")
	)
	(via
		(at 148.488595 122.0786)
		(size 0.4064)
		(drill 0.2032)
		(layers "F.Cu" "B.Cu")
		(tenting
			(front yes)
			(back yes)
		)
		(net "GND")
	)
	(via
		(at 145.738595 92.0786)
		(size 0.4064)
		(drill 0.2032)
		(layers "F.Cu" "B.Cu")
		(tenting
			(front yes)
			(back yes)
		)
		(net "GND")
	)
	(via
		(at 124.988595 82.0786)
		(size 0.4064)
		(drill 0.2032)
		(layers "F.Cu" "B.Cu")
		(tenting
			(front yes)
			(back yes)
		)
		(net "GND")
	)
	(via
		(at 225.988595 118.0786)
		(size 0.4064)
		(drill 0.2032)
		(layers "F.Cu" "B.Cu")
		(tenting
			(front yes)
			(back yes)
		)
		(net "GND")
	)
	(via
		(at 102.147195 115.0602)
		(size 0.4064)
		(drill 0.2032)
		(layers "F.Cu" "B.Cu")
		(tenting
			(front yes)
			(back yes)
		)
		(net "GND")
	)
	(via
		(at 148.488595 119.5786)
		(size 0.4064)
		(drill 0.2032)
		(layers "F.Cu" "B.Cu")
		(tenting
			(front yes)
			(back yes)
		)
		(net "GND")
	)
	(via
		(at 124.246595 99.0786)
		(size 0.4064)
		(drill 0.2032)
		(layers "F.Cu" "B.Cu")
		(tenting
			(front yes)
			(back yes)
		)
		(net "GND")
	)
	(via
		(at 121.838595 97.9786)
		(size 0.4064)
		(drill 0.2032)
		(layers "F.Cu" "B.Cu")
		(tenting
			(front yes)
			(back yes)
		)
		(net "GND")
	)
	(via
		(at 129.488595 88.3286)
		(size 0.4064)
		(drill 0.2032)
		(layers "F.Cu" "B.Cu")
		(tenting
			(front yes)
			(back yes)
		)
		(net "GND")
	)
	(via
		(at 84.188595 132.5286)
		(size 0.4064)
		(drill 0.2032)
		(layers "F.Cu" "B.Cu")
		(tenting
			(front yes)
			(back yes)
		)
		(net "GND")
	)
	(via
		(at 100.953395 122.5786)
		(size 0.4064)
		(drill 0.2032)
		(layers "F.Cu" "B.Cu")
		(tenting
			(front yes)
			(back yes)
		)
		(net "GND")
	)
	(via
		(at 137.488595 88.5786)
		(size 0.4064)
		(drill 0.2032)
		(layers "F.Cu" "B.Cu")
		(tenting
			(front yes)
			(back yes)
		)
		(net "GND")
	)
	(via
		(at 116.663595 97.9536)
		(size 0.4064)
		(drill 0.2032)
		(layers "F.Cu" "B.Cu")
		(tenting
			(front yes)
			(back yes)
		)
		(net "GND")
	)
	(via
		(at 149.988595 119.5786)
		(size 0.4064)
		(drill 0.2032)
		(layers "F.Cu" "B.Cu")
		(tenting
			(front yes)
			(back yes)
		)
		(net "GND")
	)
	(via
		(at 220.088595 85.5786)
		(size 0.4064)
		(drill 0.2032)
		(layers "F.Cu" "B.Cu")
		(tenting
			(front yes)
			(back yes)
		)
		(net "GND")
	)
	(via
		(at 148.488595 112.0786)
		(size 0.4064)
		(drill 0.2032)
		(layers "F.Cu" "B.Cu")
		(tenting
			(front yes)
			(back yes)
		)
		(net "GND")
	)
	(via
		(at 101.029595 110.0564)
		(size 0.4064)
		(drill 0.2032)
		(layers "F.Cu" "B.Cu")
		(tenting
			(front yes)
			(back yes)
		)
		(net "GND")
	)
	(via
		(at 148.488595 124.5786)
		(size 0.4064)
		(drill 0.2032)
		(layers "F.Cu" "B.Cu")
		(tenting
			(front yes)
			(back yes)
		)
		(net "GND")
	)
	(via
		(at 210.988595 98.8514)
		(size 0.4064)
		(drill 0.2032)
		(layers "F.Cu" "B.Cu")
		(tenting
			(front yes)
			(back yes)
		)
		(net "GND")
	)
	(via
		(at 222.339995 98.0278)
		(size 0.4064)
		(drill 0.2032)
		(layers "F.Cu" "B.Cu")
		(tenting
			(front yes)
			(back yes)
		)
		(net "GND")
	)
	(via
		(at 135.238595 76.0786)
		(size 0.4064)
		(drill 0.2032)
		(layers "F.Cu" "B.Cu")
		(tenting
			(front yes)
			(back yes)
		)
		(net "GND")
	)
	(via
		(at 182.988595 91.8366)
		(size 0.4064)
		(drill 0.2032)
		(layers "F.Cu" "B.Cu")
		(tenting
			(front yes)
			(back yes)
		)
		(net "GND")
	)
	(via
		(at 84.238595 119.5786)
		(size 0.4064)
		(drill 0.2032)
		(layers "F.Cu" "B.Cu")
		(tenting
			(front yes)
			(back yes)
		)
		(net "GND")
	)
	(via
		(at 121.688595 99.1536)
		(size 0.4064)
		(drill 0.2032)
		(layers "F.Cu" "B.Cu")
		(tenting
			(front yes)
			(back yes)
		)
		(net "GND")
	)
	(via
		(at 71.871595 107.9228)
		(size 0.4064)
		(drill 0.2032)
		(layers "F.Cu" "B.Cu")
		(tenting
			(front yes)
			(back yes)
		)
		(net "GND")
	)
	(via
		(at 126.188605 132.47861)
		(size 0.4064)
		(drill 0.2032)
		(layers "F.Cu" "B.Cu")
		(tenting
			(front yes)
			(back yes)
		)
		(net "GND")
	)
	(via
		(at 99.238595 56.5786)
		(size 0.4064)
		(drill 0.2032)
		(layers "F.Cu" "B.Cu")
		(tenting
			(front yes)
			(back yes)
		)
		(net "GND")
	)
	(via
		(at 110.173595 154.3286)
		(size 0.4064)
		(drill 0.2032)
		(layers "F.Cu" "B.Cu")
		(tenting
			(front yes)
			(back yes)
		)
		(net "GND")
	)
	(via
		(at 129.238595 97.9786)
		(size 0.4064)
		(drill 0.2032)
		(layers "F.Cu" "B.Cu")
		(tenting
			(front yes)
			(back yes)
		)
		(net "GND")
	)
	(via
		(at 126.738595 97.9786)
		(size 0.4064)
		(drill 0.2032)
		(layers "F.Cu" "B.Cu")
		(tenting
			(front yes)
			(back yes)
		)
		(net "GND")
	)
	(via
		(at 225.988595 119.6786)
		(size 0.4064)
		(drill 0.2032)
		(layers "F.Cu" "B.Cu")
		(tenting
			(front yes)
			(back yes)
		)
		(net "GND")
	)
	(via
		(at 107.158615 154.36162)
		(size 0.4064)
		(drill 0.2032)
		(layers "F.Cu" "B.Cu")
		(tenting
			(front yes)
			(back yes)
		)
		(net "GND")
	)
	(via
		(at 222.364875 92.6786)
		(size 0.4064)
		(drill 0.2032)
		(layers "F.Cu" "B.Cu")
		(tenting
			(front yes)
			(back yes)
		)
		(net "GND")
	)
	(via
		(at 88.488595 113.8286)
		(size 0.4064)
		(drill 0.2032)
		(layers "F.Cu" "B.Cu")
		(tenting
			(front yes)
			(back yes)
		)
		(net "GND")
	)
	(via
		(at 102.096395 125.0424)
		(size 0.4064)
		(drill 0.2032)
		(layers "F.Cu" "B.Cu")
		(tenting
			(front yes)
			(back yes)
		)
		(net "GND")
	)
	(via
		(at 149.213595 91.3036)
		(size 0.4064)
		(drill 0.2032)
		(layers "F.Cu" "B.Cu")
		(tenting
			(front yes)
			(back yes)
		)
		(net "GND")
	)
	(via
		(at 101.054995 112.5456)
		(size 0.4064)
		(drill 0.2032)
		(layers "F.Cu" "B.Cu")
		(tenting
			(front yes)
			(back yes)
		)
		(net "GND")
	)
	(via
		(at 116.913595 99.14356)
		(size 0.4064)
		(drill 0.2032)
		(layers "F.Cu" "B.Cu")
		(tenting
			(front yes)
			(back yes)
		)
		(net "GND")
	)
	(via
		(at 147.313595 144.2786)
		(size 0.4064)
		(drill 0.2032)
		(layers "F.Cu" "B.Cu")
		(tenting
			(front yes)
			(back yes)
		)
		(net "GND")
	)
	(via
		(at 225.988595 115.4786)
		(size 0.4064)
		(drill 0.2032)
		(layers "F.Cu" "B.Cu")
		(tenting
			(front yes)
			(back yes)
		)
		(net "GND")
	)
	(via
		(at 71.871595 100.506)
		(size 0.4064)
		(drill 0.2032)
		(layers "F.Cu" "B.Cu")
		(tenting
			(front yes)
			(back yes)
		)
		(net "GND")
	)
	(via
		(at 130.888595 132.4786)
		(size 0.4064)
		(drill 0.2032)
		(layers "F.Cu" "B.Cu")
		(tenting
			(front yes)
			(back yes)
		)
		(net "GND")
	)
	(via
		(at 137.488595 89.0786)
		(size 0.4064)
		(drill 0.2032)
		(layers "F.Cu" "B.Cu")
		(tenting
			(front yes)
			(back yes)
		)
		(net "GND")
	)
	(via
		(at 137.488595 88.0786)
		(size 0.4064)
		(drill 0.2032)
		(layers "F.Cu" "B.Cu")
		(tenting
			(front yes)
			(back yes)
		)
		(net "GND")
	)
	(via
		(at 137.163595 154.1786)
		(size 0.4064)
		(drill 0.2032)
		(layers "F.Cu" "B.Cu")
		(tenting
			(front yes)
			(back yes)
		)
		(net "GND")
	)
	(via
		(at 149.988595 122.0786)
		(size 0.4064)
		(drill 0.2032)
		(layers "F.Cu" "B.Cu")
		(tenting
			(front yes)
			(back yes)
		)
		(net "GND")
	)
	(via
		(at 131.655595 97.97841)
		(size 0.4064)
		(drill 0.2032)
		(layers "F.Cu" "B.Cu")
		(tenting
			(front yes)
			(back yes)
		)
		(net "GND")
	)
	(via
		(at 214.188595 90.2786)
		(size 0.4064)
		(drill 0.2032)
		(layers "F.Cu" "B.Cu")
		(tenting
			(front yes)
			(back yes)
		)
		(net "GND")
	)
	(via
		(at 124.246595 97.9786)
		(size 0.4064)
		(drill 0.2032)
		(layers "F.Cu" "B.Cu")
		(tenting
			(front yes)
			(back yes)
		)
		(net "GND")
	)
	(via
		(at 70.238595 105.0786)
		(size 0.4064)
		(drill 0.2032)
		(layers "F.Cu" "B.Cu")
		(tenting
			(front yes)
			(back yes)
		)
		(net "GND")
	)
	(via
		(at 225.988595 116.8786)
		(size 0.4064)
		(drill 0.2032)
		(layers "F.Cu" "B.Cu")
		(tenting
			(front yes)
			(back yes)
		)
		(net "GND")
	)
	(via
		(at 102.147195 122.5786)
		(size 0.4064)
		(drill 0.2032)
		(layers "F.Cu" "B.Cu")
		(tenting
			(front yes)
			(back yes)
		)
		(net "GND")
	)
	(via
		(at 88.488595 100.3286)
		(size 0.4064)
		(drill 0.2032)
		(layers "F.Cu" "B.Cu")
		(tenting
			(front yes)
			(back yes)
		)
		(net "GND")
	)
	(via
		(at 148.988595 83.5866)
		(size 0.4064)
		(drill 0.2032)
		(layers "F.Cu" "B.Cu")
		(tenting
			(front yes)
			(back yes)
		)
		(net "GND")
	)
	(via
		(at 131.597015 154.23884)
		(size 0.4064)
		(drill 0.2032)
		(layers "F.Cu" "B.Cu")
		(tenting
			(front yes)
			(back yes)
		)
		(net "GND")
	)
	(via
		(at 228.535995 114.0738)
		(size 0.4064)
		(drill 0.2032)
		(layers "F.Cu" "B.Cu")
		(tenting
			(front yes)
			(back yes)
		)
		(net "GND")
	)
	(via
		(at 102.045595 120.064)
		(size 0.4064)
		(drill 0.2032)
		(layers "F.Cu" "B.Cu")
		(tenting
			(front yes)
			(back yes)
		)
		(net "GND")
	)
	(arc
		(start 120.955918 154.653006)
		(mid 121.105102 154.832121)
		(end 121.158584 155.059007)
		(width 0.508)
		(layer "F.Cu")
		(net "GND")
	)
	(arc
		(start 133.919343 154.535981)
		(mid 134.01234 154.691687)
		(end 134.044715 154.870138)
		(width 0.508)
		(layer "F.Cu")
		(net "GND")
	)
	(segment
		(start 129.588595 154.1786)
		(end 129.608475 154.1786)
		(width 0.508)
		(layer "B.Cu")
		(net "GND")
	)
	(segment
		(start 131.921435 154.38644)
		(end 132.119715 154.58472)
		(width 0.508)
		(layer "B.Cu")
		(net "GND")
	)
	(segment
		(start 131.597015 154.23884)
		(end 131.597595 154.23889)
		(width 0.508)
		(layer "B.Cu")
		(net "GND")
	)
	(segment
		(start 120.158585 155.01903)
		(end 120.158585 155.01902)
		(width 0.508)
		(layer "B.Cu")
		(net "GND")
	)
	(segment
		(start 120.377695 154.60117)
		(end 120.643785 154.41678)
		(width 0.508)
		(layer "B.Cu")
		(net "GND")
	)
	(segment
		(start 136.194945 154.70118)
		(end 136.717525 154.1786)
		(width 0.508)
		(layer "B.Cu")
		(net "GND")
	)
	(segment
		(start 125.158575 154.58842)
		(end 125.465195 154.2818)
		(width 0.508)
		(layer "B.Cu")
		(net "GND")
	)
	(segment
		(start 107.158615 157.7576)
		(end 107.158615 154.36162)
		(width 0.508)
		(layer "B.Cu")
		(net "GND")
	)
	(segment
		(start 136.158555 157.7576)
		(end 136.169945 157.74622)
		(width 0.508)
		(layer "B.Cu")
		(net "GND")
	)
	(segment
		(start 136.717525 154.1786)
		(end 137.163595 154.1786)
		(width 0.508)
		(layer "B.Cu")
		(net "GND")
	)
	(segment
		(start 128.138575 154.47618)
		(end 128.436155 154.1786)
		(width 0.508)
		(layer "B.Cu")
		(net "GND")
	)
	(segment
		(start 128.138575 157.0786)
		(end 128.138575 154.47618)
		(width 0.508)
		(layer "B.Cu")
		(net "GND")
	)
	(segment
		(start 132.119715 157.05975)
		(end 132.138565 157.0786)
		(width 0.508)
		(layer "B.Cu")
		(net "GND")
	)
	(segment
		(start 117.158595 157.7576)
		(end 117.158595 154.3286)
		(width 0.508)
		(layer "B.Cu")
		(net "GND")
	)
	(segment
		(start 133.036965 156.977)
		(end 133.036965 154.8823)
		(width 0.508)
		(layer "B.Cu")
		(net "GND")
	)
	(segment
		(start 129.169945 157.04722)
		(end 129.169945 154.59725)
		(width 0.508)
		(layer "B.Cu")
		(net "GND")
	)
	(segment
		(start 132.119715 154.58472)
		(end 132.739385 154.58472)
		(width 0.508)
		(layer "B.Cu")
		(net "GND")
	)
	(segment
		(start 133.036965 156.977)
		(end 133.138565 157.0786)
		(width 0.508)
		(layer "B.Cu")
		(net "GND")
	)
	(segment
		(start 125.158575 157.7576)
		(end 125.158575 154.58842)
		(width 0.508)
		(layer "B.Cu")
		(net "GND")
	)
	(segment
		(start 136.194945 157.02222)
		(end 136.194945 154.70118)
		(width 0.508)
		(layer "B.Cu")
		(net "GND")
	)
	(segment
		(start 131.921035 154.38605)
		(end 131.921435 154.38644)
		(width 0.508)
		(layer "B.Cu")
		(net "GND")
	)
	(segment
		(start 136.169945 157.04721)
		(end 136.194945 157.02222)
		(width 0.508)
		(layer "B.Cu")
		(net "GND")
	)
	(segment
		(start 129.138575 157.0786)
		(end 129.169945 157.04722)
		(width 0.508)
		(layer "B.Cu")
		(net "GND")
	)
	(segment
		(start 123.158585 157.7576)
		(end 123.158585 154.35959)
		(width 0.508)
		(layer "B.Cu")
		(net "GND")
	)
	(segment
		(start 136.138555 157.0786)
		(end 136.169945 157.04721)
		(width 0.508)
		(layer "B.Cu")
		(net "GND")
	)
	(segment
		(start 129.169945 154.59725)
		(end 129.588595 154.1786)
		(width 0.508)
		(layer "B.Cu")
		(net "GND")
	)
	(segment
		(start 128.436155 154.1786)
		(end 129.588595 154.1786)
		(width 0.508)
		(layer "B.Cu")
		(net "GND")
	)
	(segment
		(start 132.739385 154.58472)
		(end 133.036965 154.8823)
		(width 0.508)
		(layer "B.Cu")
		(net "GND")
	)
	(segment
		(start 132.119715 157.05975)
		(end 132.119715 154.58472)
		(width 0.508)
		(layer "B.Cu")
		(net "GND")
	)
	(segment
		(start 120.158585 157.7576)
		(end 120.158585 155.01903)
		(width 0.508)
		(layer "B.Cu")
		(net "GND")
	)
	(segment
		(start 136.169945 157.74622)
		(end 136.169945 157.04721)
		(width 0.508)
		(layer "B.Cu")
		(net "GND")
	)
	(arc
		(start 131.597592 154.238883)
		(mid 131.772599 154.283261)
		(end 131.921033 154.386044)
		(width 0.508)
		(layer "B.Cu")
		(net "GND")
	)
	(arc
		(start 120.158585 155.019027)
		(mid 120.216684 154.783119)
		(end 120.377689 154.601169)
		(width 0.508)
		(layer "B.Cu")
		(net "GND")
	)
	(segment
		(start 105.388595 67.7286)
		(end 105.988595 68.3286)
		(width 0.3048)
		(layer "F.Cu")
		(net "FPGA_TMS")
	)
	(segment
		(start 104.838595 67.7286)
		(end 105.388595 67.7286)
		(width 0.3048)
		(layer "F.Cu")
		(net "FPGA_TMS")
	)
	(segment
		(start 99.413595 107.5286)
		(end 99.413595 104.8536)
		(width 0.2032)
		(layer "F.Cu")
		(net "FPGA_TMS")
	)
	(segment
		(start 104.488595 67.3786)
		(end 104.838595 67.7286)
		(width 0.3048)
		(layer "F.Cu")
		(net "FPGA_TMS")
	)
	(segment
		(start 105.988595 98.2786)
		(end 105.988595 69.0786)
		(width 0.2032)
		(layer "F.Cu")
		(net "FPGA_TMS")
	)
	(segment
		(start 105.988595 69.0786)
		(end 105.988595 68.3286)
		(width 0.3048)
		(layer "F.Cu")
		(net "FPGA_TMS")
	)
	(segment
		(start 104.488595 67.3786)
		(end 104.488595 66.3286)
		(width 0.3048)
		(layer "F.Cu")
		(net "FPGA_TMS")
	)
	(segment
		(start 99.413595 104.8536)
		(end 105.988595 98.2786)
		(width 0.2032)
		(layer "F.Cu")
		(net "FPGA_TMS")
	)
	(segment
		(start 102.077595 53.3616)
		(end 102.488595 53.7726)
		(width 0.2032)
		(layer "F.Cu")
		(net "+3.3V")
	)
	(segment
		(start 130.988595 90.8286)
		(end 132.238595 92.0786)
		(width 0.2032)
		(layer "F.Cu")
		(net "+3.3V")
	)
	(segment
		(start 140.238595 90.5286)
		(end 140.238595 89.8411)
		(width 0.2032)
		(layer "F.Cu")
		(net "+3.3V")
	)
	(segment
		(start 71.438595 129.8286)
		(end 71.538595 129.7286)
		(width 0.2032)
		(layer "F.Cu")
		(net "+3.3V")
	)
	(segment
		(start 142.287755 86.3186)
		(end 142.287755 86.3036)
		(width 0.2032)
		(layer "F.Cu")
		(net "+3.3V")
	)
	(segment
		(start 85.738595 115.5786)
		(end 85.746595 115.5866)
		(width 0.2032)
		(layer "F.Cu")
		(net "+3.3V")
	)
	(segment
		(start 85.738595 101.8286)
		(end 85.738595 100.3786)
		(width 0.2032)
		(layer "F.Cu")
		(net "+3.3V")
	)
	(segment
		(start 87.438595 121.8786)
		(end 87.438595 120.9286)
		(width 0.2032)
		(layer "F.Cu")
		(net "+3.3V")
	)
	(segment
		(start 142.988595 90.2036)
		(end 142.988595 89.9786)
		(width 0.2032)
		(layer "F.Cu")
		(net "+3.3V")
	)
	(segment
		(start 86.888605 132.5286)
		(end 86.988595 132.42861)
		(width 0.2032)
		(layer "F.Cu")
		(net "+3.3V")
	)
	(segment
		(start 151.163595 88.5036)
		(end 151.463595 88.2036)
		(width 0.2032)
		(layer "F.Cu")
		(net "+3.3V")
	)
	(segment
		(start 85.263595 111.5536)
		(end 85.288595 111.5286)
		(width 0.2032)
		(layer "F.Cu")
		(net "+3.3V")
	)
	(segment
		(start 86.988595 132.42861)
		(end 86.988595 130.8286)
		(width 0.2032)
		(layer "F.Cu")
		(net "+3.3V")
	)
	(segment
		(start 85.788595 100.3286)
		(end 85.788595 99.3286)
		(width 0.2032)
		(layer "F.Cu")
		(net "+3.3V")
	)
	(segment
		(start 191.938595 86.3286)
		(end 191.938595 84.8786)
		(width 0.508)
		(layer "F.Cu")
		(net "+3.3V")
	)
	(segment
		(start 104.488595 56.52361)
		(end 104.617595 56.39461)
		(width 0.2032)
		(layer "F.Cu")
		(net "+3.3V")
	)
	(segment
		(start 85.738595 117.5786)
		(end 86.988595 118.8286)
		(width 0.2032)
		(layer "F.Cu")
		(net "+3.3V")
	)
	(segment
		(start 84.988595 52.38794)
		(end 85.112255 52.5116)
		(width 0.2032)
		(layer "F.Cu")
		(net "+3.3V")
	)
	(segment
		(start 133.288595 91.9536)
		(end 133.288595 90.14481)
		(width 0.2032)
		(layer "F.Cu")
		(net "+3.3V")
	)
	(segment
		(start 218.888595 96.1536)
		(end 218.888595 94.3786)
		(width 0.508)
		(layer "F.Cu")
		(net "+3.3V")
	)
	(segment
		(start 138.738595 92.0786)
		(end 139.588595 92.0786)
		(width 0.2032)
		(layer "F.Cu")
		(net "+3.3V")
	)
	(segment
		(start 215.806115 97.4786)
		(end 215.888595 97.4786)
		(width 0.508)
		(layer "F.Cu")
		(net "+3.3V")
	)
	(segment
		(start 86.988595 120.4786)
		(end 86.988595 118.8286)
		(width 0.2032)
		(layer "F.Cu")
		(net "+3.3V")
	)
	(segment
		(start 104.651485 68.41571)
		(end 104.664375 68.40282)
		(width 0.2032)
		(layer "F.Cu")
		(net "+3.3V")
	)
	(segment
		(start 121.963595 88.5536)
		(end 121.972805 88.56281)
		(width 0.508)
		(layer "F.Cu")
		(net "+3.3V")
	)
	(segment
		(start 193.225595 86.37049)
		(end 193.663705 86.8086)
		(width 0.508)
		(layer "F.Cu")
		(net "+3.3V")
	)
	(segment
		(start 214.008795 97.3776)
		(end 215.705115 97.3776)
		(width 0.508)
		(layer "F.Cu")
		(net "+3.3V")
	)
	(segment
		(start 85.738595 113.8786)
		(end 85.788595 113.8286)
		(width 0.2032)
		(layer "F.Cu")
		(net "+3.3V")
	)
	(segment
		(start 135.688595 74.2786)
		(end 135.738595 74.3286)
		(width 0.508)
		(layer "F.Cu")
		(net "+3.3V")
	)
	(segment
		(start 147.238595 87.3536)
		(end 147.588595 87.0036)
		(width 0.2032)
		(layer "F.Cu")
		(net "+3.3V")
	)
	(segment
		(start 144.238595 90.6786)
		(end 144.338595 90.5786)
		(width 0.2032)
		(layer "F.Cu")
		(net "+3.3V")
	)
	(segment
		(start 185.488595 87.1286)
		(end 185.488595 85.5786)
		(width 0.3048)
		(layer "F.Cu")
		(net "+3.3V")
	)
	(segment
		(start 217.988595 89.5786)
		(end 217.988595 88.9786)
		(width 0.508)
		(layer "F.Cu")
		(net "+3.3V")
	)
	(segment
		(start 148.463595 88.5036)
		(end 149.263595 88.5036)
		(width 0.2032)
		(layer "F.Cu")
		(net "+3.3V")
	)
	(segment
		(start 133.163595 92.0786)
		(end 133.288595 91.9536)
		(width 0.2032)
		(layer "F.Cu")
		(net "+3.3V")
	)
	(segment
		(start 85.288595 98.8286)
		(end 85.288595 98.0286)
		(width 0.2032)
		(layer "F.Cu")
		(net "+3.3V")
	)
	(segment
		(start 104.617595 56.39461)
		(end 104.617595 55.2666)
		(width 0.2032)
		(layer "F.Cu")
		(net "+3.3V")
	)
	(segment
		(start 85.263595 112.4786)
		(end 85.263595 111.5536)
		(width 0.2032)
		(layer "F.Cu")
		(net "+3.3V")
	)
	(segment
		(start 92.738595 122.0786)
		(end 93.858595 122.0786)
		(width 0.2032)
		(layer "F.Cu")
		(net "+3.3V")
	)
	(segment
		(start 139.588595 91.1786)
		(end 140.238595 90.5286)
		(width 0.2032)
		(layer "F.Cu")
		(net "+3.3V")
	)
	(segment
		(start 217.188595 96.1786)
		(end 218.888595 96.1786)
		(width 0.508)
		(layer "F.Cu")
		(net "+3.3V")
	)
	(segment
		(start 109.199715 68.36748)
		(end 109.238595 68.3286)
		(width 0.2032)
		(layer "F.Cu")
		(net "+3.3V")
	)
	(segment
		(start 215.888595 97.4786)
		(end 217.188595 96.1786)
		(width 0.508)
		(layer "F.Cu")
		(net "+3.3V")
	)
	(segment
		(start 99.113595 68.4286)
		(end 99.117595 68.4246)
		(width 0.508)
		(layer "F.Cu")
		(net "+3.3V")
	)
	(segment
		(start 123.188595 89.7786)
		(end 130.988595 89.7786)
		(width 0.2032)
		(layer "F.Cu")
		(net "+3.3V")
	)
	(segment
		(start 85.746595 115.5866)
		(end 86.246595 115.5866)
		(width 0.2032)
		(layer "F.Cu")
		(net "+3.3V")
	)
	(segment
		(start 185.438595 87.0786)
		(end 185.488595 87.1286)
		(width 0.508)
		(layer "F.Cu")
		(net "+3.3V")
	)
	(segment
		(start 142.001095 89.5786)
		(end 142.024495 89.602)
		(width 0.2032)
		(layer "F.Cu")
		(net "+3.3V")
	)
	(segment
		(start 147.213595 89.1536)
		(end 147.813595 89.1536)
		(width 0.2032)
		(layer "F.Cu")
		(net "+3.3V")
	)
	(segment
		(start 191.938595 84.8786)
		(end 191.988595 84.8286)
		(width 0.508)
		(layer "F.Cu")
		(net "+3.3V")
	)
	(segment
		(start 86.988595 120.4786)
		(end 87.438595 120.9286)
		(width 0.2032)
		(layer "F.Cu")
		(net "+3.3V")
	)
	(segment
		(start 133.488595 74.2786)
		(end 135.688595 74.2786)
		(width 0.508)
		(layer "F.Cu")
		(net "+3.3V")
	)
	(segment
		(start 86.888605 133.5036)
		(end 86.888605 132.5286)
		(width 0.2032)
		(layer "F.Cu")
		(net "+3.3V")
	)
	(segment
		(start 112.799715 68.36748)
		(end 113.699715 68.36748)
		(width 0.2032)
		(layer "F.Cu")
		(net "+3.3V")
	)
	(segment
		(start 142.611995 89.602)
		(end 142.988595 89.9786)
		(width 0.2032)
		(layer "F.Cu")
		(net "+3.3V")
	)
	(segment
		(start 220.088595 88.8786)
		(end 222.588595 88.8786)
		(width 0.508)
		(layer "F.Cu")
		(net "+3.3V")
	)
	(segment
		(start 147.238595 87.8286)
		(end 147.238595 87.3536)
		(width 0.2032)
		(layer "F.Cu")
		(net "+3.3V")
	)
	(segment
		(start 85.738595 115.5786)
		(end 85.738595 113.8786)
		(width 0.2032)
		(layer "F.Cu")
		(net "+3.3V")
	)
	(segment
		(start 215.788595 88.9036)
		(end 215.801095 88.8911)
		(width 0.508)
		(layer "F.Cu")
		(net "+3.3V")
	)
	(segment
		(start 86.888605 133.5036)
		(end 87.388605 134.0036)
		(width 0.2032)
		(layer "F.Cu")
		(net "+3.3V")
	)
	(segment
		(start 143.738595 74.3286)
		(end 152.843615 83.43362)
		(width 0.2032)
		(layer "F.Cu")
		(net "+3.3V")
	)
	(segment
		(start 135.738595 74.3286)
		(end 142.287755 80.87775)
		(width 0.2032)
		(layer "F.Cu")
		(net "+3.3V")
	)
	(segment
		(start 142.024495 89.602)
		(end 142.611995 89.602)
		(width 0.2032)
		(layer "F.Cu")
		(net "+3.3V")
	)
	(segment
		(start 135.738595 74.3286)
		(end 138.238595 74.3286)
		(width 0.2032)
		(layer "F.Cu")
		(net "+3.3V")
	)
	(segment
		(start 151.463595 87.0036)
		(end 151.488595 86.9786)
		(width 0.2032)
		(layer "F.Cu")
		(net "+3.3V")
	)
	(segment
		(start 218.888595 94.3786)
		(end 218.888595 92.6786)
		(width 0.508)
		(layer "F.Cu")
		(net "+3.3V")
	)
	(segment
		(start 222.588595 88.8786)
		(end 223.388595 89.6786)
		(width 0.508)
		(layer "F.Cu")
		(net "+3.3V")
	)
	(segment
		(start 223.388595 89.6786)
		(end 227.885595 89.6786)
		(width 0.508)
		(layer "F.Cu")
		(net "+3.3V")
	)
	(segment
		(start 151.463595 88.2036)
		(end 151.463595 87.0036)
		(width 0.2032)
		(layer "F.Cu")
		(net "+3.3V")
	)
	(segment
		(start 90.238595 52.50759)
		(end 90.238595 51.3286)
		(width 0.2032)
		(layer "F.Cu")
		(net "+3.3V")
	)
	(segment
		(start 74.988595 51.38359)
		(end 74.988595 51.3286)
		(width 0.2032)
		(layer "F.Cu")
		(net "+3.3V")
	)
	(segment
		(start 141.238595 87.0536)
		(end 141.988595 86.3036)
		(width 0.2032)
		(layer "F.Cu")
		(net "+3.3V")
	)
	(segment
		(start 103.626485 68.41571)
		(end 104.651485 68.41571)
		(width 0.2032)
		(layer "F.Cu")
		(net "+3.3V")
	)
	(segment
		(start 149.263595 88.5036)
		(end 151.163595 88.5036)
		(width 0.2032)
		(layer "F.Cu")
		(net "+3.3V")
	)
	(segment
		(start 142.287755 86.3036)
		(end 142.287755 80.87775)
		(width 0.2032)
		(layer "F.Cu")
		(net "+3.3V")
	)
	(segment
		(start 74.867595 51.50459)
		(end 74.988595 51.38359)
		(width 0.2032)
		(layer "F.Cu")
		(net "+3.3V")
	)
	(segment
		(start 141.238595 87.8161)
		(end 141.238595 87.0536)
		(width 0.2032)
		(layer "F.Cu")
		(net "+3.3V")
	)
	(segment
		(start 181.338595 86.9236)
		(end 183.833595 86.9236)
		(width 0.508)
		(layer "F.Cu")
		(net "+3.3V")
	)
	(segment
		(start 102.488595 56.5786)
		(end 102.488595 53.7726)
		(width 0.2032)
		(layer "F.Cu")
		(net "+3.3V")
	)
	(segment
		(start 120.536175 88.5536)
		(end 121.963595 88.5536)
		(width 0.508)
		(layer "F.Cu")
		(net "+3.3V")
	)
	(segment
		(start 144.338595 90.5786)
		(end 145.738595 90.5786)
		(width 0.2032)
		(layer "F.Cu")
		(net "+3.3V")
	)
	(segment
		(start 151.526095 87.0161)
		(end 152.843615 87.0161)
		(width 0.2032)
		(layer "F.Cu")
		(net "+3.3V")
	)
	(segment
		(start 112.738595 68.4286)
		(end 112.799715 68.36748)
		(width 0.2032)
		(layer "F.Cu")
		(net "+3.3V")
	)
	(segment
		(start 147.488595 85.4786)
		(end 147.488595 83.5866)
		(width 0.2032)
		(layer "F.Cu")
		(net "+3.3V")
	)
	(segment
		(start 147.488595 85.4786)
		(end 147.588595 85.5786)
		(width 0.2032)
		(layer "F.Cu")
		(net "+3.3V")
	)
	(segment
		(start 86.246595 115.5866)
		(end 92.738595 122.0786)
		(width 0.2032)
		(layer "F.Cu")
		(net "+3.3V")
	)
	(segment
		(start 108.238595 68.4286)
		(end 108.299715 68.36748)
		(width 0.2032)
		(layer "F.Cu")
		(net "+3.3V")
	)
	(segment
		(start 120.238595 89.8286)
		(end 120.238595 88.85118)
		(width 0.508)
		(layer "F.Cu")
		(net "+3.3V")
	)
	(segment
		(start 151.488595 86.9786)
		(end 151.526095 87.0161)
		(width 0.2032)
		(layer "F.Cu")
		(net "+3.3V")
	)
	(segment
		(start 69.988595 129.8286)
		(end 71.438595 129.8286)
		(width 0.2032)
		(layer "F.Cu")
		(net "+3.3V")
	)
	(segment
		(start 131.213595 74.6036)
		(end 131.238595 74.5786)
		(width 0.508)
		(layer "F.Cu")
		(net "+3.3V")
	)
	(segment
		(start 132.238595 92.0786)
		(end 133.163595 92.0786)
		(width 0.2032)
		(layer "F.Cu")
		(net "+3.3V")
	)
	(segment
		(start 118.738595 89.8286)
		(end 120.238595 89.8286)
		(width 0.508)
		(layer "F.Cu")
		(net "+3.3V")
	)
	(segment
		(start 113.699715 68.36748)
		(end 113.738595 68.3286)
		(width 0.2032)
		(layer "F.Cu")
		(net "+3.3V")
	)
	(segment
		(start 137.963595 91.0536)
		(end 137.988595 91.0786)
		(width 0.2032)
		(layer "F.Cu")
		(net "+3.3V")
	)
	(segment
		(start 121.972805 88.56281)
		(end 123.188595 89.7786)
		(width 0.2032)
		(layer "F.Cu")
		(net "+3.3V")
	)
	(segment
		(start 215.705115 97.3776)
		(end 215.806115 97.4786)
		(width 0.508)
		(layer "F.Cu")
		(net "+3.3V")
	)
	(segment
		(start 218.617595 91.1076)
		(end 218.617595 90.2076)
		(width 0.508)
		(layer "F.Cu")
		(net "+3.3V")
	)
	(segment
		(start 141.988595 86.3036)
		(end 142.287755 86.3036)
		(width 0.2032)
		(layer "F.Cu")
		(net "+3.3V")
	)
	(segment
		(start 137.988595 91.3286)
		(end 138.738595 92.0786)
		(width 0.2032)
		(layer "F.Cu")
		(net "+3.3V")
	)
	(segment
		(start 138.238595 74.3286)
		(end 147.488595 83.5786)
		(width 0.2032)
		(layer "F.Cu")
		(net "+3.3V")
	)
	(segment
		(start 125.488595 74.5786)
		(end 125.513595 74.6036)
		(width 0.508)
		(layer "F.Cu")
		(net "+3.3V")
	)
	(segment
		(start 85.738595 100.3786)
		(end 85.788595 100.3286)
		(width 0.2032)
		(layer "F.Cu")
		(net "+3.3V")
	)
	(segment
		(start 79.988595 52.51027)
		(end 79.989925 52.5116)
		(width 0.2032)
		(layer "F.Cu")
		(net "+3.3V")
	)
	(segment
		(start 108.299715 68.36748)
		(end 109.199715 68.36748)
		(width 0.2032)
		(layer "F.Cu")
		(net "+3.3V")
	)
	(segment
		(start 147.488595 83.5866)
		(end 147.488595 83.5786)
		(width 0.2032)
		(layer "F.Cu")
		(net "+3.3V")
	)
	(segment
		(start 70.238595 102.8286)
		(end 71.588595 102.8286)
		(width 0.2032)
		(layer "F.Cu")
		(net "+3.3V")
	)
	(segment
		(start 84.988595 52.38794)
		(end 84.988595 51.3286)
		(width 0.2032)
		(layer "F.Cu")
		(net "+3.3V")
	)
	(segment
		(start 121.972805 88.56281)
		(end 121.972805 88.56281)
		(width 0.2032)
		(layer "F.Cu")
		(net "+3.3V")
	)
	(segment
		(start 152.843615 87.0161)
		(end 152.843615 83.43362)
		(width 0.2032)
		(layer "F.Cu")
		(net "+3.3V")
	)
	(segment
		(start 193.663705 86.8086)
		(end 194.488595 86.8086)
		(width 0.508)
		(layer "F.Cu")
		(net "+3.3V")
	)
	(segment
		(start 139.588595 92.0786)
		(end 139.588595 91.1786)
		(width 0.2032)
		(layer "F.Cu")
		(net "+3.3V")
	)
	(segment
		(start 87.388605 135.0786)
		(end 87.388605 134.0036)
		(width 0.2032)
		(layer "F.Cu")
		(net "+3.3V")
	)
	(segment
		(start 85.788595 113.8286)
		(end 85.788595 113.0036)
		(width 0.2032)
		(layer "F.Cu")
		(net "+3.3V")
	)
	(segment
		(start 99.117595 68.4246)
		(end 100.142595 68.4246)
		(width 0.2032)
		(layer "F.Cu")
		(net "+3.3V")
	)
	(segment
		(start 147.213595 87.8536)
		(end 147.238595 87.8286)
		(width 0.2032)
		(layer "F.Cu")
		(net "+3.3V")
	)
	(segment
		(start 215.801095 88.8911)
		(end 217.876095 88.8911)
		(width 0.508)
		(layer "F.Cu")
		(net "+3.3V")
	)
	(segment
		(start 217.876095 88.8911)
		(end 217.888595 88.8786)
		(width 0.508)
		(layer "F.Cu")
		(net "+3.3V")
	)
	(segment
		(start 79.988595 52.51027)
		(end 79.988595 51.3286)
		(width 0.2032)
		(layer "F.Cu")
		(net "+3.3V")
	)
	(segment
		(start 104.488595 56.5786)
		(end 104.488595 56.52361)
		(width 0.2032)
		(layer "F.Cu")
		(net "+3.3V")
	)
	(segment
		(start 147.813595 89.1536)
		(end 148.463595 88.5036)
		(width 0.2032)
		(layer "F.Cu")
		(net "+3.3V")
	)
	(segment
		(start 218.617595 91.1076)
		(end 218.888595 91.3786)
		(width 0.508)
		(layer "F.Cu")
		(net "+3.3V")
	)
	(segment
		(start 143.463595 90.6786)
		(end 144.238595 90.6786)
		(width 0.2032)
		(layer "F.Cu")
		(net "+3.3V")
	)
	(segment
		(start 85.263595 112.4786)
		(end 85.788595 113.0036)
		(width 0.2032)
		(layer "F.Cu")
		(net "+3.3V")
	)
	(segment
		(start 120.238595 88.85118)
		(end 120.536175 88.5536)
		(width 0.508)
		(layer "F.Cu")
		(net "+3.3V")
	)
	(segment
		(start 147.588595 87.0036)
		(end 147.588595 85.5786)
		(width 0.2032)
		(layer "F.Cu")
		(net "+3.3V")
	)
	(segment
		(start 183.988595 87.0786)
		(end 185.438595 87.0786)
		(width 0.508)
		(layer "F.Cu")
		(net "+3.3V")
	)
	(segment
		(start 137.988595 91.3286)
		(end 137.988595 91.0786)
		(width 0.2032)
		(layer "F.Cu")
		(net "+3.3V")
	)
	(segment
		(start 133.188595 74.5786)
		(end 133.488595 74.2786)
		(width 0.508)
		(layer "F.Cu")
		(net "+3.3V")
	)
	(segment
		(start 183.833595 86.9236)
		(end 183.988595 87.0786)
		(width 0.508)
		(layer "F.Cu")
		(net "+3.3V")
	)
	(segment
		(start 191.938595 86.3286)
		(end 191.980485 86.37049)
		(width 0.508)
		(layer "F.Cu")
		(net "+3.3V")
	)
	(segment
		(start 227.885595 89.6786)
		(end 228.156595 89.4076)
		(width 0.508)
		(layer "F.Cu")
		(net "+3.3V")
	)
	(segment
		(start 90.234595 52.5116)
		(end 90.238595 52.50759)
		(width 0.2032)
		(layer "F.Cu")
		(net "+3.3V")
	)
	(segment
		(start 131.238595 74.5786)
		(end 133.188595 74.5786)
		(width 0.508)
		(layer "F.Cu")
		(net "+3.3V")
	)
	(segment
		(start 125.513595 74.6036)
		(end 131.213595 74.6036)
		(width 0.508)
		(layer "F.Cu")
		(net "+3.3V")
	)
	(segment
		(start 217.988595 89.5786)
		(end 218.617595 90.2076)
		(width 0.508)
		(layer "F.Cu")
		(net "+3.3V")
	)
	(segment
		(start 74.867595 52.5116)
		(end 74.867595 51.50459)
		(width 0.2032)
		(layer "F.Cu")
		(net "+3.3V")
	)
	(segment
		(start 218.838595 96.2286)
		(end 218.888595 96.1786)
		(width 0.508)
		(layer "F.Cu")
		(net "+3.3V")
	)
	(segment
		(start 218.888595 92.6786)
		(end 218.888595 91.3786)
		(width 0.508)
		(layer "F.Cu")
		(net "+3.3V")
	)
	(segment
		(start 191.980485 86.37049)
		(end 193.225595 86.37049)
		(width 0.508)
		(layer "F.Cu")
		(net "+3.3V")
	)
	(segment
		(start 217.888595 88.8786)
		(end 220.088595 88.8786)
		(width 0.508)
		(layer "F.Cu")
		(net "+3.3V")
	)
	(segment
		(start 138.238595 74.3286)
		(end 143.738595 74.3286)
		(width 0.2032)
		(layer "F.Cu")
		(net "+3.3V")
	)
	(segment
		(start 85.288595 98.8286)
		(end 85.788595 99.3286)
		(width 0.2032)
		(layer "F.Cu")
		(net "+3.3V")
	)
	(segment
		(start 142.988595 90.2036)
		(end 143.463595 90.6786)
		(width 0.2032)
		(layer "F.Cu")
		(net "+3.3V")
	)
	(segment
		(start 103.613595 68.4286)
		(end 103.626485 68.41571)
		(width 0.2032)
		(layer "F.Cu")
		(net "+3.3V")
	)
	(segment
		(start 130.988595 90.8286)
		(end 130.988595 89.7786)
		(width 0.2032)
		(layer "F.Cu")
		(net "+3.3V")
	)
	(segment
		(start 217.888595 88.8786)
		(end 217.988595 88.9786)
		(width 0.508)
		(layer "F.Cu")
		(net "+3.3V")
	)
	(via
		(at 226.934095 80.3191)
		(size 0.4064)
		(drill 0.2032)
		(layers "F.Cu" "B.Cu")
		(tenting
			(front yes)
			(back yes)
		)
		(net "+3.3V")
	)
	(via
		(at 113.738595 68.3286)
		(size 0.4064)
		(drill 0.2032)
		(layers "F.Cu" "B.Cu")
		(tenting
			(front yes)
			(back yes)
		)
		(net "+3.3V")
	)
	(via
		(at 226.934095 80.8191)
		(size 0.4064)
		(drill 0.2032)
		(layers "F.Cu" "B.Cu")
		(tenting
			(front yes)
			(back yes)
		)
		(net "+3.3V")
	)
	(via
		(at 227.434095 80.8191)
		(size 0.4064)
		(drill 0.2032)
		(layers "F.Cu" "B.Cu")
		(tenting
			(front yes)
			(back yes)
		)
		(net "+3.3V")
	)
	(via
		(at 215.888595 97.4786)
		(size 0.8128)
		(drill 0.4064)
		(layers "F.Cu" "B.Cu")
		(tenting
			(front yes)
			(back yes)
		)
		(net "+3.3V")
	)
	(via
		(at 74.988595 51.3286)
		(size 0.4064)
		(drill 0.2032)
		(layers "F.Cu" "B.Cu")
		(tenting
			(front yes)
			(back yes)
		)
		(net "+3.3V")
	)
	(via
		(at 85.738595 117.5786)
		(size 0.4064)
		(drill 0.2032)
		(layers "F.Cu" "B.Cu")
		(tenting
			(front yes)
			(back yes)
		)
		(net "+3.3V")
	)
	(via
		(at 227.434095 80.3191)
		(size 0.4064)
		(drill 0.2032)
		(layers "F.Cu" "B.Cu")
		(tenting
			(front yes)
			(back yes)
		)
		(net "+3.3V")
	)
	(via
		(at 69.988595 129.8286)
		(size 0.4064)
		(drill 0.2032)
		(layers "F.Cu" "B.Cu")
		(tenting
			(front yes)
			(back yes)
		)
		(net "+3.3V")
	)
	(via
		(at 100.142595 68.4246)
		(size 0.4064)
		(drill 0.2032)
		(layers "F.Cu" "B.Cu")
		(tenting
			(front yes)
			(back yes)
		)
		(net "+3.3V")
	)
	(via
		(at 135.738595 74.3286)
		(size 0.4064)
		(drill 0.2032)
		(layers "F.Cu" "B.Cu")
		(tenting
			(front yes)
			(back yes)
		)
		(net "+3.3V")
	)
	(via
		(at 191.988595 84.8286)
		(size 0.4064)
		(drill 0.2032)
		(layers "F.Cu" "B.Cu")
		(tenting
			(front yes)
			(back yes)
		)
		(net "+3.3V")
	)
	(via
		(at 142.287755 86.3186)
		(size 0.4064)
		(drill 0.2032)
		(layers "F.Cu" "B.Cu")
		(tenting
			(front yes)
			(back yes)
		)
		(net "+3.3V")
	)
	(via
		(at 121.972805 88.56281)
		(size 0.4064)
		(drill 0.2032)
		(layers "F.Cu" "B.Cu")
		(tenting
			(front yes)
			(back yes)
		)
		(net "+3.3V")
	)
	(via
		(at 185.488595 85.5786)
		(size 0.4064)
		(drill 0.2032)
		(layers "F.Cu" "B.Cu")
		(tenting
			(front yes)
			(back yes)
		)
		(net "+3.3V")
	)
	(via
		(at 145.738595 90.5786)
		(size 0.4064)
		(drill 0.2032)
		(layers "F.Cu" "B.Cu")
		(tenting
			(front yes)
			(back yes)
		)
		(net "+3.3V")
	)
	(via
		(at 227.934095 80.3191)
		(size 0.4064)
		(drill 0.2032)
		(layers "F.Cu" "B.Cu")
		(tenting
			(front yes)
			(back yes)
		)
		(net "+3.3V")
	)
	(via
		(at 102.488595 56.5786)
		(size 0.4064)
		(drill 0.2032)
		(layers "F.Cu" "B.Cu")
		(tenting
			(front yes)
			(back yes)
		)
		(net "+3.3V")
	)
	(via
		(at 84.988595 51.3286)
		(size 0.4064)
		(drill 0.2032)
		(layers "F.Cu" "B.Cu")
		(tenting
			(front yes)
			(back yes)
		)
		(net "+3.3V")
	)
	(via
		(at 104.664375 68.40282)
		(size 0.4064)
		(drill 0.2032)
		(layers "F.Cu" "B.Cu")
		(tenting
			(front yes)
			(back yes)
		)
		(net "+3.3V")
	)
	(via
		(at 104.488595 56.5786)
		(size 0.4064)
		(drill 0.2032)
		(layers "F.Cu" "B.Cu")
		(tenting
			(front yes)
			(back yes)
		)
		(net "+3.3V")
	)
	(via
		(at 90.238595 51.3286)
		(size 0.4064)
		(drill 0.2032)
		(layers "F.Cu" "B.Cu")
		(tenting
			(front yes)
			(back yes)
		)
		(net "+3.3V")
	)
	(via
		(at 85.738595 101.8286)
		(size 0.4064)
		(drill 0.2032)
		(layers "F.Cu" "B.Cu")
		(tenting
			(front yes)
			(back yes)
		)
		(net "+3.3V")
	)
	(via
		(at 79.988595 51.3286)
		(size 0.4064)
		(drill 0.2032)
		(layers "F.Cu" "B.Cu")
		(tenting
			(front yes)
			(back yes)
		)
		(net "+3.3V")
	)
	(via
		(at 109.238595 68.3286)
		(size 0.4064)
		(drill 0.2032)
		(layers "F.Cu" "B.Cu")
		(tenting
			(front yes)
			(back yes)
		)
		(net "+3.3V")
	)
	(via
		(at 147.488595 83.5866)
		(size 0.4064)
		(drill 0.2032)
		(layers "F.Cu" "B.Cu")
		(tenting
			(front yes)
			(back yes)
		)
		(net "+3.3V")
	)
	(via
		(at 86.988595 130.8286)
		(size 0.4064)
		(drill 0.2032)
		(layers "F.Cu" "B.Cu")
		(tenting
			(front yes)
			(back yes)
		)
		(net "+3.3V")
	)
	(via
		(at 227.934095 80.8191)
		(size 0.4064)
		(drill 0.2032)
		(layers "F.Cu" "B.Cu")
		(tenting
			(front yes)
			(back yes)
		)
		(net "+3.3V")
	)
	(via
		(at 92.738595 122.0786)
		(size 0.4064)
		(drill 0.2032)
		(layers "F.Cu" "B.Cu")
		(tenting
			(front yes)
			(back yes)
		)
		(net "+3.3V")
	)
	(via
		(at 152.843615 87.0161)
		(size 0.4064)
		(drill 0.2032)
		(layers "F.Cu" "B.Cu")
		(tenting
			(front yes)
			(back yes)
		)
		(net "+3.3V")
	)
	(via
		(at 137.963595 91.0536)
		(size 0.4064)
		(drill 0.2032)
		(layers "F.Cu" "B.Cu")
		(tenting
			(front yes)
			(back yes)
		)
		(net "+3.3V")
	)
	(via
		(at 70.238595 102.8286)
		(size 0.4064)
		(drill 0.2032)
		(layers "F.Cu" "B.Cu")
		(tenting
			(front yes)
			(back yes)
		)
		(net "+3.3V")
	)
	(via
		(at 85.738595 115.5786)
		(size 0.4064)
		(drill 0.2032)
		(layers "F.Cu" "B.Cu")
		(tenting
			(front yes)
			(back yes)
		)
		(net "+3.3V")
	)
	(segment
		(start 191.488595 84.3286)
		(end 191.988595 84.8286)
		(width 0.508)
		(layer "In2.Cu")
		(net "+3.3V")
	)
	(segment
		(start 191.488595 84.3286)
		(end 191.488595 52.3286)
		(width 0.508)
		(layer "In2.Cu")
		(net "+3.3V")
	)
	(segment
		(start 76.988595 130.8286)
		(end 86.988595 130.8286)
		(width 0.2032)
		(layer "In3.Cu")
		(net "+3.3V")
	)
	(segment
		(start 121.972805 88.56281)
		(end 121.972805 88.56281)
		(width 0.2032)
		(layer "In3.Cu")
		(net "+3.3V")
	)
	(segment
		(start 185.488595 85.5786)
		(end 187.738595 83.3286)
		(width 0.635)
		(layer "In3.Cu")
		(net "+3.3V")
	)
	(segment
		(start 114.238595 80.8286)
		(end 114.238595 68.8286)
		(width 0.2032)
		(layer "In3.Cu")
		(net "+3.3V")
	)
	(segment
		(start 191.988595 84.3286)
		(end 192.988595 83.3286)
		(width 0.508)
		(layer "In3.Cu")
		(net "+3.3V")
	)
	(segment
		(start 85.778175 70.78902)
		(end 85.778175 70.36818)
		(width 0.508)
		(layer "In3.Cu")
		(net "+3.3V")
	)
	(segment
		(start 224.424595 83.3286)
		(end 226.934095 80.8191)
		(width 0.635)
		(layer "In3.Cu")
		(net "+3.3V")
	)
	(segment
		(start 70.238595 102.8286)
		(end 84.738595 102.8286)
		(width 0.2032)
		(layer "In3.Cu")
		(net "+3.3V")
	)
	(segment
		(start 85.738595 129.5786)
		(end 85.738595 115.5786)
		(width 0.508)
		(layer "In3.Cu")
		(net "+3.3V")
	)
	(segment
		(start 114.238595 80.8286)
		(end 121.972805 88.56281)
		(width 0.2032)
		(layer "In3.Cu")
		(net "+3.3V")
	)
	(segment
		(start 86.313425 68.4246)
		(end 100.142595 68.4246)
		(width 0.508)
		(layer "In3.Cu")
		(net "+3.3V")
	)
	(segment
		(start 145.738595 90.5786)
		(end 145.738595 85.3286)
		(width 0.2032)
		(layer "In3.Cu")
		(net "+3.3V")
	)
	(segment
		(start 191.988595 84.8286)
		(end 191.988595 84.3286)
		(width 0.508)
		(layer "In3.Cu")
		(net "+3.3V")
	)
	(segment
		(start 138.438595 90.5786)
		(end 145.738595 90.5786)
		(width 0.2032)
		(layer "In3.Cu")
		(net "+3.3V")
	)
	(segment
		(start 113.738595 68.3286)
		(end 114.238595 68.8286)
		(width 0.2032)
		(layer "In3.Cu")
		(net "+3.3V")
	)
	(segment
		(start 85.074015 69.66402)
		(end 86.313425 68.4246)
		(width 0.508)
		(layer "In3.Cu")
		(net "+3.3V")
	)
	(segment
		(start 104.642595 68.4246)
		(end 104.664375 68.40282)
		(width 0.508)
		(layer "In3.Cu")
		(net "+3.3V")
	)
	(segment
		(start 135.738595 74.3286)
		(end 135.738595 65.3286)
		(width 0.508)
		(layer "In3.Cu")
		(net "+3.3V")
	)
	(segment
		(start 85.738595 70.8286)
		(end 85.778175 70.78902)
		(width 0.508)
		(layer "In3.Cu")
		(net "+3.3V")
	)
	(segment
		(start 69.988595 129.8286)
		(end 75.988595 129.8286)
		(width 0.2032)
		(layer "In3.Cu")
		(net "+3.3V")
	)
	(segment
		(start 75.988595 129.8286)
		(end 76.988595 130.8286)
		(width 0.2032)
		(layer "In3.Cu")
		(net "+3.3V")
	)
	(segment
		(start 109.238595 68.3286)
		(end 113.738595 68.3286)
		(width 0.508)
		(layer "In3.Cu")
		(net "+3.3V")
	)
	(segment
		(start 192.988595 83.3286)
		(end 224.424595 83.3286)
		(width 0.635)
		(layer "In3.Cu")
		(net "+3.3V")
	)
	(segment
		(start 145.738595 85.3286)
		(end 147.480595 83.5866)
		(width 0.2032)
		(layer "In3.Cu")
		(net "+3.3V")
	)
	(segment
		(start 147.480595 83.5866)
		(end 147.488595 83.5866)
		(width 0.2032)
		(layer "In3.Cu")
		(net "+3.3V")
	)
	(segment
		(start 85.738595 101.8286)
		(end 85.738595 70.8286)
		(width 0.508)
		(layer "In3.Cu")
		(net "+3.3V")
	)
	(segment
		(start 84.738595 102.8286)
		(end 85.738595 101.8286)
		(width 0.2032)
		(layer "In3.Cu")
		(net "+3.3V")
	)
	(segment
		(start 85.074015 69.66402)
		(end 85.778175 70.36818)
		(width 0.508)
		(layer "In3.Cu")
		(net "+3.3V")
	)
	(segment
		(start 104.738595 68.3286)
		(end 109.238595 68.3286)
		(width 0.508)
		(layer "In3.Cu")
		(net "+3.3V")
	)
	(segment
		(start 187.738595 83.3286)
		(end 192.988595 83.3286)
		(width 0.635)
		(layer "In3.Cu")
		(net "+3.3V")
	)
	(segment
		(start 137.963595 91.0536)
		(end 138.438595 90.5786)
		(width 0.2032)
		(layer "In3.Cu")
		(net "+3.3V")
	)
	(segment
		(start 100.142595 68.4246)
		(end 104.642595 68.4246)
		(width 0.508)
		(layer "In3.Cu")
		(net "+3.3V")
	)
	(segment
		(start 85.738595 129.5786)
		(end 86.988595 130.8286)
		(width 0.508)
		(layer "In3.Cu")
		(net "+3.3V")
	)
	(segment
		(start 85.738595 115.5786)
		(end 85.738595 101.8286)
		(width 0.508)
		(layer "In3.Cu")
		(net "+3.3V")
	)
	(segment
		(start 104.664375 68.40282)
		(end 104.738595 68.3286)
		(width 0.508)
		(layer "In3.Cu")
		(net "+3.3V")
	)
	(segment
		(start 101.363595 74.5786)
		(end 105.438595 78.6536)
		(width 0.2032)
		(layer "F.Cu")
		(net "FPGA_TDO")
	)
	(segment
		(start 101.363595 69.0786)
		(end 101.363595 68.1786)
		(width 0.3048)
		(layer "F.Cu")
		(net "FPGA_TDO")
	)
	(segment
		(start 101.738595 66.3286)
		(end 101.988595 66.3286)
		(width 0.2032)
		(layer "F.Cu")
		(net "FPGA_TDO")
	)
	(segment
		(start 100.388595 102.1536)
		(end 101.513595 102.1536)
		(width 0.2032)
		(layer "F.Cu")
		(net "FPGA_TDO")
	)
	(segment
		(start 101.363595 74.5786)
		(end 101.363595 69.0786)
		(width 0.2032)
		(layer "F.Cu")
		(net "FPGA_TDO")
	)
	(segment
		(start 103.000465 107.55882)
		(end 104.903395 107.55882)
		(width 0.2032)
		(layer "F.Cu")
		(net "FPGA_TDO")
	)
	(segment
		(start 104.903395 107.55882)
		(end 105.261105 107.20111)
		(width 0.2032)
		(layer "F.Cu")
		(net "FPGA_TDO")
	)
	(segment
		(start 101.938595 67.6036)
		(end 101.938595 66.3786)
		(width 0.3048)
		(layer "F.Cu")
		(net "FPGA_TDO")
	)
	(segment
		(start 101.938595 66.3786)
		(end 101.988595 66.3286)
		(width 0.3048)
		(layer "F.Cu")
		(net "FPGA_TDO")
	)
	(segment
		(start 105.438595 98.2286)
		(end 105.438595 78.6536)
		(width 0.2032)
		(layer "F.Cu")
		(net "FPGA_TDO")
	)
	(segment
		(start 101.513595 102.1536)
		(end 105.438595 98.2286)
		(width 0.2032)
		(layer "F.Cu")
		(net "FPGA_TDO")
	)
	(segment
		(start 101.363595 68.1786)
		(end 101.938595 67.6036)
		(width 0.3048)
		(layer "F.Cu")
		(net "FPGA_TDO")
	)
	(via
		(at 100.388595 102.1536)
		(size 0.4064)
		(drill 0.2032)
		(layers "F.Cu" "B.Cu")
		(tenting
			(front yes)
			(back yes)
		)
		(net "FPGA_TDO")
	)
	(via
		(at 105.261105 107.20111)
		(size 0.4064)
		(drill 0.2032)
		(layers "F.Cu" "B.Cu")
		(tenting
			(front yes)
			(back yes)
		)
		(net "FPGA_TDO")
	)
	(segment
		(start 105.261105 107.20111)
		(end 105.261105 104.57611)
		(width 0.2032)
		(layer "B.Cu")
		(net "FPGA_TDO")
	)
	(segment
		(start 100.388595 102.1536)
		(end 102.838595 102.1536)
		(width 0.2032)
		(layer "B.Cu")
		(net "FPGA_TDO")
	)
	(segment
		(start 102.838595 102.1536)
		(end 105.261105 104.57611)
		(width 0.2032)
		(layer "B.Cu")
		(net "FPGA_TDO")
	)
	(segment
		(start 96.863595 69.0786)
		(end 96.938595 69.0036)
		(width 0.3048)
		(layer "F.Cu")
		(net "FPGA_TCK")
	)
	(segment
		(start 105.066695 108.05894)
		(end 105.278515 107.84713)
		(width 0.2032)
		(layer "F.Cu")
		(net "FPGA_TCK")
	)
	(segment
		(start 97.763595 66.3286)
		(end 99.488595 66.3286)
		(width 0.3048)
		(layer "F.Cu")
		(net "FPGA_TCK")
	)
	(segment
		(start 96.863595 70.8286)
		(end 105.088595 79.0536)
		(width 0.2032)
		(layer "F.Cu")
		(net "FPGA_TCK")
	)
	(segment
		(start 100.763595 101.2286)
		(end 101.713595 101.2286)
		(width 0.2032)
		(layer "F.Cu")
		(net "FPGA_TCK")
	)
	(segment
		(start 105.278515 107.84713)
		(end 105.333495 107.84713)
		(width 0.2032)
		(layer "F.Cu")
		(net "FPGA_TCK")
	)
	(segment
		(start 105.088595 97.8536)
		(end 105.088595 79.0536)
		(width 0.2032)
		(layer "F.Cu")
		(net "FPGA_TCK")
	)
	(segment
		(start 96.938595 69.0036)
		(end 96.938595 67.1536)
		(width 0.3048)
		(layer "F.Cu")
		(net "FPGA_TCK")
	)
	(segment
		(start 101.713595 101.2286)
		(end 105.088595 97.8536)
		(width 0.2032)
		(layer "F.Cu")
		(net "FPGA_TCK")
	)
	(segment
		(start 103.613025 108.05894)
		(end 105.066695 108.05894)
		(width 0.2032)
		(layer "F.Cu")
		(net "FPGA_TCK")
	)
	(segment
		(start 96.938595 67.1536)
		(end 97.763595 66.3286)
		(width 0.3048)
		(layer "F.Cu")
		(net "FPGA_TCK")
	)
	(segment
		(start 96.863595 70.8286)
		(end 96.863595 69.0786)
		(width 0.2032)
		(layer "F.Cu")
		(net "FPGA_TCK")
	)
	(via
		(at 105.333495 107.84713)
		(size 0.4064)
		(drill 0.2032)
		(layers "F.Cu" "B.Cu")
		(tenting
			(front yes)
			(back yes)
		)
		(net "FPGA_TCK")
	)
	(via
		(at 100.763595 101.2286)
		(size 0.4064)
		(drill 0.2032)
		(layers "F.Cu" "B.Cu")
		(tenting
			(front yes)
			(back yes)
		)
		(net "FPGA_TCK")
	)
	(segment
		(start 100.763595 101.2286)
		(end 102.763595 101.2286)
		(width 0.2032)
		(layer "B.Cu")
		(net "FPGA_TCK")
	)
	(segment
		(start 102.763595 101.2286)
		(end 106.088595 104.5536)
		(width 0.2032)
		(layer "B.Cu")
		(net "FPGA_TCK")
	)
	(segment
		(start 106.088595 107.09203)
		(end 106.088595 104.5536)
		(width 0.2032)
		(layer "B.Cu")
		(net "FPGA_TCK")
	)
	(segment
		(start 105.333495 107.84713)
		(end 106.088595 107.09203)
		(width 0.2032)
		(layer "B.Cu")
		(net "FPGA_TCK")
	)
	(segment
		(start 228.977395 109.7398)
		(end 228.977395 106.8816)
		(width 0.508)
		(layer "F.Cu")
		(net "+12V")
	)
	(segment
		(start 216.853595 106.5046)
		(end 216.959595 106.3986)
		(width 0.508)
		(layer "F.Cu")
		(net "+12V")
	)
	(segment
		(start 227.419595 107.5786)
		(end 227.819015 107.17918)
		(width 0.508)
		(layer "F.Cu")
		(net "+12V")
	)
	(segment
		(start 107.888595 144.8786)
		(end 107.994595 144.7726)
		(width 0.508)
		(layer "F.Cu")
		(net "+12V")
	)
	(segment
		(start 216.488595 108.0786)
		(end 216.853595 107.7136)
		(width 0.508)
		(layer "F.Cu")
		(net "+12V")
	)
	(segment
		(start 228.977395 106.3398)
		(end 229.176595 106.1406)
		(width 0.508)
		(layer "F.Cu")
		(net "+12V")
	)
	(segment
		(start 109.788595 144.5786)
		(end 109.788595 144.5786)
		(width 0.508)
		(layer "F.Cu")
		(net "+12V")
	)
	(segment
		(start 218.334095 105.1741)
		(end 219.393595 105.1741)
		(width 0.508)
		(layer "F.Cu")
		(net "+12V")
	)
	(segment
		(start 111.988595 144.5786)
		(end 111.988595 144.5786)
		(width 0.508)
		(layer "F.Cu")
		(net "+12V")
	)
	(segment
		(start 218.038595 104.8786)
		(end 218.334095 105.1741)
		(width 0.508)
		(layer "F.Cu")
		(net "+12V")
	)
	(segment
		(start 216.853595 107.7136)
		(end 216.853595 106.5046)
		(width 0.508)
		(layer "F.Cu")
		(net "+12V")
	)
	(segment
		(start 217.618595 106.3986)
		(end 218.038595 105.9786)
		(width 0.508)
		(layer "F.Cu")
		(net "+12V")
	)
	(segment
		(start 228.457595 110.2596)
		(end 228.977395 109.7398)
		(width 0.508)
		(layer "F.Cu")
		(net "+12V")
	)
	(segment
		(start 218.038595 102.8786)
		(end 218.531595 102.3856)
		(width 0.508)
		(layer "F.Cu")
		(net "+12V")
	)
	(segment
		(start 109.788595 144.5786)
		(end 111.988595 144.5786)
		(width 0.508)
		(layer "F.Cu")
		(net "+12V")
	)
	(segment
		(start 109.594595 144.7726)
		(end 109.788595 144.5786)
		(width 0.508)
		(layer "F.Cu")
		(net "+12V")
	)
	(segment
		(start 216.959595 106.3986)
		(end 217.618595 106.3986)
		(width 0.508)
		(layer "F.Cu")
		(net "+12V")
	)
	(segment
		(start 228.977395 106.8816)
		(end 228.977395 106.3398)
		(width 0.508)
		(layer "F.Cu")
		(net "+12V")
	)
	(segment
		(start 218.038595 105.9786)
		(end 218.038595 104.8786)
		(width 0.508)
		(layer "F.Cu")
		(net "+12V")
	)
	(segment
		(start 225.488595 107.5786)
		(end 227.419595 107.5786)
		(width 0.508)
		(layer "F.Cu")
		(net "+12V")
	)
	(segment
		(start 227.078595 110.2596)
		(end 228.457595 110.2596)
		(width 0.508)
		(layer "F.Cu")
		(net "+12V")
	)
	(segment
		(start 227.819015 107.17918)
		(end 228.679815 107.17918)
		(width 0.508)
		(layer "F.Cu")
		(net "+12V")
	)
	(segment
		(start 218.531595 102.3856)
		(end 219.836595 102.3856)
		(width 0.508)
		(layer "F.Cu")
		(net "+12V")
	)
	(segment
		(start 218.038595 104.8786)
		(end 218.038595 102.8786)
		(width 0.508)
		(layer "F.Cu")
		(net "+12V")
	)
	(segment
		(start 107.994595 144.7726)
		(end 109.594595 144.7726)
		(width 0.508)
		(layer "F.Cu")
		(net "+12V")
	)
	(segment
		(start 229.176595 106.1406)
		(end 229.934595 106.1406)
		(width 0.508)
		(layer "F.Cu")
		(net "+12V")
	)
	(segment
		(start 228.679815 107.17918)
		(end 228.977395 106.8816)
		(width 0.508)
		(layer "F.Cu")
		(net "+12V")
	)
	(via
		(at 111.738595 146.8286)
		(size 0.4064)
		(drill 0.2032)
		(layers "F.Cu" "B.Cu")
		(tenting
			(front yes)
			(back yes)
		)
		(net "+12V")
	)
	(via
		(at 215.988595 110.0786)
		(size 0.4064)
		(drill 0.2032)
		(layers "F.Cu" "B.Cu")
		(tenting
			(front yes)
			(back yes)
		)
		(net "+12V")
	)
	(via
		(at 216.488595 110.5786)
		(size 0.4064)
		(drill 0.2032)
		(layers "F.Cu" "B.Cu")
		(tenting
			(front yes)
			(back yes)
		)
		(net "+12V")
	)
	(via
		(at 112.238595 146.8286)
		(size 0.4064)
		(drill 0.2032)
		(layers "F.Cu" "B.Cu")
		(tenting
			(front yes)
			(back yes)
		)
		(net "+12V")
	)
	(via
		(at 112.738595 146.3286)
		(size 0.4064)
		(drill 0.2032)
		(layers "F.Cu" "B.Cu")
		(tenting
			(front yes)
			(back yes)
		)
		(net "+12V")
	)
	(via
		(at 112.738595 146.8286)
		(size 0.4064)
		(drill 0.2032)
		(layers "F.Cu" "B.Cu")
		(tenting
			(front yes)
			(back yes)
		)
		(net "+12V")
	)
	(via
		(at 112.238595 146.3286)
		(size 0.4064)
		(drill 0.2032)
		(layers "F.Cu" "B.Cu")
		(tenting
			(front yes)
			(back yes)
		)
		(net "+12V")
	)
	(via
		(at 111.738595 146.3286)
		(size 0.4064)
		(drill 0.2032)
		(layers "F.Cu" "B.Cu")
		(tenting
			(front yes)
			(back yes)
		)
		(net "+12V")
	)
	(via
		(at 225.488595 107.5786)
		(size 0.4064)
		(drill 0.2032)
		(layers "F.Cu" "B.Cu")
		(tenting
			(front yes)
			(back yes)
		)
		(net "+12V")
	)
	(via
		(at 216.488595 109.5786)
		(size 0.4064)
		(drill 0.2032)
		(layers "F.Cu" "B.Cu")
		(tenting
			(front yes)
			(back yes)
		)
		(net "+12V")
	)
	(via
		(at 215.988595 110.5786)
		(size 0.4064)
		(drill 0.2032)
		(layers "F.Cu" "B.Cu")
		(tenting
			(front yes)
			(back yes)
		)
		(net "+12V")
	)
	(via
		(at 216.488595 108.0786)
		(size 0.4064)
		(drill 0.2032)
		(layers "F.Cu" "B.Cu")
		(tenting
			(front yes)
			(back yes)
		)
		(net "+12V")
	)
	(via
		(at 215.988595 109.5786)
		(size 0.4064)
		(drill 0.2032)
		(layers "F.Cu" "B.Cu")
		(tenting
			(front yes)
			(back yes)
		)
		(net "+12V")
	)
	(via
		(at 216.488595 110.0786)
		(size 0.4064)
		(drill 0.2032)
		(layers "F.Cu" "B.Cu")
		(tenting
			(front yes)
			(back yes)
		)
		(net "+12V")
	)
	(segment
		(start 137.488595 132.0786)
		(end 158.988595 132.0786)
		(width 0.762)
		(layer "B.Cu")
		(net "+12V")
	)
	(segment
		(start 135.238595 129.8286)
		(end 137.488595 132.0786)
		(width 0.762)
		(layer "B.Cu")
		(net "+12V")
	)
	(segment
		(start 180.988595 110.0786)
		(end 215.988595 110.0786)
		(width 0.762)
		(layer "B.Cu")
		(net "+12V")
	)
	(segment
		(start 111.738595 146.3286)
		(end 111.738595 131.8286)
		(width 0.762)
		(layer "B.Cu")
		(net "+12V")
	)
	(segment
		(start 113.738595 129.8286)
		(end 135.238595 129.8286)
		(width 0.762)
		(layer "B.Cu")
		(net "+12V")
	)
	(segment
		(start 111.738595 131.8286)
		(end 113.738595 129.8286)
		(width 0.762)
		(layer "B.Cu")
		(net "+12V")
	)
	(segment
		(start 158.988595 132.0786)
		(end 180.988595 110.0786)
		(width 0.762)
		(layer "B.Cu")
		(net "+12V")
	)
	(segment
		(start 103.611125 121.56069)
		(end 103.613025 121.55879)
		(width 0.2032)
		(layer "F.Cu")
		(net "KEY1")
	)
	(segment
		(start 219.012595 125.6526)
		(end 219.012595 123.4916)
		(width 0.508)
		(layer "F.Cu")
		(net "+5.0V")
	)
	(segment
		(start 122.988595 74.5786)
		(end 123.488595 75.0786)
		(width 0.508)
		(layer "F.Cu")
		(net "+5.0V")
	)
	(segment
		(start 151.233465 108.07103)
		(end 153.231025 108.07103)
		(width 0.2032)
		(layer "F.Cu")
		(net "+5.0V")
	)
	(segment
		(start 150.604095 142.0951)
		(end 152.597095 142.0951)
		(width 0.508)
		(layer "F.Cu")
		(net "+5.0V")
	)
	(segment
		(start 144.496165 108.07103)
		(end 147.168555 108.07103)
		(width 0.2032)
		(layer "F.Cu")
		(net "+5.0V")
	)
	(segment
		(start 228.348595 119.6576)
		(end 228.488595 119.7976)
		(width 0.508)
		(layer "F.Cu")
		(net "+5.0V")
	)
	(segment
		(start 232.148585 115.31861)
		(end 232.188595 115.2786)
		(width 0.508)
		(layer "F.Cu")
		(net "+5.0V")
	)
	(segment
		(start 153.230965 108.57096)
		(end 153.238595 108.5786)
		(width 0.2032)
		(layer "F.Cu")
		(net "+5.0V")
	)
	(segment
		(start 126.517595 79.1076)
		(end 126.967595 79.1076)
		(width 0.508)
		(layer "F.Cu")
		(net "+5.0V")
	)
	(segment
		(start 144.496225 107.57097)
		(end 147.168485 107.57097)
		(width 0.2032)
		(layer "F.Cu")
		(net "+5.0V")
	)
	(segment
		(start 123.488595 77.5786)
		(end 123.488595 75.0786)
		(width 0.508)
		(layer "F.Cu")
		(net "+5.0V")
	)
	(segment
		(start 144.488595 108.5786)
		(end 144.496235 108.57096)
		(width 0.2032)
		(layer "F.Cu")
		(net "+5.0V")
	)
	(segment
		(start 121.043595 74.5786)
		(end 122.988595 74.5786)
		(width 0.508)
		(layer "F.Cu")
		(net "+5.0V")
	)
	(segment
		(start 127.338595 79.2786)
		(end 128.788595 79.2786)
		(width 0.508)
		(layer "F.Cu")
		(net "+5.0V")
	)
	(segment
		(start 232.292595 115.1746)
		(end 232.292595 114.4506)
		(width 0.508)
		(layer "F.Cu")
		(net "+5.0V")
	)
	(segment
		(start 126.238595 78.8286)
		(end 126.517595 79.1076)
		(width 0.508)
		(layer "F.Cu")
		(net "+5.0V")
	)
	(segment
		(start 218.925595 123.5786)
		(end 219.012595 123.4916)
		(width 0.2032)
		(layer "F.Cu")
		(net "+5.0V")
	)
	(segment
		(start 151.225895 107.56333)
		(end 151.233535 107.57097)
		(width 0.2032)
		(layer "F.Cu")
		(net "+5.0V")
	)
	(segment
		(start 144.496235 108.57096)
		(end 147.168485 108.57096)
		(width 0.2032)
		(layer "F.Cu")
		(net "+5.0V")
	)
	(segment
		(start 127.238595 79.3786)
		(end 127.338595 79.2786)
		(width 0.508)
		(layer "F.Cu")
		(net "+5.0V")
	)
	(segment
		(start 151.225895 108.56333)
		(end 151.233535 108.57096)
		(width 0.2032)
		(layer "F.Cu")
		(net "+5.0V")
	)
	(segment
		(start 124.988595 78.9286)
		(end 125.088595 78.8286)
		(width 0.508)
		(layer "F.Cu")
		(net "+5.0V")
	)
	(segment
		(start 152.597095 142.0951)
		(end 152.638595 142.0536)
		(width 0.508)
		(layer "F.Cu")
		(net "+5.0V")
	)
	(segment
		(start 228.348595 116.8636)
		(end 228.348595 115.4666)
		(width 0.508)
		(layer "F.Cu")
		(net "+5.0V")
	)
	(segment
		(start 124.838595 78.9286)
		(end 124.988595 78.9286)
		(width 0.508)
		(layer "F.Cu")
		(net "+5.0V")
	)
	(segment
		(start 227.838595 126.7786)
		(end 228.675595 125.9416)
		(width 0.508)
		(layer "F.Cu")
		(net "+5.0V")
	)
	(segment
		(start 144.496165 109.07103)
		(end 147.168555 109.07103)
		(width 0.2032)
		(layer "F.Cu")
		(net "+5.0V")
	)
	(segment
		(start 151.225895 109.06346)
		(end 151.233465 109.07103)
		(width 0.2032)
		(layer "F.Cu")
		(net "+5.0V")
	)
	(segment
		(start 147.168555 108.07103)
		(end 147.176125 108.06346)
		(width 0.2032)
		(layer "F.Cu")
		(net "+5.0V")
	)
	(segment
		(start 232.188595 115.2786)
		(end 232.292595 115.1746)
		(width 0.508)
		(layer "F.Cu")
		(net "+5.0V")
	)
	(segment
		(start 151.233465 109.07103)
		(end 153.231025 109.07103)
		(width 0.2032)
		(layer "F.Cu")
		(net "+5.0V")
	)
	(segment
		(start 150.313595 144.1786)
		(end 150.438095 144.0541)
		(width 0.508)
		(layer "F.Cu")
		(net "+5.0V")
	)
	(segment
		(start 144.488595 107.5786)
		(end 144.496225 107.57097)
		(width 0.2032)
		(layer "F.Cu")
		(net "+5.0V")
	)
	(segment
		(start 219.012595 125.6526)
		(end 220.138595 126.7786)
		(width 0.508)
		(layer "F.Cu")
		(net "+5.0V")
	)
	(segment
		(start 228.488595 121.5026)
		(end 228.488595 119.7976)
		(width 0.508)
		(layer "F.Cu")
		(net "+5.0V")
	)
	(segment
		(start 228.348595 118.1336)
		(end 228.348595 116.8636)
		(width 0.508)
		(layer "F.Cu")
		(net "+5.0V")
	)
	(segment
		(start 228.488595 121.5026)
		(end 228.675595 121.6896)
		(width 0.508)
		(layer "F.Cu")
		(net "+5.0V")
	)
	(segment
		(start 220.138595 126.7786)
		(end 227.838595 126.7786)
		(width 0.508)
		(layer "F.Cu")
		(net "+5.0V")
	)
	(segment
		(start 123.488595 77.5786)
		(end 124.838595 78.9286)
		(width 0.508)
		(layer "F.Cu")
		(net "+5.0V")
	)
	(segment
		(start 151.225895 108.06346)
		(end 151.233465 108.07103)
		(width 0.2032)
		(layer "F.Cu")
		(net "+5.0V")
	)
	(segment
		(start 147.168555 109.07103)
		(end 147.176125 109.06346)
		(width 0.2032)
		(layer "F.Cu")
		(net "+5.0V")
	)
	(segment
		(start 153.230965 107.57097)
		(end 153.238595 107.5786)
		(width 0.2032)
		(layer "F.Cu")
		(net "+5.0V")
	)
	(segment
		(start 228.348595 115.4666)
		(end 231.790175 115.4666)
		(width 0.508)
		(layer "F.Cu")
		(net "+5.0V")
	)
	(segment
		(start 126.967595 79.1076)
		(end 127.238595 79.3786)
		(width 0.508)
		(layer "F.Cu")
		(net "+5.0V")
	)
	(segment
		(start 144.488595 108.0786)
		(end 144.496165 108.07103)
		(width 0.2032)
		(layer "F.Cu")
		(net "+5.0V")
	)
	(segment
		(start 232.148575 115.31862)
		(end 232.148585 115.31861)
		(width 0.508)
		(layer "F.Cu")
		(net "+5.0V")
	)
	(segment
		(start 228.348595 119.6576)
		(end 228.348595 118.1336)
		(width 0.508)
		(layer "F.Cu")
		(net "+5.0V")
	)
	(segment
		(start 228.675595 124.4836)
		(end 228.675595 121.6896)
		(width 0.508)
		(layer "F.Cu")
		(net "+5.0V")
	)
	(segment
		(start 150.438095 142.2611)
		(end 150.604095 142.0951)
		(width 0.508)
		(layer "F.Cu")
		(net "+5.0V")
	)
	(segment
		(start 228.675595 125.9416)
		(end 228.675595 124.4836)
		(width 0.508)
		(layer "F.Cu")
		(net "+5.0V")
	)
	(segment
		(start 232.188595 118.6786)
		(end 232.188595 115.2786)
		(width 0.508)
		(layer "F.Cu")
		(net "+5.0V")
	)
	(segment
		(start 144.488595 109.0786)
		(end 144.496165 109.07103)
		(width 0.2032)
		(layer "F.Cu")
		(net "+5.0V")
	)
	(segment
		(start 125.088595 78.8286)
		(end 126.238595 78.8286)
		(width 0.508)
		(layer "F.Cu")
		(net "+5.0V")
	)
	(segment
		(start 151.233535 107.57097)
		(end 153.230965 107.57097)
		(width 0.2032)
		(layer "F.Cu")
		(net "+5.0V")
	)
	(segment
		(start 147.168485 107.57097)
		(end 147.176125 107.56333)
		(width 0.2032)
		(layer "F.Cu")
		(net "+5.0V")
	)
	(segment
		(start 153.231025 109.07103)
		(end 153.238595 109.0786)
		(width 0.2032)
		(layer "F.Cu")
		(net "+5.0V")
	)
	(segment
		(start 153.231025 108.07103)
		(end 153.238595 108.0786)
		(width 0.2032)
		(layer "F.Cu")
		(net "+5.0V")
	)
	(segment
		(start 147.168485 108.57096)
		(end 147.176125 108.56333)
		(width 0.2032)
		(layer "F.Cu")
		(net "+5.0V")
	)
	(segment
		(start 150.438095 144.0541)
		(end 150.438095 142.2611)
		(width 0.508)
		(layer "F.Cu")
		(net "+5.0V")
	)
	(segment
		(start 151.233535 108.57096)
		(end 153.230965 108.57096)
		(width 0.2032)
		(layer "F.Cu")
		(net "+5.0V")
	)
	(via
		(at 153.238595 108.0786)
		(size 0.4064)
		(drill 0.2032)
		(layers "F.Cu" "B.Cu")
		(tenting
			(front yes)
			(back yes)
		)
		(net "+5.0V")
	)
	(via
		(at 144.488595 109.0786)
		(size 0.4064)
		(drill 0.2032)
		(layers "F.Cu" "B.Cu")
		(tenting
			(front yes)
			(back yes)
		)
		(net "+5.0V")
	)
	(via
		(at 232.188595 118.6786)
		(size 0.8128)
		(drill 0.4064)
		(layers "F.Cu" "B.Cu")
		(tenting
			(front yes)
			(back yes)
		)
		(net "+5.0V")
	)
	(via
		(at 152.638595 142.0536)
		(size 1.27)
		(drill 0.7112)
		(layers "F.Cu" "B.Cu")
		(net "+5.0V")
	)
	(via
		(at 210.238595 123.5786)
		(size 0.4064)
		(drill 0.2032)
		(layers "F.Cu" "B.Cu")
		(tenting
			(front yes)
			(back yes)
		)
		(net "+5.0V")
	)
	(via
		(at 144.488595 107.5786)
		(size 0.4064)
		(drill 0.2032)
		(layers "F.Cu" "B.Cu")
		(tenting
			(front yes)
			(back yes)
		)
		(net "+5.0V")
	)
	(via
		(at 153.238595 109.0786)
		(size 0.4064)
		(drill 0.2032)
		(layers "F.Cu" "B.Cu")
		(tenting
			(front yes)
			(back yes)
		)
		(net "+5.0V")
	)
	(via
		(at 153.238595 108.5786)
		(size 0.4064)
		(drill 0.2032)
		(layers "F.Cu" "B.Cu")
		(tenting
			(front yes)
			(back yes)
		)
		(net "+5.0V")
	)
	(via
		(at 209.738595 123.5786)
		(size 0.4064)
		(drill 0.2032)
		(layers "F.Cu" "B.Cu")
		(tenting
			(front yes)
			(back yes)
		)
		(net "+5.0V")
	)
	(via
		(at 209.738595 124.0786)
		(size 0.4064)
		(drill 0.2032)
		(layers "F.Cu" "B.Cu")
		(tenting
			(front yes)
			(back yes)
		)
		(net "+5.0V")
	)
	(via
		(at 210.238595 124.5786)
		(size 0.4064)
		(drill 0.2032)
		(layers "F.Cu" "B.Cu")
		(tenting
			(front yes)
			(back yes)
		)
		(net "+5.0V")
	)
	(via
		(at 153.238595 107.5786)
		(size 0.4064)
		(drill 0.2032)
		(layers "F.Cu" "B.Cu")
		(tenting
			(front yes)
			(back yes)
		)
		(net "+5.0V")
	)
	(via
		(at 144.488595 108.0786)
		(size 0.4064)
		(drill 0.2032)
		(layers "F.Cu" "B.Cu")
		(tenting
			(front yes)
			(back yes)
		)
		(net "+5.0V")
	)
	(via
		(at 210.238595 124.0786)
		(size 0.4064)
		(drill 0.2032)
		(layers "F.Cu" "B.Cu")
		(tenting
			(front yes)
			(back yes)
		)
		(net "+5.0V")
	)
	(via
		(at 144.488595 108.5786)
		(size 0.4064)
		(drill 0.2032)
		(layers "F.Cu" "B.Cu")
		(tenting
			(front yes)
			(back yes)
		)
		(net "+5.0V")
	)
	(via
		(at 209.738595 124.5786)
		(size 0.4064)
		(drill 0.2032)
		(layers "F.Cu" "B.Cu")
		(tenting
			(front yes)
			(back yes)
		)
		(net "+5.0V")
	)
	(via
		(at 128.788595 79.2786)
		(size 0.4064)
		(drill 0.2032)
		(layers "F.Cu" "B.Cu")
		(tenting
			(front yes)
			(back yes)
		)
		(net "+5.0V")
	)
	(arc
		(start 232.148577 115.318617)
		(mid 231.984051 115.428149)
		(end 231.790175 115.4666)
		(width 0.508)
		(layer "F.Cu")
		(net "+5.0V")
	)
	(segment
		(start 133.188595 107.5786)
		(end 144.488595 107.5786)
		(width 0.3048)
		(layer "B.Cu")
		(net "+5.0V")
	)
	(segment
		(start 128.588595 102.9786)
		(end 133.188595 107.5786)
		(width 0.3048)
		(layer "B.Cu")
		(net "+5.0V")
	)
	(segment
		(start 128.788595 79.30609)
		(end 128.788595 79.2786)
		(width 0.3048)
		(layer "B.Cu")
		(net "+5.0V")
	)
	(segment
		(start 128.588595 102.9786)
		(end 128.588595 79.50609)
		(width 0.3048)
		(layer "B.Cu")
		(net "+5.0V")
	)
	(segment
		(start 128.588595 79.50609)
		(end 128.788595 79.30609)
		(width 0.3048)
		(layer "B.Cu")
		(net "+5.0V")
	)
	(segment
		(start 152.638595 142.0536)
		(end 155.981075 142.0536)
		(width 0.635)
		(layer "B.Cu")
		(net "+5.0V")
	)
	(segment
		(start 155.981075 142.0536)
		(end 159.806075 138.2286)
		(width 0.635)
		(layer "B.Cu")
		(net "+5.0V")
	)
	(segment
		(start 210.263595 124.0536)
		(end 210.263595 123.6036)
		(width 0.635)
		(layer "In2.Cu")
		(net "+5.0V")
	)
	(segment
		(start 210.238595 123.5786)
		(end 210.263595 123.6036)
		(width 0.635)
		(layer "In2.Cu")
		(net "+5.0V")
	)
	(segment
		(start 210.263595 124.0536)
		(end 210.288595 124.0786)
		(width 0.635)
		(layer "In2.Cu")
		(net "+5.0V")
	)
	(segment
		(start 210.288595 137.0286)
		(end 210.288595 124.0786)
		(width 0.635)
		(layer "In2.Cu")
		(net "+5.0V")
	)
	(segment
		(start 205.263595 142.0536)
		(end 210.288595 137.0286)
		(width 0.635)
		(layer "In2.Cu")
		(net "+5.0V")
	)
	(segment
		(start 152.638595 142.0536)
		(end 205.263595 142.0536)
		(width 0.635)
		(layer "In2.Cu")
		(net "+5.0V")
	)
	(segment
		(start 209.988595 123.3286)
		(end 209.988595 118.8286)
		(width 0.635)
		(layer "In3.Cu")
		(net "+5.0V")
	)
	(segment
		(start 209.988595 123.3286)
		(end 210.238595 123.5786)
		(width 0.635)
		(layer "In3.Cu")
		(net "+5.0V")
	)
	(segment
		(start 153.988595 109.0786)
		(end 200.238595 109.0786)
		(width 0.635)
		(layer "In3.Cu")
		(net "+5.0V")
	)
	(segment
		(start 200.238595 109.0786)
		(end 209.988595 118.8286)
		(width 0.635)
		(layer "In3.Cu")
		(net "+5.0V")
	)
	(segment
		(start 99.888595 106.4786)
		(end 100.713595 107.3036)
		(width 0.2032)
		(layer "F.Cu")
		(net "FPGA_TDI")
	)
	(segment
		(start 99.576775 108.03908)
		(end 100.407625 108.03908)
		(width 0.2032)
		(layer "F.Cu")
		(net "FPGA_TDI")
	)
	(segment
		(start 109.738595 67.6536)
		(end 110.488595 68.4036)
		(width 0.3048)
		(layer "F.Cu")
		(net "FPGA_TDI")
	)
	(segment
		(start 99.553405 108.06244)
		(end 99.556905 108.05894)
		(width 0.2032)
		(layer "F.Cu")
		(net "FPGA_TDI")
	)
	(segment
		(start 99.556905 108.05894)
		(end 99.576775 108.03908)
		(width 0.2032)
		(layer "F.Cu")
		(net "FPGA_TDI")
	)
	(segment
		(start 110.488595 94.3536)
		(end 110.488595 69.0786)
		(width 0.2032)
		(layer "F.Cu")
		(net "FPGA_TDI")
	)
	(segment
		(start 109.738595 67.6536)
		(end 109.738595 66.3286)
		(width 0.3048)
		(layer "F.Cu")
		(net "FPGA_TDI")
	)
	(segment
		(start 100.713595 107.7331)
		(end 100.713595 107.3036)
		(width 0.2032)
		(layer "F.Cu")
		(net "FPGA_TDI")
	)
	(segment
		(start 100.407625 108.03908)
		(end 100.713595 107.7331)
		(width 0.2032)
		(layer "F.Cu")
		(net "FPGA_TDI")
	)
	(segment
		(start 110.488595 69.0786)
		(end 110.488595 68.4036)
		(width 0.3048)
		(layer "F.Cu")
		(net "FPGA_TDI")
	)
	(segment
		(start 99.888595 104.9536)
		(end 110.488595 94.3536)
		(width 0.2032)
		(layer "F.Cu")
		(net "FPGA_TDI")
	)
	(segment
		(start 99.888595 106.4786)
		(end 99.888595 104.9536)
		(width 0.2032)
		(layer "F.Cu")
		(net "FPGA_TDI")
	)
	(zone
		(net "GND")
		(layer "F.Cu")
		(hatch edge 0.5)
		(connect_pads yes
			(clearance 0.5)
		)
		(min_thickness 0.25)
		(fill yes
			(thermal_gap 0.2032)
			(thermal_bridge_width 0.254)
			(island_removal_mode 0)
		)
		(polygon
			(pts
				(xy 205.488595 92.5786) (xy 154.738595 92.5786) (xy 154.738595 143.3286) (xy 205.488595 143.3286)
			)
		)
	)
	(zone
		(net "+5.0V")
		(layer "F.Cu")
		(hatch edge 0.5)
		(priority 12)
		(connect_pads yes
			(clearance 0.5)
		)
		(min_thickness 0.25)
		(fill yes
			(thermal_gap 0.2032)
			(thermal_bridge_width 0.254)
			(island_removal_mode 0)
		)
		(polygon
			(pts
				(xy 234.838595 113.6786) (xy 229.238595 113.6786) (xy 227.738595 115.1786) (xy 227.738595 127.6786)
				(xy 229.338595 127.6786) (xy 234.838595 122.1786)
			)
		)
	)
	(zone
		(layer "F.Cu")
		(hatch edge 0.5)
		(connect_pads
			(clearance 0)
		)
		(min_thickness 0.25)
		(keepout
			(tracks not_allowed)
			(vias not_allowed)
			(pads not_allowed)
			(copperpour not_allowed)
			(footprints allowed)
		)
		(placement
			(enabled no)
			(sheetname "")
		)
		(fill
			(thermal_gap 0.5)
			(thermal_bridge_width 0.5)
			(island_removal_mode 0)
		)
		(polygon
			(pts
				(arc
					(start 58.438215 156.0786)
					(mid 58.452971 156.114224)
					(end 58.488595 156.12898)
				)
				(arc
					(start 73.488595 156.12898)
					(mid 73.524219 156.114224)
					(end 73.538975 156.0786)
				)
				(xy 73.538975 147.87898) (xy 91.788215 147.87898)
				(arc
					(start 91.788215 152.6286)
					(mid 91.802971 152.664224)
					(end 91.838595 152.67898)
				)
				(arc
					(start 99.838595 152.67898)
					(mid 99.874219 152.664224)
					(end 99.888975 152.6286)
				)
				(xy 99.888972 152.628094) (xy 99.888975 152.62809)
				(arc
					(start 99.888975 149.6536)
					(mid 101.663595 147.87898)
					(end 103.438215 149.6536)
				)
				(arc
					(start 103.438215 149.6536)
					(mid 103.488595 149.70398)
					(end 103.538975 149.6536)
				)
				(arc
					(start 103.538975 146.8286)
					(mid 103.524219 146.792976)
					(end 103.488595 146.77822)
				)
				(arc
					(start 58.488595 146.77822)
					(mid 58.452971 146.792976)
					(end 58.438215 146.8286)
				)
			)
		)
	)
	(zone
		(net "+3.3V")
		(layer "F.Cu")
		(hatch edge 0.5)
		(priority 14)
		(connect_pads yes
			(clearance 0.5)
		)
		(min_thickness 0.25)
		(fill yes
			(thermal_gap 0.2032)
			(thermal_bridge_width 0.254)
			(island_removal_mode 0)
		)
		(polygon
			(pts
				(xy 231.338595 85.1786) (xy 222.588595 85.1786) (xy 222.588595 89.9286) (xy 222.338595 90.1786)
				(xy 213.588595 90.1786) (xy 213.588595 97.6786) (xy 213.838595 97.4286) (xy 219.338595 97.4286)
				(xy 219.338595 92.4286) (xy 219.838595 91.9286) (xy 231.338595 91.9286)
			)
		)
	)
	(zone
		(layer "F.Cu")
		(hatch edge 0.5)
		(connect_pads
			(clearance 0)
		)
		(min_thickness 0.25)
		(keepout
			(tracks allowed)
			(vias allowed)
			(pads allowed)
			(copperpour not_allowed)
			(footprints allowed)
		)
		(placement
			(enabled no)
			(sheetname "")
		)
		(fill
			(thermal_gap 0.5)
			(thermal_bridge_width 0.5)
			(island_removal_mode 0)
		)
		(polygon
			(pts
				(arc
					(start 198.549165 138.2286)
					(mid 199.093041 139.541634)
					(end 200.406075 140.08551)
				)
				(arc
					(start 200.406075 140.08551)
					(mid 201.719109 139.541634)
					(end 202.262985 138.2286)
				)
				(arc
					(start 202.262985 138.2286)
					(mid 201.719109 136.915566)
					(end 200.406075 136.37169)
				)
				(arc
					(start 200.406075 136.37169)
					(mid 199.093041 136.915566)
					(end 198.549165 138.2286)
				)
			)
		)
	)
	(zone
		(net "+3.3V")
		(layer "F.Cu")
		(hatch edge 0.5)
		(priority 4)
		(connect_pads yes
			(clearance 0.5)
		)
		(min_thickness 0.25)
		(fill yes
			(thermal_gap 0.2032)
			(thermal_bridge_width 0.254)
			(island_removal_mode 0)
		)
		(polygon
			(pts
				(xy 228.284105 88.1441) (xy 228.284105 79.8941) (xy 226.584095 79.8941) (xy 226.584095 88.1441)
			)
		)
	)
	(zone
		(layer "F.Cu")
		(hatch edge 0.5)
		(connect_pads
			(clearance 0)
		)
		(min_thickness 0.25)
		(keepout
			(tracks allowed)
			(vias allowed)
			(pads allowed)
			(copperpour not_allowed)
			(footprints allowed)
		)
		(placement
			(enabled no)
			(sheetname "")
		)
		(fill
			(thermal_gap 0.5)
			(thermal_bridge_width 0.5)
			(island_removal_mode 0)
		)
		(polygon
			(pts
				(arc
					(start 157.949165 138.2286)
					(mid 158.493041 139.541634)
					(end 159.806075 140.08551)
				)
				(arc
					(start 159.806075 140.08551)
					(mid 161.119109 139.541634)
					(end 161.662985 138.2286)
				)
				(arc
					(start 161.662985 138.2286)
					(mid 161.119109 136.915566)
					(end 159.806075 136.37169)
				)
				(arc
					(start 159.806075 136.37169)
					(mid 158.493041 136.915566)
					(end 157.949165 138.2286)
				)
			)
		)
	)
	(zone
		(net "+5.0V")
		(layer "F.Cu")
		(hatch edge 0.5)
		(priority 10)
		(connect_pads yes
			(clearance 0.5)
		)
		(min_thickness 0.25)
		(fill yes
			(thermal_gap 0.2032)
			(thermal_bridge_width 0.254)
			(island_removal_mode 0)
		)
		(polygon
			(pts
				(xy 217.613595 123.2286) (xy 209.363595 123.2286) (xy 209.363595 124.9286) (xy 217.613595 124.9286)
			)
		)
	)
	(zone
		(layer "F.Cu")
		(hatch edge 0.5)
		(connect_pads
			(clearance 0)
		)
		(min_thickness 0.25)
		(keepout
			(tracks allowed)
			(vias allowed)
			(pads allowed)
			(copperpour not_allowed)
			(footprints allowed)
		)
		(placement
			(enabled no)
			(sheetname "")
		)
		(fill
			(thermal_gap 0.5)
			(thermal_bridge_width 0.5)
			(island_removal_mode 0)
		)
		(polygon
			(pts
				(arc
					(start 198.549165 97.6286)
					(mid 199.093041 98.941634)
					(end 200.406075 99.48551)
				)
				(arc
					(start 200.406075 99.48551)
					(mid 201.719109 98.941634)
					(end 202.262985 97.6286)
				)
				(arc
					(start 202.262985 97.6286)
					(mid 201.719109 96.315566)
					(end 200.406075 95.77169)
				)
				(arc
					(start 200.406075 95.77169)
					(mid 199.093041 96.315566)
					(end 198.549165 97.6286)
				)
			)
		)
	)
	(zone
		(layer "F.Cu")
		(hatch edge 0.5)
		(connect_pads
			(clearance 0)
		)
		(min_thickness 0.25)
		(keepout
			(tracks allowed)
			(vias allowed)
			(pads allowed)
			(copperpour not_allowed)
			(footprints allowed)
		)
		(placement
			(enabled no)
			(sheetname "")
		)
		(fill
			(thermal_gap 0.5)
			(thermal_bridge_width 0.5)
			(island_removal_mode 0)
		)
		(polygon
			(pts
				(arc
					(start 198.549165 117.9286)
					(mid 199.093041 119.241634)
					(end 200.406075 119.78551)
				)
				(arc
					(start 200.406075 119.78551)
					(mid 201.719109 119.241634)
					(end 202.262985 117.9286)
				)
				(arc
					(start 202.262985 117.9286)
					(mid 201.719109 116.615566)
					(end 200.406075 116.07169)
				)
				(arc
					(start 200.406075 116.07169)
					(mid 199.093041 116.615566)
					(end 198.549165 117.9286)
				)
			)
		)
	)
	(zone
		(layers "F.Cu" "B.Cu" "In1.Cu" "In2.Cu" "In3.Cu" "In4.Cu")
		(hatch edge 0.5)
		(connect_pads
			(clearance 0)
		)
		(min_thickness 0.25)
		(keepout
			(tracks not_allowed)
			(vias not_allowed)
			(pads not_allowed)
			(copperpour not_allowed)
			(footprints allowed)
		)
		(placement
			(enabled no)
			(sheetname "")
		)
		(fill
			(thermal_gap 0.5)
			(thermal_bridge_width 0.5)
			(island_removal_mode 0)
		)
		(polygon
			(pts
				(xy 91.838595 156.0786) (xy 99.838595 156.0786) (xy 99.838595 152.6286) (xy 91.838595 152.6286)
			)
		)
	)
	(zone
		(layer "F.Mask")
		(hatch edge 0.5)
		(priority 38)
		(connect_pads yes
			(clearance 0.5)
		)
		(min_thickness 0.25)
		(fill yes
			(thermal_gap 0.2032)
			(thermal_bridge_width 0.254)
			(island_removal_mode 0)
		)
		(polygon
			(pts
				(xy 205.488595 92.5786) (xy 154.738595 92.5786) (xy 154.738595 143.3286) (xy 205.488595 143.3286)
			)
		)
	)
	(zone
		(layer "B.Cu")
		(hatch edge 0.5)
		(connect_pads
			(clearance 0)
		)
		(min_thickness 0.25)
		(keepout
			(tracks not_allowed)
			(vias not_allowed)
			(pads not_allowed)
			(copperpour not_allowed)
			(footprints allowed)
		)
		(placement
			(enabled no)
			(sheetname "")
		)
		(fill
			(thermal_gap 0.5)
			(thermal_bridge_width 0.5)
			(island_removal_mode 0)
		)
		(polygon
			(pts
				(arc
					(start 58.438215 156.0786)
					(mid 58.452971 156.114224)
					(end 58.488595 156.12898)
				)
				(arc
					(start 73.488595 156.12898)
					(mid 73.524219 156.114224)
					(end 73.538975 156.0786)
				)
				(xy 73.538975 147.87898) (xy 91.788215 147.87898)
				(arc
					(start 91.788215 152.6286)
					(mid 91.802971 152.664224)
					(end 91.838595 152.67898)
				)
				(arc
					(start 99.838595 152.67898)
					(mid 99.874219 152.664224)
					(end 99.888975 152.6286)
				)
				(xy 99.888972 152.628094) (xy 99.888975 152.62809)
				(arc
					(start 99.888975 149.6536)
					(mid 101.663595 147.87898)
					(end 103.438215 149.6536)
				)
				(arc
					(start 103.438215 149.6536)
					(mid 103.488595 149.70398)
					(end 103.538975 149.6536)
				)
				(arc
					(start 103.538975 146.8286)
					(mid 103.524219 146.792976)
					(end 103.488595 146.77822)
				)
				(arc
					(start 58.488595 146.77822)
					(mid 58.452971 146.792976)
					(end 58.438215 146.8286)
				)
			)
		)
	)
	(zone
		(net "+12V")
		(layer "B.Cu")
		(hatch edge 0.5)
		(priority 1)
		(connect_pads yes
			(clearance 0.5)
		)
		(min_thickness 0.25)
		(fill yes
			(thermal_gap 0.2032)
			(thermal_bridge_width 0.254)
			(island_removal_mode 0)
		)
		(polygon
			(pts
				(xy 231.488595 104.0786) (xy 215.488595 104.0786) (xy 215.488595 111.0786) (xy 231.488595 111.0786)
			)
		)
	)
	(zone
		(layer "In1.Cu")
		(hatch edge 0.5)
		(connect_pads
			(clearance 0)
		)
		(min_thickness 0.25)
		(keepout
			(tracks allowed)
			(vias allowed)
			(pads allowed)
			(copperpour not_allowed)
			(footprints allowed)
		)
		(placement
			(enabled no)
			(sheetname "")
		)
		(fill
			(thermal_gap 0.5)
			(thermal_bridge_width 0.5)
			(island_removal_mode 0)
		)
		(polygon
			(pts
				(xy 103.338595 160.9286) (xy 103.338595 154.8536) (xy 138.088595 154.8536) (xy 138.088595 161.1786)
			)
		)
	)
	(zone
		(net "GND")
		(layer "In1.Cu")
		(hatch edge 0.5)
		(priority 22)
		(connect_pads yes
			(clearance 0.5)
		)
		(min_thickness 0.25)
		(fill yes
			(thermal_gap 0.2032)
			(thermal_bridge_width 0.254)
			(island_removal_mode 0)
		)
		(polygon
			(pts
				(xy 73.267395 155.8018) (xy 73.267395 147.5722) (xy 92.063395 147.5722) (xy 92.063395 155.8018)
				(xy 99.607195 155.8018) (xy 99.607195 148.639) (xy 100.750195 147.496) (xy 102.578995 147.496) (xy 103.747395 148.6644)
				(xy 103.747395 160.0436) (xy 104.026795 160.323) (xy 114.135995 160.323) (xy 114.440795 160.0182)
				(xy 114.440795 152.6014) (xy 115.253595 151.7886) (xy 115.964795 151.7886) (xy 116.777595 152.6014)
				(xy 116.777595 160.0436) (xy 117.107795 160.3738) (xy 137.249995 160.3738) (xy 137.605595 160.0182)
				(xy 137.605595 147.6484) (xy 238.288585 147.6484) (xy 238.288595 49.6786) (xy 58.994585 49.67861)
				(xy 58.687795 49.9854) (xy 58.687795 155.8018)
			)
		)
	)
	(zone
		(net "+5.0V")
		(layer "In3.Cu")
		(hatch edge 0.5)
		(priority 8)
		(connect_pads yes
			(clearance 0.5)
		)
		(min_thickness 0.25)
		(fill yes
			(thermal_gap 0.2032)
			(thermal_bridge_width 0.254)
			(island_removal_mode 0)
		)
		(polygon
			(pts
				(xy 209.388595 123.2786) (xy 210.688595 123.2786) (xy 210.688595 124.8786) (xy 209.388595 124.8786)
			)
		)
	)
	(zone
		(net "+5.0V")
		(layer "In3.Cu")
		(hatch edge 0.5)
		(priority 9)
		(connect_pads yes
			(clearance 0.5)
		)
		(min_thickness 0.25)
		(fill yes
			(thermal_gap 0.2032)
			(thermal_bridge_width 0.254)
			(island_removal_mode 0)
		)
		(polygon
			(pts
				(xy 154.238595 106.5786) (xy 143.738595 106.5786) (xy 143.738595 110.5786) (xy 154.238595 110.5786)
			)
		)
	)
	(zone
		(net "+3.3V")
		(layer "In3.Cu")
		(hatch edge 0.5)
		(priority 7)
		(connect_pads yes
			(clearance 0.5)
		)
		(min_thickness 0.25)
		(fill yes
			(thermal_gap 0.2032)
			(thermal_bridge_width 0.254)
			(island_removal_mode 0)
		)
		(polygon
			(pts
				(xy 72.238595 50.5786) (xy 72.238595 73.0786) (xy 115.988595 73.0786) (xy 115.988595 50.5786)
			)
		)
	)
	(zone
		(net "+3.3V")
		(layer "In3.Cu")
		(hatch edge 0.5)
		(priority 2)
		(connect_pads yes
			(clearance 0.5)
		)
		(min_thickness 0.25)
		(fill yes
			(thermal_gap 0.2032)
			(thermal_bridge_width 0.254)
			(island_removal_mode 0)
		)
		(polygon
			(pts
				(xy 229.238595 81.8286) (xy 229.238595 61.0786) (xy 225.738595 61.0786) (xy 225.738595 81.8286)
			)
		)
	)
	(zone
		(net "+3.3V")
		(layer "In3.Cu")
		(hatch edge 0.5)
		(priority 5)
		(connect_pads yes
			(clearance 0.5)
		)
		(min_thickness 0.25)
		(fill yes
			(thermal_gap 0.2032)
			(thermal_bridge_width 0.254)
			(island_removal_mode 0)
		)
		(polygon
			(pts
				(xy 228.288595 61.0786) (xy 222.988595 61.0786) (xy 112.488595 61.0786) (xy 112.488595 66.5786)
				(xy 113.488595 67.5786) (xy 228.288585 67.57861)
			)
		)
	)
	(zone
		(layer "In4.Cu")
		(hatch edge 0.5)
		(connect_pads
			(clearance 0)
		)
		(min_thickness 0.25)
		(keepout
			(tracks allowed)
			(vias allowed)
			(pads allowed)
			(copperpour not_allowed)
			(footprints allowed)
		)
		(placement
			(enabled no)
			(sheetname "")
		)
		(fill
			(thermal_gap 0.5)
			(thermal_bridge_width 0.5)
			(island_removal_mode 0)
		)
		(polygon
			(pts
				(xy 103.338595 160.9286) (xy 103.338595 154.8536) (xy 138.088595 154.8536) (xy 138.088595 161.1786)
			)
		)
	)
	(zone
		(net "GND")
		(layer "In4.Cu")
		(hatch edge 0.5)
		(priority 20)
		(connect_pads yes
			(clearance 0.5)
		)
		(min_thickness 0.25)
		(fill yes
			(thermal_gap 0.2032)
			(thermal_bridge_width 0.254)
			(island_removal_mode 0)
		)
		(polygon
			(pts
				(xy 73.142395 155.9016) (xy 73.142395 147.672) (xy 91.938395 147.672) (xy 91.938395 155.9016) (xy 99.482195 155.9016)
				(xy 99.482195 148.7388) (xy 100.625195 147.5958) (xy 102.453995 147.5958) (xy 103.622395 148.7642)
				(xy 103.622395 160.1434) (xy 103.901795 160.4228) (xy 114.010995 160.4228) (xy 114.315795 160.118)
				(xy 114.315795 152.7012) (xy 115.128595 151.8884) (xy 115.839795 151.8884) (xy 116.652595 152.7012)
				(xy 116.652595 160.1434) (xy 116.982795 160.4736) (xy 137.124995 160.4736) (xy 137.480595 160.118)
				(xy 137.480595 147.7482) (xy 238.388595 147.7482) (xy 238.388595 50.009) (xy 58.638995 50.009) (xy 58.562795 50.0852)
				(xy 58.562795 155.9016)
			)
		)
	)
)
